{ Packager-XL run on 16-Jun-2017 AT 17:50:48 }
FILE_TYPE = BACK_ANNOTATION;
DRAWING = "@baseboard_fab2_lib.baseboard_fab2(sch_1):page21";
BODY = "RES","I149": #LOCATION = "R6N10" !CDS_LOCATION = "R6N10" #SEC = "1" !CDS_SEC = "1";
"A":   PN = "1"  !CDS_PN = "1";
"B":   PN = "2"  !CDS_PN = "2";
BODY = "RES","I150": #LOCATION = "R6N12" !CDS_LOCATION = "R6N12" #SEC = "1" !CDS_SEC = "1";
"A":   PN = "1"  !CDS_PN = "1";
"B":   PN = "2"  !CDS_PN = "2";
BODY = "RES","I151": #LOCATION = "R6N11" !CDS_LOCATION = "R6N11" #SEC = "1" !CDS_SEC = "1";
"A":   PN = "1"  !CDS_PN = "1";
"B":   PN = "2"  !CDS_PN = "2";
BODY = "RES","I152": #LOCATION = "R6B3" !CDS_LOCATION = "R6B3" #SEC = "1" !CDS_SEC = "1";
"A":   PN = "1"  !CDS_PN = "1";
"B":   PN = "2"  !CDS_PN = "2";
BODY = "RES","I153": #LOCATION = "R6B5" !CDS_LOCATION = "R6B5" #SEC = "1" !CDS_SEC = "1";
"A":   PN = "1"  !CDS_PN = "1";
"B":   PN = "2"  !CDS_PN = "2";
BODY = "RES","I154": #LOCATION = "R6B4" !CDS_LOCATION = "R6B4" #SEC = "1" !CDS_SEC = "1";
"A":   PN = "1"  !CDS_PN = "1";
"B":   PN = "2"  !CDS_PN = "2";
BODY = "RES","I159": #LOCATION = "R6B2" !CDS_LOCATION = "R6B2" #SEC = "1" !CDS_SEC = "1";
"A":   PN = "1"  !CDS_PN = "1";
"B":   PN = "2"  !CDS_PN = "2";
BODY = "RES","I161": #LOCATION = "R6B1" !CDS_LOCATION = "R6B1" #SEC = "1" !CDS_SEC = "1";
"A":   PN = "1"  !CDS_PN = "1";
"B":   PN = "2"  !CDS_PN = "2";
BODY = "RES","I163": #LOCATION = "R6N2" !CDS_LOCATION = "R6N2" #SEC = "1" !CDS_SEC = "1";
"A":   PN = "1"  !CDS_PN = "1";
"B":   PN = "2"  !CDS_PN = "2";
BODY = "RES","I164": #LOCATION = "R6N1" !CDS_LOCATION = "R6N1" #SEC = "1" !CDS_SEC = "1";
"A":   PN = "1"  !CDS_PN = "1";
"B":   PN = "2"  !CDS_PN = "2";
BODY = "RES","I177": #LOCATION = "R5D1" !CDS_LOCATION = "R5D1" #SEC = "1" !CDS_SEC = "1";
"A":   PN = "1"  !CDS_PN = "1";
"B":   PN = "2"  !CDS_PN = "2";
BODY = "RES","I178": #LOCATION = "R5D2" !CDS_LOCATION = "R5D2" #SEC = "1" !CDS_SEC = "1";
"A":   PN = "1"  !CDS_PN = "1";
"B":   PN = "2"  !CDS_PN = "2";
BODY = "RES","I179": #LOCATION = "R6D1" !CDS_LOCATION = "R6D1" #SEC = "1" !CDS_SEC = "1";
"A":   PN = "1"  !CDS_PN = "1";
"B":   PN = "2"  !CDS_PN = "2";
BODY = "RES","I180": #LOCATION = "R4P8" !CDS_LOCATION = "R4P8" #SEC = "1" !CDS_SEC = "1";
"A":   PN = "1"  !CDS_PN = "1";
"B":   PN = "2"  !CDS_PN = "2";
BODY = "RES","I181": #LOCATION = "R4P10" !CDS_LOCATION = "R4P10" #SEC = "1" !CDS_SEC = "1";
"A":   PN = "1"  !CDS_PN = "1";
"B":   PN = "2"  !CDS_PN = "2";
BODY = "RES","I182": #LOCATION = "R4P11" !CDS_LOCATION = "R4P11" #SEC = "1" !CDS_SEC = "1";
"A":   PN = "1"  !CDS_PN = "1";
"B":   PN = "2"  !CDS_PN = "2";
BODY = "RES","I184": #LOCATION = "R6D11" !CDS_LOCATION = "R6D11" #SEC = "1" !CDS_SEC = "1";
"A":   PN = "1"  !CDS_PN = "1";
"B":   PN = "2"  !CDS_PN = "2";
BODY = "RES","I186": #LOCATION = "R4P3" !CDS_LOCATION = "R4P3" #SEC = "1" !CDS_SEC = "1";
"A":   PN = "1"  !CDS_PN = "1";
"B":   PN = "2"  !CDS_PN = "2";
BODY = "RES","I188": #LOCATION = "R4P2" !CDS_LOCATION = "R4P2" #SEC = "1" !CDS_SEC = "1";
"A":   PN = "1"  !CDS_PN = "1";
"B":   PN = "2"  !CDS_PN = "2";
BODY = "RES","I189": #LOCATION = "R4P4" !CDS_LOCATION = "R4P4" #SEC = "1" !CDS_SEC = "1";
"A":   PN = "1"  !CDS_PN = "1";
"B":   PN = "2"  !CDS_PN = "2";
BODY = "RES","I204": #LOCATION = "R6D2" !CDS_LOCATION = "R6D2" #SEC = "1" !CDS_SEC = "1";
"A":   PN = "1"  !CDS_PN = "1";
"B":   PN = "2"  !CDS_PN = "2";
BODY = "SOCKET_P_MECH_A","I216": #LOCATION = "XRU1" !CDS_LOCATION = "XRU1";
BODY = "SOCKET_P_MECH_A","I217": #LOCATION = "XLU1" !CDS_LOCATION = "XLU1";
BODY = "RES","I219": #LOCATION = "R4P19" !CDS_LOCATION = "R4P19" #SEC = "1" !CDS_SEC = "1";
"A":   PN = "1"  !CDS_PN = "1";
"B":   PN = "2"  !CDS_PN = "2";
BODY = "RES","I227": #LOCATION = "R5N2" !CDS_LOCATION = "R5N2" #SEC = "1" !CDS_SEC = "1";
"A":   PN = "1"  !CDS_PN = "1";
"B":   PN = "2"  !CDS_PN = "2";
BODY = "RES","I238": #LOCATION = "R5N1" !CDS_LOCATION = "R5N1" #SEC = "1" !CDS_SEC = "1";
"A":   PN = "1"  !CDS_PN = "1";
"B":   PN = "2"  !CDS_PN = "2";
BODY = "RES","I239": #LOCATION = "R5N5" !CDS_LOCATION = "R5N5" #SEC = "1" !CDS_SEC = "1";
"A":   PN = "1"  !CDS_PN = "1";
"B":   PN = "2"  !CDS_PN = "2";
BODY = "RES","I240": #LOCATION = "R5N3" !CDS_LOCATION = "R5N3" #SEC = "1" !CDS_SEC = "1";
"A":   PN = "1"  !CDS_PN = "1";
"B":   PN = "2"  !CDS_PN = "2";
BODY = "RES","I241": #LOCATION = "R5N4" !CDS_LOCATION = "R5N4" #SEC = "1" !CDS_SEC = "1";
"A":   PN = "1"  !CDS_PN = "1";
"B":   PN = "2"  !CDS_PN = "2";
BODY = "RES","I244": #LOCATION = "R4P18" !CDS_LOCATION = "R4P18" #SEC = "1" !CDS_SEC = "1";
"A":   PN = "1"  !CDS_PN = "1";
"B":   PN = "2"  !CDS_PN = "2";
BODY = "RES","I258": #LOCATION = "R4R5" !CDS_LOCATION = "R4R5" #SEC = "1" !CDS_SEC = "1";
"A":   PN = "1"  !CDS_PN = "1";
"B":   PN = "2"  !CDS_PN = "2";
BODY = "SKX_EXT_B","I259": #LOCATION = "U5D1" !CDS_LOCATION = "U5D1" #SEC = "1" !CDS_SEC = "1";
"BCLK0_DN":   PN = "AU24"  !CDS_PN = "AU24";
"BCLK0_DP":   PN = "AW24"  !CDS_PN = "AW24";
"BCLK1_DN":   PN = "CR26"  !CDS_PN = "CR26";
"BCLK1_DP":   PN = "CP27"  !CDS_PN = "CP27";
"BCLK2_DN":   PN = "CT25"  !CDS_PN = "CT25";
"BCLK2_DP":   PN = "CU26"  !CDS_PN = "CU26";
"BIST_ENABLE":   PN = "BA20"  !CDS_PN = "BA20";
"BMCINIT":   PN = "BD23"  !CDS_PN = "BD23";
"BPM<0>_N":   PN = "AJ10"  !CDS_PN = "AJ10";
"BPM<1>_N":   PN = "AH11"  !CDS_PN = "AH11";
"BPM<2>_N":   PN = "AG10"  !CDS_PN = "AG10";
"BPM<3>_N":   PN = "AF11"  !CDS_PN = "AF11";
"BPM<4>_N":   PN = "AA12"  !CDS_PN = "AA12";
"BPM<5>_N":   PN = "Y11"  !CDS_PN = "Y11";
"BPM<6>_N":   PN = "AE12"  !CDS_PN = "AE12";
"BPM<7>_N":   PN = "AC12"  !CDS_PN = "AC12";
"CATERR_N":   PN = "AL14"  !CDS_PN = "AL14";
"DDR0_CAVREF":   PN = "AJ64"  !CDS_PN = "AJ64";
"DDR1_CAVREF":   PN = "AK63"  !CDS_PN = "AK63";
"DDR2_CAVREF":   PN = "AH63"  !CDS_PN = "AH63";
"DDR3_CAVREF":   PN = "CP61"  !CDS_PN = "CP61";
"DDR4_CAVREF":   PN = "CT61"  !CDS_PN = "CT61";
"DDR5_CAVREF":   PN = "CV61"  !CDS_PN = "CV61";
"DDR012_DRAM_PWR_OK":   PN = "AN30"  !CDS_PN = "AN30";
"DDR012_RCOMP<0>":   PN = "Y43"  !CDS_PN = "Y43";
"DDR012_RCOMP<1>":   PN = "AB43"  !CDS_PN = "AB43";
"DDR012_RCOMP<2>":   PN = "AC42"  !CDS_PN = "AC42";
"DDR012_RESET_N":   PN = "U64"  !CDS_PN = "U64";
"DDR012_SPDSCL":   PN = "AJ18"  !CDS_PN = "AJ18";
"DDR012_SPDSDA":   PN = "AF17"  !CDS_PN = "AF17";
"DDR345_DRAM_PWR_OK":   PN = "CR28"  !CDS_PN = "CR28";
"DDR345_RCOMP<0>":   PN = "DC48"  !CDS_PN = "DC48";
"DDR345_RCOMP<1>":   PN = "DD47"  !CDS_PN = "DD47";
"DDR345_RCOMP<2>":   PN = "DD49"  !CDS_PN = "DD49";
"DDR345_RESET_N":   PN = "DV63"  !CDS_PN = "DV63";
"DDR345_SPDSCL":   PN = "AE18"  !CDS_PN = "AE18";
"DDR345_SPDSDA":   PN = "AD17"  !CDS_PN = "AD17";
"EAR_N":   PN = "AJ14"  !CDS_PN = "AJ14";
"ERROR<0>_N":   PN = "AJ12"  !CDS_PN = "AJ12";
"ERROR<1>_N":   PN = "AK11"  !CDS_PN = "AK11";
"ERROR<2>_N":   PN = "AL12"  !CDS_PN = "AL12";
"FRMAGENT":   PN = "AV17"  !CDS_PN = "AV17";
"LEGACY_SKT":   PN = "AE20"  !CDS_PN = "AE20";
"MCP01_RBIAS<0>":   PN = "CU32"  !CDS_PN = "CU32";
"MCP01_RBIAS<1>":   PN = "CT31"  !CDS_PN = "CT31";
"MEM_HOT_C012_N":   PN = "AH13"  !CDS_PN = "AH13";
"MEM_HOT_C345_N":   PN = "AF13"  !CDS_PN = "AF13";
"MSMI_N":   PN = "AN20"  !CDS_PN = "AN20";
"NMI":   PN = "AP11"  !CDS_PN = "AP11";
"PE3_RBIAS<0>":   PN = "CP29"  !CDS_PN = "CP29";
"PE3_RBIAS<1>":   PN = "CR30"  !CDS_PN = "CR30";
"PE012_RBIAS<0>":   PN = "CN30"  !CDS_PN = "CN30";
"PE012_RBIAS<1>":   PN = "CL30"  !CDS_PN = "CL30";
"PE_HP_SCL":   PN = "AM19"  !CDS_PN = "AM19";
"PE_HP_SDA":   PN = "AL18"  !CDS_PN = "AL18";
"PECI":   PN = "AU12"  !CDS_PN = "AU12";
"PIROM_ADDR<0>":   PN = "CU58"  !CDS_PN = "CU58";
"PIROM_ADDR<1>":   PN = "CV57"  !CDS_PN = "CV57";
"PIROM_ADDR<2>":   PN = "CW56"  !CDS_PN = "CW56";
"PKGID<0>":   PN = "DC72"  !CDS_PN = "DC72";
"PKGID<1>":   PN = "CW72"  !CDS_PN = "CW72";
"PKGID<2>":   PN = "DA72"  !CDS_PN = "DA72";
"PM_FAST_WAKE_N":   PN = "AF15"  !CDS_PN = "AF15";
"PMSYNC":   PN = "AR14"  !CDS_PN = "AR14";
"PMSYNC_CLK":   PN = "AT19"  !CDS_PN = "AT19";
"PRDY_N":   PN = "AG16"  !CDS_PN = "AG16";
"PREQ_N":   PN = "AR12"  !CDS_PN = "AR12";
"PROC_ID<0>":   PN = "CY71"  !CDS_PN = "CY71";
"PROC_ID<1>":   PN = "DB71"  !CDS_PN = "DB71";
"PROCDIS_N":   PN = "AB17"  !CDS_PN = "AB17";
"PROCHOT_N":   PN = "AC16"  !CDS_PN = "AC16";
"PWRGOOD":   PN = "BC24"  !CDS_PN = "BC24";
"RESET_N":   PN = "AP21"  !CDS_PN = "AP21";
"SAFE_MODE_BOOT":   PN = "AR18"  !CDS_PN = "AR18";
"SKTOCC_N":   PN = "AB13"  !CDS_PN = "AB13";
"SM_WP":   PN = "CV59"  !CDS_PN = "CV59";
"SMBCLK":   PN = "CT59"  !CDS_PN = "CT59";
"SMBDAT":   PN = "CW58"  !CDS_PN = "CW58";
"SOCKET_ID<0>":   PN = "AU22"  !CDS_PN = "AU22";
"SOCKET_ID<1>":   PN = "AU16"  !CDS_PN = "AU16";
"SOCKET_ID<2>":   PN = "AU20"  !CDS_PN = "AU20";
"SVIDALERT<0>_N":   PN = "DE44"  !CDS_PN = "DE44";
"SVIDALERT<1>_N":   PN = "DL44"  !CDS_PN = "DL44";
"SVIDCLK<0>":   PN = "DC44"  !CDS_PN = "DC44";
"SVIDCLK<1>":   PN = "DG44"  !CDS_PN = "DG44";
"SVIDDATA<0>":   PN = "DB45"  !CDS_PN = "DB45";
"SVIDDATA<1>":   PN = "DJ44"  !CDS_PN = "DJ44";
"TCK":   PN = "AA14"  !CDS_PN = "AA14";
"TDI":   PN = "AC14"  !CDS_PN = "AC14";
"TDO":   PN = "AE14"  !CDS_PN = "AE14";
"TEST_12":   PN = "AY19"  !CDS_PN = "AY19";
"TEST_13":   PN = "DB51"  !CDS_PN = "DB51";
"TEST_14":   PN = "DC50"  !CDS_PN = "DC50";
"TEST_15":   PN = "AW14"  !CDS_PN = "AW14";
"THERMTRIP_N":   PN = "AB15"  !CDS_PN = "AB15";
"TMS":   PN = "W14"  !CDS_PN = "W14";
"TRST_N":   PN = "Y13"  !CDS_PN = "Y13";
"TSC_SYNC":   PN = "AM11"  !CDS_PN = "AM11";
"TXT_AGENT":   PN = "AW18"  !CDS_PN = "AW18";
"TXT_PLTEN":   PN = "AV15"  !CDS_PN = "AV15";
"UPI01_RBIAS<0>":   PN = "AT29"  !CDS_PN = "AT29";
"UPI01_RBIAS<1>":   PN = "AP29"  !CDS_PN = "AP29";
"UPI2_RBIAS<0>":   PN = "CL28"  !CDS_PN = "CL28";
"UPI2_RBIAS<1>":   PN = "CK29"  !CDS_PN = "CK29";
DRAWING = "@baseboard_fab2_lib.baseboard_fab2(sch_1):page22";
BODY = "RES","I188": #LOCATION = "R5R1" !CDS_LOCATION = "R5R1" #SEC = "1" !CDS_SEC = "1";
"A":   PN = "1"  !CDS_PN = "1";
"B":   PN = "2"  !CDS_PN = "2";
BODY = "RES","I190": #LOCATION = "R5P4" !CDS_LOCATION = "R5P4" #SEC = "1" !CDS_SEC = "1";
"A":   PN = "1"  !CDS_PN = "1";
"B":   PN = "2"  !CDS_PN = "2";
BODY = "SKX_EXT_B","I204": #LOCATION = "U5D1" !CDS_LOCATION = "U5D1" #SEC = "2" !CDS_SEC = "2";
"DEBUG_EN_N":   PN = "AV21"  !CDS_PN = "AV21";
"DMIMODE_OVERRIDE":   PN = "AW12"  !CDS_PN = "AW12";
"FIVR_FAULT":   PN = "AU14"  !CDS_PN = "AU14";
"PWR_DEBUG_N":   PN = "AP17"  !CDS_PN = "AP17";
"RSVD<194>":   PN = "AP61"  !CDS_PN = "AP61";
"RSVD<195>":   PN = "AP27"  !CDS_PN = "AP27";
"RSVD<196>":   PN = "AP25"  !CDS_PN = "AP25";
"RSVD<197>":   PN = "AP23"  !CDS_PN = "AP23";
"RSVD<198>":   PN = "AN62"  !CDS_PN = "AN62";
"RSVD<199>":   PN = "AN60"  !CDS_PN = "AN60";
"RSVD<200>":   PN = "AN26"  !CDS_PN = "AN26";
"RSVD<201>":   PN = "AN24"  !CDS_PN = "AN24";
"RSVD<202>":   PN = "AN22"  !CDS_PN = "AN22";
"RSVD<203>":   PN = "AN18"  !CDS_PN = "AN18";
"RSVD<204>":   PN = "AM61"  !CDS_PN = "AM61";
"RSVD<205>":   PN = "AM59"  !CDS_PN = "AM59";
"RSVD<206>":   PN = "AM27"  !CDS_PN = "AM27";
"RSVD<207>":   PN = "AM25"  !CDS_PN = "AM25";
"RSVD<208>":   PN = "AM23"  !CDS_PN = "AM23";
"RSVD<209>":   PN = "AM21"  !CDS_PN = "AM21";
"RSVD<210>":   PN = "AL62"  !CDS_PN = "AL62";
"RSVD<211>":   PN = "AL60"  !CDS_PN = "AL60";
"RSVD<212>":   PN = "AL58"  !CDS_PN = "AL58";
"RSVD<213>":   PN = "AL26"  !CDS_PN = "AL26";
"RSVD<214>":   PN = "AL22"  !CDS_PN = "AL22";
"RSVD<215>":   PN = "AL20"  !CDS_PN = "AL20";
"RSVD<216>":   PN = "AK69"  !CDS_PN = "AK69";
"RSVD<217>":   PN = "AK61"  !CDS_PN = "AK61";
"RSVD<218>":   PN = "AK59"  !CDS_PN = "AK59";
"RSVD<219>":   PN = "AK57"  !CDS_PN = "AK57";
"RSVD<220>":   PN = "AK27"  !CDS_PN = "AK27";
"RSVD<221>":   PN = "AK21"  !CDS_PN = "AK21";
"RSVD<222>":   PN = "AJ70"  !CDS_PN = "AJ70";
"RSVD<223>":   PN = "AJ62"  !CDS_PN = "AJ62";
"RSVD<224>":   PN = "AJ60"  !CDS_PN = "AJ60";
"RSVD<225>":   PN = "AJ58"  !CDS_PN = "AJ58";
"RSVD<226>":   PN = "AJ56"  !CDS_PN = "AJ56";
"RSVD<227>":   PN = "AJ20"  !CDS_PN = "AJ20";
"RSVD<228>":   PN = "AH73"  !CDS_PN = "AH73";
"RSVD<229>":   PN = "AH71"  !CDS_PN = "AH71";
"RSVD<230>":   PN = "AH57"  !CDS_PN = "AH57";
"RSVD<231>":   PN = "AH55"  !CDS_PN = "AH55";
"RSVD<232>":   PN = "AH19"  !CDS_PN = "AH19";
"RSVD<233>":   PN = "AH15"  !CDS_PN = "AH15";
"RSVD<234>":   PN = "AG72"  !CDS_PN = "AG72";
"RSVD<235>":   PN = "AG56"  !CDS_PN = "AG56";
"RSVD<236>":   PN = "AG54"  !CDS_PN = "AG54";
"RSVD<237>":   PN = "AG52"  !CDS_PN = "AG52";
"RSVD<238>":   PN = "AG50"  !CDS_PN = "AG50";
"RSVD<239>":   PN = "AG48"  !CDS_PN = "AG48";
"RSVD<240>":   PN = "AG20"  !CDS_PN = "AG20";
"RSVD<241>":   PN = "AF71"  !CDS_PN = "AF71";
"RSVD<242>":   PN = "AF53"  !CDS_PN = "AF53";
"RSVD<243>":   PN = "AF51"  !CDS_PN = "AF51";
"RSVD<244>":   PN = "AF49"  !CDS_PN = "AF49";
"RSVD<245>":   PN = "AF47"  !CDS_PN = "AF47";
"RSVD<246>":   PN = "AF19"  !CDS_PN = "AF19";
"RSVD<247>":   PN = "AE72"  !CDS_PN = "AE72";
"RSVD<248>":   PN = "AE52"  !CDS_PN = "AE52";
"RSVD<249>":   PN = "AE50"  !CDS_PN = "AE50";
"RSVD<250>":   PN = "AE48"  !CDS_PN = "AE48";
"RSVD<251>":   PN = "AE46"  !CDS_PN = "AE46";
"RSVD<252>":   PN = "AD51"  !CDS_PN = "AD51";
"RSVD<253>":   PN = "AD49"  !CDS_PN = "AD49";
"RSVD<254>":   PN = "AD47"  !CDS_PN = "AD47";
"RSVD<256>":   PN = "Y65"  !CDS_PN = "Y65";
"RSVD<257>":   PN = "Y23"  !CDS_PN = "Y23";
"RSVD<258>":   PN = "W66"  !CDS_PN = "W66";
"RSVD<259>":   PN = "V67"  !CDS_PN = "V67";
"RSVD<260>":   PN = "V65"  !CDS_PN = "V65";
"RSVD<261>":   PN = "U66"  !CDS_PN = "U66";
"RSVD<262>":   PN = "T67"  !CDS_PN = "T67";
"RSVD<263>":   PN = "R66"  !CDS_PN = "R66";
"RSVD<264>":   PN = "R62"  !CDS_PN = "R62";
"RSVD<265>":   PN = "P65"  !CDS_PN = "P65";
"RSVD<266>":   PN = "M63"  !CDS_PN = "M63";
"RSVD<267>":   PN = "K61"  !CDS_PN = "K61";
"RSVD<268>":   PN = "J62"  !CDS_PN = "J62";
"RSVD<269>":   PN = "J46"  !CDS_PN = "J46";
"RSVD<270>":   PN = "H85"  !CDS_PN = "H85";
"RSVD<271>":   PN = "H83"  !CDS_PN = "H83";
"RSVD<272>":   PN = "H1"  !CDS_PN = "H1";
"RSVD<273>":   PN = "G84"  !CDS_PN = "G84";
"RSVD<274>":   PN = "G64"  !CDS_PN = "G64";
"RSVD<275>":   PN = "G2"  !CDS_PN = "G2";
"RSVD<276>":   PN = "F83"  !CDS_PN = "F83";
"RSVD<277>":   PN = "F65"  !CDS_PN = "F65";
"RSVD<278>":   PN = "F23"  !CDS_PN = "F23";
"RSVD<279>":   PN = "F3"  !CDS_PN = "F3";
"RSVD<280>":   PN = "E84"  !CDS_PN = "E84";
"RSVD<281>":   PN = "E24"  !CDS_PN = "E24";
"RSVD<282>":   PN = "E4"  !CDS_PN = "E4";
"RSVD<283>":   PN = "E2"  !CDS_PN = "E2";
"RSVD<284>":   PN = "D83"  !CDS_PN = "D83";
"RSVD<285>":   PN = "D65"  !CDS_PN = "D65";
"RSVD<286>":   PN = "D17"  !CDS_PN = "D17";
"RSVD<287>":   PN = "D5"  !CDS_PN = "D5";
"RSVD<288>":   PN = "C82"  !CDS_PN = "C82";
"RSVD<289>":   PN = "C24"  !CDS_PN = "C24";
"RSVD<290>":   PN = "C18"  !CDS_PN = "C18";
"RSVD<291>":   PN = "C6"  !CDS_PN = "C6";
"RSVD<292>":   PN = "B81"  !CDS_PN = "B81";
"RSVD<293>":   PN = "B77"  !CDS_PN = "B77";
"RSVD<294>":   PN = "B17"  !CDS_PN = "B17";
"RSVD<295>":   PN = "B15"  !CDS_PN = "B15";
"RSVD<296>":   PN = "B13"  !CDS_PN = "B13";
"RSVD<298>":   PN = "B7"  !CDS_PN = "B7";
"RSVD<299>":   PN = "B3"  !CDS_PN = "B3";
"RSVD<300>":   PN = "A24"  !CDS_PN = "A24";
"RSVD<301>":   PN = "A16"  !CDS_PN = "A16";
"RSVD<302>":   PN = "A14"  !CDS_PN = "A14";
"RSVD<303>":   PN = "A6"  !CDS_PN = "A6";
"RSVD<304>":   PN = "A4"  !CDS_PN = "A4";
"TEST_1":   PN = "AF45"  !CDS_PN = "AF45";
"TEST_2":   PN = "AG46"  !CDS_PN = "AG46";
"TEST_3":   PN = "AM13"  !CDS_PN = "AM13";
"TEST_4":   PN = "AN12"  !CDS_PN = "AN12";
"TEST_5":   PN = "AN14"  !CDS_PN = "AN14";
"TEST_11":   PN = "AY13"  !CDS_PN = "AY13";
DRAWING = "@baseboard_fab2_lib.baseboard_fab2(sch_1):page23";
BODY = "SKX_EXT_B","I172": #LOCATION = "U5D1" !CDS_LOCATION = "U5D1" #SEC = "3" !CDS_SEC = "3";
"DDR0_ACT_N":   PN = "J60"  !CDS_PN = "J60";
"DDR0_ALERT_N":   PN = "B61"  !CDS_PN = "B61";
"DDR0_BA<0>":   PN = "C52"  !CDS_PN = "C52";
"DDR0_BA<1>":   PN = "G54"  !CDS_PN = "G54";
"DDR0_BG<0>":   PN = "D61"  !CDS_PN = "D61";
"DDR0_BG<1>":   PN = "F63"  !CDS_PN = "F63";
"DDR0_CID<2>":   PN = "G46"  !CDS_PN = "G46";
"DDR0_CKE<0>":   PN = "C62"  !CDS_PN = "C62";
"DDR0_CKE<1>":   PN = "C64"  !CDS_PN = "C64";
"DDR0_CKE<2>":   PN = "B63"  !CDS_PN = "B63";
"DDR0_CKE<3>":   PN = "D63"  !CDS_PN = "D63";
"DDR0_CLK_DN<0>":   PN = "F55"  !CDS_PN = "F55";
"DDR0_CLK_DN<1>":   PN = "C54"  !CDS_PN = "C54";
"DDR0_CLK_DN<2>":   PN = "J56"  !CDS_PN = "J56";
"DDR0_CLK_DN<3>":   PN = "C56"  !CDS_PN = "C56";
"DDR0_CLK_DP<0>":   PN = "D55"  !CDS_PN = "D55";
"DDR0_CLK_DP<1>":   PN = "B55"  !CDS_PN = "B55";
"DDR0_CLK_DP<2>":   PN = "G56"  !CDS_PN = "G56";
"DDR0_CLK_DP<3>":   PN = "B57"  !CDS_PN = "B57";
"DDR0_CS<0>_N":   PN = "G52"  !CDS_PN = "G52";
"DDR0_CS<1>_N":   PN = "F49"  !CDS_PN = "F49";
"DDR0_CS<2>_N":   PN = "D47"  !CDS_PN = "D47";
"DDR0_CS<3>_N":   PN = "F47"  !CDS_PN = "F47";
"DDR0_CS<4>_N":   PN = "B51"  !CDS_PN = "B51";
"DDR0_CS<5>_N":   PN = "D49"  !CDS_PN = "D49";
"DDR0_CS<6>_N":   PN = "F45"  !CDS_PN = "F45";
"DDR0_CS<7>_N":   PN = "K45"  !CDS_PN = "K45";
"DDR0_DQ<0>":   PN = "AN86"  !CDS_PN = "AN86";
"DDR0_DQ<1>":   PN = "AN84"  !CDS_PN = "AN84";
"DDR0_DQ<2>":   PN = "AE86"  !CDS_PN = "AE86";
"DDR0_DQ<3>":   PN = "AE84"  !CDS_PN = "AE84";
"DDR0_DQ<4>":   PN = "AR86"  !CDS_PN = "AR86";
"DDR0_DQ<5>":   PN = "AR84"  !CDS_PN = "AR84";
"DDR0_DQ<6>":   PN = "AG86"  !CDS_PN = "AG86";
"DDR0_DQ<7>":   PN = "AG84"  !CDS_PN = "AG84";
"DDR0_DQ<8>":   PN = "W86"  !CDS_PN = "W86";
"DDR0_DQ<9>":   PN = "W84"  !CDS_PN = "W84";
"DDR0_DQ<10>":   PN = "L86"  !CDS_PN = "L86";
"DDR0_DQ<11>":   PN = "L84"  !CDS_PN = "L84";
"DDR0_DQ<12>":   PN = "AA86"  !CDS_PN = "AA86";
"DDR0_DQ<13>":   PN = "AA84"  !CDS_PN = "AA84";
"DDR0_DQ<14>":   PN = "N86"  !CDS_PN = "N86";
"DDR0_DQ<15>":   PN = "N84"  !CDS_PN = "N84";
"DDR0_DQ<16>":   PN = "V81"  !CDS_PN = "V81";
"DDR0_DQ<17>":   PN = "T79"  !CDS_PN = "T79";
"DDR0_DQ<18>":   PN = "N82"  !CDS_PN = "N82";
"DDR0_DQ<19>":   PN = "M81"  !CDS_PN = "M81";
"DDR0_DQ<20>":   PN = "W80"  !CDS_PN = "W80";
"DDR0_DQ<21>":   PN = "V79"  !CDS_PN = "V79";
"DDR0_DQ<22>":   PN = "R82"  !CDS_PN = "R82";
"DDR0_DQ<23>":   PN = "N80"  !CDS_PN = "N80";
"DDR0_DQ<24>":   PN = "L76"  !CDS_PN = "L76";
"DDR0_DQ<25>":   PN = "R76"  !CDS_PN = "R76";
"DDR0_DQ<26>":   PN = "M73"  !CDS_PN = "M73";
"DDR0_DQ<27>":   PN = "P73"  !CDS_PN = "P73";
"DDR0_DQ<28>":   PN = "M77"  !CDS_PN = "M77";
"DDR0_DQ<29>":   PN = "P77"  !CDS_PN = "P77";
"DDR0_DQ<30>":   PN = "L74"  !CDS_PN = "L74";
"DDR0_DQ<31>":   PN = "R74"  !CDS_PN = "R74";
"DDR0_DQ<32>":   PN = "C42"  !CDS_PN = "C42";
"DDR0_DQ<33>":   PN = "B41"  !CDS_PN = "B41";
"DDR0_DQ<34>":   PN = "C38"  !CDS_PN = "C38";
"DDR0_DQ<35>":   PN = "E38"  !CDS_PN = "E38";
"DDR0_DQ<36>":   PN = "E42"  !CDS_PN = "E42";
"DDR0_DQ<37>":   PN = "F41"  !CDS_PN = "F41";
"DDR0_DQ<38>":   PN = "B39"  !CDS_PN = "B39";
"DDR0_DQ<39>":   PN = "F39"  !CDS_PN = "F39";
"DDR0_DQ<40>":   PN = "K37"  !CDS_PN = "K37";
"DDR0_DQ<41>":   PN = "P37"  !CDS_PN = "P37";
"DDR0_DQ<42>":   PN = "L34"  !CDS_PN = "L34";
"DDR0_DQ<43>":   PN = "N34"  !CDS_PN = "N34";
"DDR0_DQ<44>":   PN = "L38"  !CDS_PN = "L38";
"DDR0_DQ<45>":   PN = "N38"  !CDS_PN = "N38";
"DDR0_DQ<46>":   PN = "K35"  !CDS_PN = "K35";
"DDR0_DQ<47>":   PN = "P35"  !CDS_PN = "P35";
"DDR0_DQ<48>":   PN = "K31"  !CDS_PN = "K31";
"DDR0_DQ<49>":   PN = "P31"  !CDS_PN = "P31";
"DDR0_DQ<50>":   PN = "L28"  !CDS_PN = "L28";
"DDR0_DQ<51>":   PN = "N28"  !CDS_PN = "N28";
"DDR0_DQ<52>":   PN = "L32"  !CDS_PN = "L32";
"DDR0_DQ<53>":   PN = "N32"  !CDS_PN = "N32";
"DDR0_DQ<54>":   PN = "K29"  !CDS_PN = "K29";
"DDR0_DQ<55>":   PN = "P29"  !CDS_PN = "P29";
"DDR0_DQ<56>":   PN = "K25"  !CDS_PN = "K25";
"DDR0_DQ<57>":   PN = "P25"  !CDS_PN = "P25";
"DDR0_DQ<58>":   PN = "P23"  !CDS_PN = "P23";
"DDR0_DQ<59>":   PN = "T23"  !CDS_PN = "T23";
"DDR0_DQ<60>":   PN = "L26"  !CDS_PN = "L26";
"DDR0_DQ<61>":   PN = "N26"  !CDS_PN = "N26";
"DDR0_DQ<62>":   PN = "H23"  !CDS_PN = "H23";
"DDR0_DQ<63>":   PN = "K23"  !CDS_PN = "K23";
"DDR0_DQS_DN<0>":   PN = "AJ84"  !CDS_PN = "AJ84";
"DDR0_DQS_DN<1>":   PN = "R84"  !CDS_PN = "R84";
"DDR0_DQS_DN<2>":   PN = "P79"  !CDS_PN = "P79";
"DDR0_DQS_DN<3>":   PN = "T75"  !CDS_PN = "T75";
"DDR0_DQS_DN<4>":   PN = "G40"  !CDS_PN = "G40";
"DDR0_DQS_DN<5>":   PN = "R36"  !CDS_PN = "R36";
"DDR0_DQS_DN<6>":   PN = "R30"  !CDS_PN = "R30";
"DDR0_DQS_DN<7>":   PN = "N24"  !CDS_PN = "N24";
"DDR0_DQS_DN<8>":   PN = "AH67"  !CDS_PN = "AH67";
"DDR0_DQS_DN<9>":   PN = "AL84"  !CDS_PN = "AL84";
"DDR0_DQS_DN<10>":   PN = "U84"  !CDS_PN = "U84";
"DDR0_DQS_DN<11>":   PN = "U82"  !CDS_PN = "U82";
"DDR0_DQS_DN<12>":   PN = "K75"  !CDS_PN = "K75";
"DDR0_DQS_DN<13>":   PN = "A40"  !CDS_PN = "A40";
"DDR0_DQS_DN<14>":   PN = "J36"  !CDS_PN = "J36";
"DDR0_DQS_DN<15>":   PN = "J30"  !CDS_PN = "J30";
"DDR0_DQS_DN<16>":   PN = "J24"  !CDS_PN = "J24";
"DDR0_DQS_DN<17>":   PN = "AB67"  !CDS_PN = "AB67";
"DDR0_DQS_DP<0>":   PN = "AH85"  !CDS_PN = "AH85";
"DDR0_DQS_DP<1>":   PN = "P85"  !CDS_PN = "P85";
"DDR0_DQS_DP<2>":   PN = "R80"  !CDS_PN = "R80";
"DDR0_DQS_DP<3>":   PN = "P75"  !CDS_PN = "P75";
"DDR0_DQS_DP<4>":   PN = "E40"  !CDS_PN = "E40";
"DDR0_DQS_DP<5>":   PN = "N36"  !CDS_PN = "N36";
"DDR0_DQS_DP<6>":   PN = "N30"  !CDS_PN = "N30";
"DDR0_DQS_DP<7>":   PN = "R24"  !CDS_PN = "R24";
"DDR0_DQS_DP<8>":   PN = "AF67"  !CDS_PN = "AF67";
"DDR0_DQS_DP<9>":   PN = "AM85"  !CDS_PN = "AM85";
"DDR0_DQS_DP<10>":   PN = "V85"  !CDS_PN = "V85";
"DDR0_DQS_DP<11>":   PN = "T81"  !CDS_PN = "T81";
"DDR0_DQS_DP<12>":   PN = "M75"  !CDS_PN = "M75";
"DDR0_DQS_DP<13>":   PN = "C40"  !CDS_PN = "C40";
"DDR0_DQS_DP<14>":   PN = "L36"  !CDS_PN = "L36";
"DDR0_DQS_DP<15>":   PN = "L30"  !CDS_PN = "L30";
"DDR0_DQS_DP<16>":   PN = "L24"  !CDS_PN = "L24";
"DDR0_DQS_DP<17>":   PN = "AD67"  !CDS_PN = "AD67";
"DDR0_ECC<0>":   PN = "AC68"  !CDS_PN = "AC68";
"DDR0_ECC<1>":   PN = "AG68"  !CDS_PN = "AG68";
"DDR0_ECC<2>":   PN = "AD65"  !CDS_PN = "AD65";
"DDR0_ECC<3>":   PN = "AF65"  !CDS_PN = "AF65";
"DDR0_ECC<4>":   PN = "AD69"  !CDS_PN = "AD69";
"DDR0_ECC<5>":   PN = "AF69"  !CDS_PN = "AF69";
"DDR0_ECC<6>":   PN = "AC66"  !CDS_PN = "AC66";
"DDR0_ECC<7>":   PN = "AG66"  !CDS_PN = "AG66";
"DDR0_MA<0>":   PN = "F53"  !CDS_PN = "F53";
"DDR0_MA<1>":   PN = "F57"  !CDS_PN = "F57";
"DDR0_MA<2>":   PN = "D57"  !CDS_PN = "D57";
"DDR0_MA<3>":   PN = "C58"  !CDS_PN = "C58";
"DDR0_MA<4>":   PN = "G58"  !CDS_PN = "G58";
"DDR0_MA<5>":   PN = "F59"  !CDS_PN = "F59";
"DDR0_MA<6>":   PN = "D59"  !CDS_PN = "D59";
"DDR0_MA<7>":   PN = "G60"  !CDS_PN = "G60";
"DDR0_MA<8>":   PN = "C60"  !CDS_PN = "C60";
"DDR0_MA<9>":   PN = "F61"  !CDS_PN = "F61";
"DDR0_MA<10>":   PN = "J54"  !CDS_PN = "J54";
"DDR0_MA<11>":   PN = "G62"  !CDS_PN = "G62";
"DDR0_MA<12>":   PN = "J64"  !CDS_PN = "J64";
"DDR0_MA<13>":   PN = "J48"  !CDS_PN = "J48";
"DDR0_MA<14>":   PN = "F51"  !CDS_PN = "F51";
"DDR0_MA<15>":   PN = "K49"  !CDS_PN = "K49";
"DDR0_MA<16>":   PN = "D51"  !CDS_PN = "D51";
"DDR0_MA<17>":   PN = "K47"  !CDS_PN = "K47";
"DDR0_ODT<0>":   PN = "C50"  !CDS_PN = "C50";
"DDR0_ODT<1>":   PN = "C48"  !CDS_PN = "C48";
"DDR0_ODT<2>":   PN = "G50"  !CDS_PN = "G50";
"DDR0_ODT<3>":   PN = "G48"  !CDS_PN = "G48";
"DDR0_PAR":   PN = "D53"  !CDS_PN = "D53";
DRAWING = "@baseboard_fab2_lib.baseboard_fab2(sch_1):page24";
BODY = "SKX_EXT_B","I172": #LOCATION = "U5D1" !CDS_LOCATION = "U5D1" #SEC = "4" !CDS_SEC = "4";
"DDR1_ACT_N":   PN = "T63"  !CDS_PN = "T63";
"DDR1_ALERT_N":   PN = "W62"  !CDS_PN = "W62";
"DDR1_BA<0>":   PN = "T53"  !CDS_PN = "T53";
"DDR1_BA<1>":   PN = "K55"  !CDS_PN = "K55";
"DDR1_BG<0>":   PN = "M61"  !CDS_PN = "M61";
"DDR1_BG<1>":   PN = "N60"  !CDS_PN = "N60";
"DDR1_CID<2>":   PN = "M47"  !CDS_PN = "M47";
"DDR1_CKE<0>":   PN = "N62"  !CDS_PN = "N62";
"DDR1_CKE<1>":   PN = "R64"  !CDS_PN = "R64";
"DDR1_CKE<2>":   PN = "K63"  !CDS_PN = "K63";
"DDR1_CKE<3>":   PN = "L64"  !CDS_PN = "L64";
"DDR1_CLK_DN<0>":   PN = "M53"  !CDS_PN = "M53";
"DDR1_CLK_DN<1>":   PN = "R54"  !CDS_PN = "R54";
"DDR1_CLK_DN<2>":   PN = "N56"  !CDS_PN = "N56";
"DDR1_CLK_DN<3>":   PN = "R56"  !CDS_PN = "R56";
"DDR1_CLK_DP<0>":   PN = "N54"  !CDS_PN = "N54";
"DDR1_CLK_DP<1>":   PN = "T55"  !CDS_PN = "T55";
"DDR1_CLK_DP<2>":   PN = "M57"  !CDS_PN = "M57";
"DDR1_CLK_DP<3>":   PN = "T57"  !CDS_PN = "T57";
"DDR1_CS<0>_N":   PN = "K51"  !CDS_PN = "K51";
"DDR1_CS<1>_N":   PN = "R50"  !CDS_PN = "R50";
"DDR1_CS<2>_N":   PN = "N46"  !CDS_PN = "N46";
"DDR1_CS<3>_N":   PN = "V47"  !CDS_PN = "V47";
"DDR1_CS<4>_N":   PN = "J50"  !CDS_PN = "J50";
"DDR1_CS<5>_N":   PN = "T49"  !CDS_PN = "T49";
"DDR1_CS<6>_N":   PN = "M45"  !CDS_PN = "M45";
"DDR1_CS<7>_N":   PN = "R46"  !CDS_PN = "R46";
"DDR1_DQ<0>":   PN = "AV81"  !CDS_PN = "AV81";
"DDR1_DQ<1>":   PN = "AT79"  !CDS_PN = "AT79";
"DDR1_DQ<2>":   PN = "AN82"  !CDS_PN = "AN82";
"DDR1_DQ<3>":   PN = "AM81"  !CDS_PN = "AM81";
"DDR1_DQ<4>":   PN = "AW80"  !CDS_PN = "AW80";
"DDR1_DQ<5>":   PN = "AV79"  !CDS_PN = "AV79";
"DDR1_DQ<6>":   PN = "AR82"  !CDS_PN = "AR82";
"DDR1_DQ<7>":   PN = "AN80"  !CDS_PN = "AN80";
"DDR1_DQ<8>":   PN = "AH81"  !CDS_PN = "AH81";
"DDR1_DQ<9>":   PN = "AF79"  !CDS_PN = "AF79";
"DDR1_DQ<10>":   PN = "AC82"  !CDS_PN = "AC82";
"DDR1_DQ<11>":   PN = "AB81"  !CDS_PN = "AB81";
"DDR1_DQ<12>":   PN = "AJ80"  !CDS_PN = "AJ80";
"DDR1_DQ<13>":   PN = "AH79"  !CDS_PN = "AH79";
"DDR1_DQ<14>":   PN = "AE82"  !CDS_PN = "AE82";
"DDR1_DQ<15>":   PN = "AC80"  !CDS_PN = "AC80";
"DDR1_DQ<16>":   PN = "E80"  !CDS_PN = "E80";
"DDR1_DQ<17>":   PN = "J80"  !CDS_PN = "J80";
"DDR1_DQ<18>":   PN = "F77"  !CDS_PN = "F77";
"DDR1_DQ<19>":   PN = "H77"  !CDS_PN = "H77";
"DDR1_DQ<20>":   PN = "F81"  !CDS_PN = "F81";
"DDR1_DQ<21>":   PN = "H81"  !CDS_PN = "H81";
"DDR1_DQ<22>":   PN = "E78"  !CDS_PN = "E78";
"DDR1_DQ<23>":   PN = "J78"  !CDS_PN = "J78";
"DDR1_DQ<24>":   PN = "D75"  !CDS_PN = "D75";
"DDR1_DQ<25>":   PN = "C74"  !CDS_PN = "C74";
"DDR1_DQ<26>":   PN = "D71"  !CDS_PN = "D71";
"DDR1_DQ<27>":   PN = "F71"  !CDS_PN = "F71";
"DDR1_DQ<28>":   PN = "F75"  !CDS_PN = "F75";
"DDR1_DQ<29>":   PN = "G74"  !CDS_PN = "G74";
"DDR1_DQ<30>":   PN = "C72"  !CDS_PN = "C72";
"DDR1_DQ<31>":   PN = "G72"  !CDS_PN = "G72";
"DDR1_DQ<32>":   PN = "K43"  !CDS_PN = "K43";
"DDR1_DQ<33>":   PN = "H43"  !CDS_PN = "H43";
"DDR1_DQ<34>":   PN = "L40"  !CDS_PN = "L40";
"DDR1_DQ<35>":   PN = "N40"  !CDS_PN = "N40";
"DDR1_DQ<36>":   PN = "P43"  !CDS_PN = "P43";
"DDR1_DQ<37>":   PN = "T43"  !CDS_PN = "T43";
"DDR1_DQ<38>":   PN = "K41"  !CDS_PN = "K41";
"DDR1_DQ<39>":   PN = "P41"  !CDS_PN = "P41";
"DDR1_DQ<40>":   PN = "C36"  !CDS_PN = "C36";
"DDR1_DQ<41>":   PN = "B35"  !CDS_PN = "B35";
"DDR1_DQ<42>":   PN = "C32"  !CDS_PN = "C32";
"DDR1_DQ<43>":   PN = "E32"  !CDS_PN = "E32";
"DDR1_DQ<44>":   PN = "E36"  !CDS_PN = "E36";
"DDR1_DQ<45>":   PN = "F35"  !CDS_PN = "F35";
"DDR1_DQ<46>":   PN = "B33"  !CDS_PN = "B33";
"DDR1_DQ<47>":   PN = "F33"  !CDS_PN = "F33";
"DDR1_DQ<48>":   PN = "C30"  !CDS_PN = "C30";
"DDR1_DQ<49>":   PN = "B29"  !CDS_PN = "B29";
"DDR1_DQ<50>":   PN = "C26"  !CDS_PN = "C26";
"DDR1_DQ<51>":   PN = "E26"  !CDS_PN = "E26";
"DDR1_DQ<52>":   PN = "E30"  !CDS_PN = "E30";
"DDR1_DQ<53>":   PN = "F29"  !CDS_PN = "F29";
"DDR1_DQ<54>":   PN = "B27"  !CDS_PN = "B27";
"DDR1_DQ<55>":   PN = "F27"  !CDS_PN = "F27";
"DDR1_DQ<56>":   PN = "U28"  !CDS_PN = "U28";
"DDR1_DQ<57>":   PN = "AA28"  !CDS_PN = "AA28";
"DDR1_DQ<58>":   PN = "V25"  !CDS_PN = "V25";
"DDR1_DQ<59>":   PN = "Y25"  !CDS_PN = "Y25";
"DDR1_DQ<60>":   PN = "V29"  !CDS_PN = "V29";
"DDR1_DQ<61>":   PN = "Y29"  !CDS_PN = "Y29";
"DDR1_DQ<62>":   PN = "U26"  !CDS_PN = "U26";
"DDR1_DQ<63>":   PN = "AA26"  !CDS_PN = "AA26";
"DDR1_DQS_DN<0>":   PN = "AP79"  !CDS_PN = "AP79";
"DDR1_DQS_DN<1>":   PN = "AD79"  !CDS_PN = "AD79";
"DDR1_DQS_DN<2>":   PN = "K79"  !CDS_PN = "K79";
"DDR1_DQS_DN<3>":   PN = "H73"  !CDS_PN = "H73";
"DDR1_DQS_DN<4>":   PN = "N42"  !CDS_PN = "N42";
"DDR1_DQS_DN<5>":   PN = "G34"  !CDS_PN = "G34";
"DDR1_DQS_DN<6>":   PN = "G28"  !CDS_PN = "G28";
"DDR1_DQS_DN<7>":   PN = "AB27"  !CDS_PN = "AB27";
"DDR1_DQS_DN<8>":   PN = "N68"  !CDS_PN = "N68";
"DDR1_DQS_DN<9>":   PN = "AU82"  !CDS_PN = "AU82";
"DDR1_DQS_DN<10>":   PN = "AG82"  !CDS_PN = "AG82";
"DDR1_DQS_DN<11>":   PN = "D79"  !CDS_PN = "D79";
"DDR1_DQS_DN<12>":   PN = "B73"  !CDS_PN = "B73";
"DDR1_DQS_DN<13>":   PN = "J42"  !CDS_PN = "J42";
"DDR1_DQS_DN<14>":   PN = "A34"  !CDS_PN = "A34";
"DDR1_DQS_DN<15>":   PN = "A28"  !CDS_PN = "A28";
"DDR1_DQS_DN<16>":   PN = "T27"  !CDS_PN = "T27";
"DDR1_DQS_DN<17>":   PN = "G68"  !CDS_PN = "G68";
"DDR1_DQS_DP<0>":   PN = "AR80"  !CDS_PN = "AR80";
"DDR1_DQS_DP<1>":   PN = "AE80"  !CDS_PN = "AE80";
"DDR1_DQS_DP<2>":   PN = "H79"  !CDS_PN = "H79";
"DDR1_DQS_DP<3>":   PN = "F73"  !CDS_PN = "F73";
"DDR1_DQS_DP<4>":   PN = "R42"  !CDS_PN = "R42";
"DDR1_DQS_DP<5>":   PN = "E34"  !CDS_PN = "E34";
"DDR1_DQS_DP<6>":   PN = "E28"  !CDS_PN = "E28";
"DDR1_DQS_DP<7>":   PN = "Y27"  !CDS_PN = "Y27";
"DDR1_DQS_DP<8>":   PN = "L68"  !CDS_PN = "L68";
"DDR1_DQS_DP<9>":   PN = "AT81"  !CDS_PN = "AT81";
"DDR1_DQS_DP<10>":   PN = "AF81"  !CDS_PN = "AF81";
"DDR1_DQS_DP<11>":   PN = "F79"  !CDS_PN = "F79";
"DDR1_DQS_DP<12>":   PN = "D73"  !CDS_PN = "D73";
"DDR1_DQS_DP<13>":   PN = "L42"  !CDS_PN = "L42";
"DDR1_DQS_DP<14>":   PN = "C34"  !CDS_PN = "C34";
"DDR1_DQS_DP<15>":   PN = "C28"  !CDS_PN = "C28";
"DDR1_DQS_DP<16>":   PN = "V27"  !CDS_PN = "V27";
"DDR1_DQS_DP<17>":   PN = "J68"  !CDS_PN = "J68";
"DDR1_ECC<0>":   PN = "J70"  !CDS_PN = "J70";
"DDR1_ECC<1>":   PN = "H69"  !CDS_PN = "H69";
"DDR1_ECC<2>":   PN = "J66"  !CDS_PN = "J66";
"DDR1_ECC<3>":   PN = "L66"  !CDS_PN = "L66";
"DDR1_ECC<4>":   PN = "L70"  !CDS_PN = "L70";
"DDR1_ECC<5>":   PN = "M69"  !CDS_PN = "M69";
"DDR1_ECC<6>":   PN = "H67"  !CDS_PN = "H67";
"DDR1_ECC<7>":   PN = "M67"  !CDS_PN = "M67";
"DDR1_MA<0>":   PN = "J52"  !CDS_PN = "J52";
"DDR1_MA<1>":   PN = "J58"  !CDS_PN = "J58";
"DDR1_MA<2>":   PN = "K57"  !CDS_PN = "K57";
"DDR1_MA<3>":   PN = "N58"  !CDS_PN = "N58";
"DDR1_MA<4>":   PN = "M59"  !CDS_PN = "M59";
"DDR1_MA<5>":   PN = "R58"  !CDS_PN = "R58";
"DDR1_MA<6>":   PN = "T59"  !CDS_PN = "T59";
"DDR1_MA<7>":   PN = "V61"  !CDS_PN = "V61";
"DDR1_MA<8>":   PN = "W60"  !CDS_PN = "W60";
"DDR1_MA<9>":   PN = "K59"  !CDS_PN = "K59";
"DDR1_MA<10>":   PN = "M55"  !CDS_PN = "M55";
"DDR1_MA<11>":   PN = "R60"  !CDS_PN = "R60";
"DDR1_MA<12>":   PN = "T61"  !CDS_PN = "T61";
"DDR1_MA<13>":   PN = "M51"  !CDS_PN = "M51";
"DDR1_MA<14>":   PN = "T51"  !CDS_PN = "T51";
"DDR1_MA<15>":   PN = "N52"  !CDS_PN = "N52";
"DDR1_MA<16>":   PN = "R52"  !CDS_PN = "R52";
"DDR1_MA<17>":   PN = "N48"  !CDS_PN = "N48";
"DDR1_ODT<0>":   PN = "N50"  !CDS_PN = "N50";
"DDR1_ODT<1>":   PN = "R48"  !CDS_PN = "R48";
"DDR1_ODT<2>":   PN = "M49"  !CDS_PN = "M49";
"DDR1_ODT<3>":   PN = "T47"  !CDS_PN = "T47";
"DDR1_PAR":   PN = "K53"  !CDS_PN = "K53";
DRAWING = "@baseboard_fab2_lib.baseboard_fab2(sch_1):page25";
BODY = "SKX_EXT_B","I172": #LOCATION = "U5D1" !CDS_LOCATION = "U5D1" #SEC = "5" !CDS_SEC = "5";
"DDR2_ACT_N":   PN = "AB61"  !CDS_PN = "AB61";
"DDR2_ALERT_N":   PN = "AD61"  !CDS_PN = "AD61";
"DDR2_BA<0>":   PN = "W52"  !CDS_PN = "W52";
"DDR2_BA<1>":   PN = "AE56"  !CDS_PN = "AE56";
"DDR2_BG<0>":   PN = "AA60"  !CDS_PN = "AA60";
"DDR2_BG<1>":   PN = "AE62"  !CDS_PN = "AE62";
"DDR2_CID<2>":   PN = "AB45"  !CDS_PN = "AB45";
"DDR2_CKE<0>":   PN = "AA62"  !CDS_PN = "AA62";
"DDR2_CKE<1>":   PN = "AD63"  !CDS_PN = "AD63";
"DDR2_CKE<2>":   PN = "V63"  !CDS_PN = "V63";
"DDR2_CKE<3>":   PN = "AB63"  !CDS_PN = "AB63";
"DDR2_CLK_DN<0>":   PN = "AA54"  !CDS_PN = "AA54";
"DDR2_CLK_DN<1>":   PN = "W54"  !CDS_PN = "W54";
"DDR2_CLK_DN<2>":   PN = "AA56"  !CDS_PN = "AA56";
"DDR2_CLK_DN<3>":   PN = "W56"  !CDS_PN = "W56";
"DDR2_CLK_DP<0>":   PN = "AB55"  !CDS_PN = "AB55";
"DDR2_CLK_DP<1>":   PN = "V55"  !CDS_PN = "V55";
"DDR2_CLK_DP<2>":   PN = "AB57"  !CDS_PN = "AB57";
"DDR2_CLK_DP<3>":   PN = "V57"  !CDS_PN = "V57";
"DDR2_CS<0>_N":   PN = "V51"  !CDS_PN = "V51";
"DDR2_CS<1>_N":   PN = "AB49"  !CDS_PN = "AB49";
"DDR2_CS<2>_N":   PN = "W46"  !CDS_PN = "W46";
"DDR2_CS<3>_N":   PN = "AA46"  !CDS_PN = "AA46";
"DDR2_CS<4>_N":   PN = "AB51"  !CDS_PN = "AB51";
"DDR2_CS<5>_N":   PN = "W48"  !CDS_PN = "W48";
"DDR2_CS<6>_N":   PN = "T45"  !CDS_PN = "T45";
"DDR2_CS<7>_N":   PN = "V45"  !CDS_PN = "V45";
"DDR2_DQ<0>":   PN = "AR76"  !CDS_PN = "AR76";
"DDR2_DQ<1>":   PN = "AN74"  !CDS_PN = "AN74";
"DDR2_DQ<2>":   PN = "AK77"  !CDS_PN = "AK77";
"DDR2_DQ<3>":   PN = "AJ76"  !CDS_PN = "AJ76";
"DDR2_DQ<4>":   PN = "AT75"  !CDS_PN = "AT75";
"DDR2_DQ<5>":   PN = "AR74"  !CDS_PN = "AR74";
"DDR2_DQ<6>":   PN = "AM77"  !CDS_PN = "AM77";
"DDR2_DQ<7>":   PN = "AK75"  !CDS_PN = "AK75";
"DDR2_DQ<8>":   PN = "AE76"  !CDS_PN = "AE76";
"DDR2_DQ<9>":   PN = "AC74"  !CDS_PN = "AC74";
"DDR2_DQ<10>":   PN = "Y77"  !CDS_PN = "Y77";
"DDR2_DQ<11>":   PN = "W76"  !CDS_PN = "W76";
"DDR2_DQ<12>":   PN = "AF75"  !CDS_PN = "AF75";
"DDR2_DQ<13>":   PN = "AE74"  !CDS_PN = "AE74";
"DDR2_DQ<14>":   PN = "AB77"  !CDS_PN = "AB77";
"DDR2_DQ<15>":   PN = "Y75"  !CDS_PN = "Y75";
"DDR2_DQ<16>":   PN = "W72"  !CDS_PN = "W72";
"DDR2_DQ<17>":   PN = "AA70"  !CDS_PN = "AA70";
"DDR2_DQ<18>":   PN = "R70"  !CDS_PN = "R70";
"DDR2_DQ<19>":   PN = "T69"  !CDS_PN = "T69";
"DDR2_DQ<20>":   PN = "AA72"  !CDS_PN = "AA72";
"DDR2_DQ<21>":   PN = "AB71"  !CDS_PN = "AB71";
"DDR2_DQ<22>":   PN = "T71"  !CDS_PN = "T71";
"DDR2_DQ<23>":   PN = "V69"  !CDS_PN = "V69";
"DDR2_DQ<24>":   PN = "AM67"  !CDS_PN = "AM67";
"DDR2_DQ<25>":   PN = "AT67"  !CDS_PN = "AT67";
"DDR2_DQ<26>":   PN = "AN64"  !CDS_PN = "AN64";
"DDR2_DQ<27>":   PN = "AR64"  !CDS_PN = "AR64";
"DDR2_DQ<28>":   PN = "AN68"  !CDS_PN = "AN68";
"DDR2_DQ<29>":   PN = "AR68"  !CDS_PN = "AR68";
"DDR2_DQ<30>":   PN = "AM65"  !CDS_PN = "AM65";
"DDR2_DQ<31>":   PN = "AT65"  !CDS_PN = "AT65";
"DDR2_DQ<32>":   PN = "U40"  !CDS_PN = "U40";
"DDR2_DQ<33>":   PN = "AA40"  !CDS_PN = "AA40";
"DDR2_DQ<34>":   PN = "V37"  !CDS_PN = "V37";
"DDR2_DQ<35>":   PN = "Y37"  !CDS_PN = "Y37";
"DDR2_DQ<36>":   PN = "V41"  !CDS_PN = "V41";
"DDR2_DQ<37>":   PN = "Y41"  !CDS_PN = "Y41";
"DDR2_DQ<38>":   PN = "U38"  !CDS_PN = "U38";
"DDR2_DQ<39>":   PN = "AA38"  !CDS_PN = "AA38";
"DDR2_DQ<40>":   PN = "U34"  !CDS_PN = "U34";
"DDR2_DQ<41>":   PN = "AA34"  !CDS_PN = "AA34";
"DDR2_DQ<42>":   PN = "V31"  !CDS_PN = "V31";
"DDR2_DQ<43>":   PN = "Y31"  !CDS_PN = "Y31";
"DDR2_DQ<44>":   PN = "V35"  !CDS_PN = "V35";
"DDR2_DQ<45>":   PN = "Y35"  !CDS_PN = "Y35";
"DDR2_DQ<46>":   PN = "U32"  !CDS_PN = "U32";
"DDR2_DQ<47>":   PN = "AA32"  !CDS_PN = "AA32";
"DDR2_DQ<48>":   PN = "AD31"  !CDS_PN = "AD31";
"DDR2_DQ<49>":   PN = "AH31"  !CDS_PN = "AH31";
"DDR2_DQ<50>":   PN = "AE28"  !CDS_PN = "AE28";
"DDR2_DQ<51>":   PN = "AG28"  !CDS_PN = "AG28";
"DDR2_DQ<52>":   PN = "AE32"  !CDS_PN = "AE32";
"DDR2_DQ<53>":   PN = "AG32"  !CDS_PN = "AG32";
"DDR2_DQ<54>":   PN = "AD29"  !CDS_PN = "AD29";
"DDR2_DQ<55>":   PN = "AH29"  !CDS_PN = "AH29";
"DDR2_DQ<56>":   PN = "AD25"  !CDS_PN = "AD25";
"DDR2_DQ<57>":   PN = "AH25"  !CDS_PN = "AH25";
"DDR2_DQ<58>":   PN = "AE22"  !CDS_PN = "AE22";
"DDR2_DQ<59>":   PN = "AG22"  !CDS_PN = "AG22";
"DDR2_DQ<60>":   PN = "AE26"  !CDS_PN = "AE26";
"DDR2_DQ<61>":   PN = "AG26"  !CDS_PN = "AG26";
"DDR2_DQ<62>":   PN = "AD23"  !CDS_PN = "AD23";
"DDR2_DQ<63>":   PN = "AH23"  !CDS_PN = "AH23";
"DDR2_DQS_DN<0>":   PN = "AL74"  !CDS_PN = "AL74";
"DDR2_DQS_DN<1>":   PN = "AA74"  !CDS_PN = "AA74";
"DDR2_DQS_DN<2>":   PN = "Y69"  !CDS_PN = "Y69";
"DDR2_DQS_DN<3>":   PN = "AU66"  !CDS_PN = "AU66";
"DDR2_DQS_DN<4>":   PN = "AB39"  !CDS_PN = "AB39";
"DDR2_DQS_DN<5>":   PN = "AB33"  !CDS_PN = "AB33";
"DDR2_DQS_DN<6>":   PN = "AJ30"  !CDS_PN = "AJ30";
"DDR2_DQS_DN<7>":   PN = "AJ24"  !CDS_PN = "AJ24";
"DDR2_DQS_DN<8>":   PN = "BB71"  !CDS_PN = "BB71";
"DDR2_DQS_DN<9>":   PN = "AP77"  !CDS_PN = "AP77";
"DDR2_DQS_DN<10>":   PN = "AD77"  !CDS_PN = "AD77";
"DDR2_DQS_DN<11>":   PN = "U72"  !CDS_PN = "U72";
"DDR2_DQS_DN<12>":   PN = "AL66"  !CDS_PN = "AL66";
"DDR2_DQS_DN<13>":   PN = "T39"  !CDS_PN = "T39";
"DDR2_DQS_DN<14>":   PN = "T33"  !CDS_PN = "T33";
"DDR2_DQS_DN<15>":   PN = "AC30"  !CDS_PN = "AC30";
"DDR2_DQS_DN<16>":   PN = "AC24"  !CDS_PN = "AC24";
"DDR2_DQS_DN<17>":   PN = "AT71"  !CDS_PN = "AT71";
"DDR2_DQS_DP<0>":   PN = "AM75"  !CDS_PN = "AM75";
"DDR2_DQS_DP<1>":   PN = "AB75"  !CDS_PN = "AB75";
"DDR2_DQS_DP<2>":   PN = "W70"  !CDS_PN = "W70";
"DDR2_DQS_DP<3>":   PN = "AR66"  !CDS_PN = "AR66";
"DDR2_DQS_DP<4>":   PN = "Y39"  !CDS_PN = "Y39";
"DDR2_DQS_DP<5>":   PN = "Y33"  !CDS_PN = "Y33";
"DDR2_DQS_DP<6>":   PN = "AG30"  !CDS_PN = "AG30";
"DDR2_DQS_DP<7>":   PN = "AG24"  !CDS_PN = "AG24";
"DDR2_DQS_DP<8>":   PN = "AY71"  !CDS_PN = "AY71";
"DDR2_DQS_DP<9>":   PN = "AN76"  !CDS_PN = "AN76";
"DDR2_DQS_DP<10>":   PN = "AC76"  !CDS_PN = "AC76";
"DDR2_DQS_DP<11>":   PN = "V71"  !CDS_PN = "V71";
"DDR2_DQS_DP<12>":   PN = "AN66"  !CDS_PN = "AN66";
"DDR2_DQS_DP<13>":   PN = "V39"  !CDS_PN = "V39";
"DDR2_DQS_DP<14>":   PN = "V33"  !CDS_PN = "V33";
"DDR2_DQS_DP<15>":   PN = "AE30"  !CDS_PN = "AE30";
"DDR2_DQS_DP<16>":   PN = "AE24"  !CDS_PN = "AE24";
"DDR2_DQS_DP<17>":   PN = "AV71"  !CDS_PN = "AV71";
"DDR2_ECC<0>":   PN = "AU72"  !CDS_PN = "AU72";
"DDR2_ECC<1>":   PN = "BA72"  !CDS_PN = "BA72";
"DDR2_ECC<2>":   PN = "AV69"  !CDS_PN = "AV69";
"DDR2_ECC<3>":   PN = "AY69"  !CDS_PN = "AY69";
"DDR2_ECC<4>":   PN = "AV73"  !CDS_PN = "AV73";
"DDR2_ECC<5>":   PN = "AY73"  !CDS_PN = "AY73";
"DDR2_ECC<6>":   PN = "AU70"  !CDS_PN = "AU70";
"DDR2_ECC<7>":   PN = "BA70"  !CDS_PN = "BA70";
"DDR2_MA<0>":   PN = "AB53"  !CDS_PN = "AB53";
"DDR2_MA<1>":   PN = "AE58"  !CDS_PN = "AE58";
"DDR2_MA<2>":   PN = "AD57"  !CDS_PN = "AD57";
"DDR2_MA<3>":   PN = "W58"  !CDS_PN = "W58";
"DDR2_MA<4>":   PN = "AA58"  !CDS_PN = "AA58";
"DDR2_MA<5>":   PN = "V59"  !CDS_PN = "V59";
"DDR2_MA<6>":   PN = "AB59"  !CDS_PN = "AB59";
"DDR2_MA<7>":   PN = "AE60"  !CDS_PN = "AE60";
"DDR2_MA<8>":   PN = "AD59"  !CDS_PN = "AD59";
"DDR2_MA<9>":   PN = "AG58"  !CDS_PN = "AG58";
"DDR2_MA<10>":   PN = "AD55"  !CDS_PN = "AD55";
"DDR2_MA<11>":   PN = "AG60"  !CDS_PN = "AG60";
"DDR2_MA<12>":   PN = "AG62"  !CDS_PN = "AG62";
"DDR2_MA<13>":   PN = "AD53"  !CDS_PN = "AD53";
"DDR2_MA<14>":   PN = "W50"  !CDS_PN = "W50";
"DDR2_MA<15>":   PN = "AE54"  !CDS_PN = "AE54";
"DDR2_MA<16>":   PN = "AA52"  !CDS_PN = "AA52";
"DDR2_MA<17>":   PN = "AC46"  !CDS_PN = "AC46";
"DDR2_ODT<0>":   PN = "AA50"  !CDS_PN = "AA50";
"DDR2_ODT<1>":   PN = "AA48"  !CDS_PN = "AA48";
"DDR2_ODT<2>":   PN = "V49"  !CDS_PN = "V49";
"DDR2_ODT<3>":   PN = "AB47"  !CDS_PN = "AB47";
"DDR2_PAR":   PN = "V53"  !CDS_PN = "V53";
DRAWING = "@baseboard_fab2_lib.baseboard_fab2(sch_1):page26";
BODY = "SKX_EXT_B","I172": #LOCATION = "U5D1" !CDS_LOCATION = "U5D1" #SEC = "6" !CDS_SEC = "6";
"DDR3_ACT_N":   PN = "DW60"  !CDS_PN = "DW60";
"DDR3_ALERT_N":   PN = "ED63"  !CDS_PN = "ED63";
"DDR3_BA<0>":   PN = "EE52"  !CDS_PN = "EE52";
"DDR3_BA<1>":   PN = "EA54"  !CDS_PN = "EA54";
"DDR3_BG<0>":   PN = "ED61"  !CDS_PN = "ED61";
"DDR3_BG<1>":   PN = "DW62"  !CDS_PN = "DW62";
"DDR3_CID<2>":   PN = "DV47"  !CDS_PN = "DV47";
"DDR3_CKE<0>":   PN = "EE62"  !CDS_PN = "EE62";
"DDR3_CKE<1>":   PN = "EF63"  !CDS_PN = "EF63";
"DDR3_CKE<2>":   PN = "EA62"  !CDS_PN = "EA62";
"DDR3_CKE<3>":   PN = "EB63"  !CDS_PN = "EB63";
"DDR3_CLK_DN<0>":   PN = "ED55"  !CDS_PN = "ED55";
"DDR3_CLK_DN<1>":   PN = "EF55"  !CDS_PN = "EF55";
"DDR3_CLK_DN<2>":   PN = "DW56"  !CDS_PN = "DW56";
"DDR3_CLK_DN<3>":   PN = "EF57"  !CDS_PN = "EF57";
"DDR3_CLK_DP<0>":   PN = "EB55"  !CDS_PN = "EB55";
"DDR3_CLK_DP<1>":   PN = "EE54"  !CDS_PN = "EE54";
"DDR3_CLK_DP<2>":   PN = "EA56"  !CDS_PN = "EA56";
"DDR3_CLK_DP<3>":   PN = "EE56"  !CDS_PN = "EE56";
"DDR3_CS<0>_N":   PN = "EF51"  !CDS_PN = "EF51";
"DDR3_CS<1>_N":   PN = "ED49"  !CDS_PN = "ED49";
"DDR3_CS<2>_N":   PN = "ED47"  !CDS_PN = "ED47";
"DDR3_CS<3>_N":   PN = "EB47"  !CDS_PN = "EB47";
"DDR3_CS<4>_N":   PN = "EB51"  !CDS_PN = "EB51";
"DDR3_CS<5>_N":   PN = "EB49"  !CDS_PN = "EB49";
"DDR3_CS<6>_N":   PN = "DV45"  !CDS_PN = "DV45";
"DDR3_CS<7>_N":   PN = "EB45"  !CDS_PN = "EB45";
"DDR3_DQ<0>":   PN = "CN84"  !CDS_PN = "CN84";
"DDR3_DQ<1>":   PN = "CN86"  !CDS_PN = "CN86";
"DDR3_DQ<2>":   PN = "DA86"  !CDS_PN = "DA86";
"DDR3_DQ<3>":   PN = "DA84"  !CDS_PN = "DA84";
"DDR3_DQ<4>":   PN = "CL84"  !CDS_PN = "CL84";
"DDR3_DQ<5>":   PN = "CL86"  !CDS_PN = "CL86";
"DDR3_DQ<6>":   PN = "CW86"  !CDS_PN = "CW86";
"DDR3_DQ<7>":   PN = "CW84"  !CDS_PN = "CW84";
"DDR3_DQ<8>":   PN = "DG84"  !CDS_PN = "DG84";
"DDR3_DQ<9>":   PN = "DH85"  !CDS_PN = "DH85";
"DDR3_DQ<10>":   PN = "DV83"  !CDS_PN = "DV83";
"DDR3_DQ<11>":   PN = "DY83"  !CDS_PN = "DY83";
"DDR3_DQ<12>":   PN = "DD85"  !CDS_PN = "DD85";
"DDR3_DQ<13>":   PN = "DE84"  !CDS_PN = "DE84";
"DDR3_DQ<14>":   PN = "DR84"  !CDS_PN = "DR84";
"DDR3_DQ<15>":   PN = "DV85"  !CDS_PN = "DV85";
"DDR3_DQ<16>":   PN = "DM79"  !CDS_PN = "DM79";
"DDR3_DQ<17>":   PN = "DK81"  !CDS_PN = "DK81";
"DDR3_DQ<18>":   PN = "DT81"  !CDS_PN = "DT81";
"DDR3_DQ<19>":   PN = "DR82"  !CDS_PN = "DR82";
"DDR3_DQ<20>":   PN = "DK79"  !CDS_PN = "DK79";
"DDR3_DQ<21>":   PN = "DJ80"  !CDS_PN = "DJ80";
"DDR3_DQ<22>":   PN = "DR80"  !CDS_PN = "DR80";
"DDR3_DQ<23>":   PN = "DN82"  !CDS_PN = "DN82";
"DDR3_DQ<24>":   PN = "DN76"  !CDS_PN = "DN76";
"DDR3_DQ<25>":   PN = "DU76"  !CDS_PN = "DU76";
"DDR3_DQ<26>":   PN = "DP73"  !CDS_PN = "DP73";
"DDR3_DQ<27>":   PN = "DT73"  !CDS_PN = "DT73";
"DDR3_DQ<28>":   PN = "DP77"  !CDS_PN = "DP77";
"DDR3_DQ<29>":   PN = "DT77"  !CDS_PN = "DT77";
"DDR3_DQ<30>":   PN = "DN74"  !CDS_PN = "DN74";
"DDR3_DQ<31>":   PN = "DU74"  !CDS_PN = "DU74";
"DDR3_DQ<32>":   PN = "EC40"  !CDS_PN = "EC40";
"DDR3_DQ<33>":   PN = "ED39"  !CDS_PN = "ED39";
"DDR3_DQ<34>":   PN = "EA36"  !CDS_PN = "EA36";
"DDR3_DQ<35>":   PN = "EC36"  !CDS_PN = "EC36";
"DDR3_DQ<36>":   PN = "DY39"  !CDS_PN = "DY39";
"DDR3_DQ<37>":   PN = "EA40"  !CDS_PN = "EA40";
"DDR3_DQ<38>":   PN = "DY37"  !CDS_PN = "DY37";
"DDR3_DQ<39>":   PN = "ED37"  !CDS_PN = "ED37";
"DDR3_DQ<40>":   PN = "DN36"  !CDS_PN = "DN36";
"DDR3_DQ<41>":   PN = "DU36"  !CDS_PN = "DU36";
"DDR3_DQ<42>":   PN = "DP33"  !CDS_PN = "DP33";
"DDR3_DQ<43>":   PN = "DT33"  !CDS_PN = "DT33";
"DDR3_DQ<44>":   PN = "DP37"  !CDS_PN = "DP37";
"DDR3_DQ<45>":   PN = "DT37"  !CDS_PN = "DT37";
"DDR3_DQ<46>":   PN = "DN34"  !CDS_PN = "DN34";
"DDR3_DQ<47>":   PN = "DU34"  !CDS_PN = "DU34";
"DDR3_DQ<48>":   PN = "DN30"  !CDS_PN = "DN30";
"DDR3_DQ<49>":   PN = "DU30"  !CDS_PN = "DU30";
"DDR3_DQ<50>":   PN = "DP27"  !CDS_PN = "DP27";
"DDR3_DQ<51>":   PN = "DT27"  !CDS_PN = "DT27";
"DDR3_DQ<52>":   PN = "DP31"  !CDS_PN = "DP31";
"DDR3_DQ<53>":   PN = "DT31"  !CDS_PN = "DT31";
"DDR3_DQ<54>":   PN = "DN28"  !CDS_PN = "DN28";
"DDR3_DQ<55>":   PN = "DU28"  !CDS_PN = "DU28";
"DDR3_DQ<56>":   PN = "DN24"  !CDS_PN = "DN24";
"DDR3_DQ<57>":   PN = "DU24"  !CDS_PN = "DU24";
"DDR3_DQ<58>":   PN = "DY21"  !CDS_PN = "DY21";
"DDR3_DQ<59>":   PN = "EB21"  !CDS_PN = "EB21";
"DDR3_DQ<60>":   PN = "DP25"  !CDS_PN = "DP25";
"DDR3_DQ<61>":   PN = "DT25"  !CDS_PN = "DT25";
"DDR3_DQ<62>":   PN = "EC22"  !CDS_PN = "EC22";
"DDR3_DQ<63>":   PN = "DW22"  !CDS_PN = "DW22";
"DDR3_DQS_DN<0>":   PN = "CU84"  !CDS_PN = "CU84";
"DDR3_DQS_DN<1>":   PN = "DN84"  !CDS_PN = "DN84";
"DDR3_DQS_DN<2>":   PN = "DL82"  !CDS_PN = "DL82";
"DDR3_DQS_DN<3>":   PN = "DV75"  !CDS_PN = "DV75";
"DDR3_DQS_DN<4>":   PN = "EE38"  !CDS_PN = "EE38";
"DDR3_DQS_DN<5>":   PN = "DV35"  !CDS_PN = "DV35";
"DDR3_DQS_DN<6>":   PN = "DV29"  !CDS_PN = "DV29";
"DDR3_DQS_DN<7>":   PN = "DV23"  !CDS_PN = "DV23";
"DDR3_DQS_DN<8>":   PN = "DF67"  !CDS_PN = "DF67";
"DDR3_DQS_DN<9>":   PN = "CR84"  !CDS_PN = "CR84";
"DDR3_DQS_DN<10>":   PN = "DM85"  !CDS_PN = "DM85";
"DDR3_DQS_DN<11>":   PN = "DN80"  !CDS_PN = "DN80";
"DDR3_DQS_DN<12>":   PN = "DP75"  !CDS_PN = "DP75";
"DDR3_DQS_DN<13>":   PN = "EA38"  !CDS_PN = "EA38";
"DDR3_DQS_DN<14>":   PN = "DP35"  !CDS_PN = "DP35";
"DDR3_DQS_DN<15>":   PN = "DM29"  !CDS_PN = "DM29";
"DDR3_DQS_DN<16>":   PN = "DM23"  !CDS_PN = "DM23";
"DDR3_DQS_DN<17>":   PN = "DB67"  !CDS_PN = "DB67";
"DDR3_DQS_DP<0>":   PN = "CV85"  !CDS_PN = "CV85";
"DDR3_DQS_DP<1>":   PN = "DP85"  !CDS_PN = "DP85";
"DDR3_DQS_DP<2>":   PN = "DM81"  !CDS_PN = "DM81";
"DDR3_DQS_DP<3>":   PN = "DT75"  !CDS_PN = "DT75";
"DDR3_DQS_DP<4>":   PN = "EC38"  !CDS_PN = "EC38";
"DDR3_DQS_DP<5>":   PN = "DT35"  !CDS_PN = "DT35";
"DDR3_DQS_DP<6>":   PN = "DT29"  !CDS_PN = "DT29";
"DDR3_DQS_DP<7>":   PN = "DT23"  !CDS_PN = "DT23";
"DDR3_DQS_DP<8>":   PN = "DD67"  !CDS_PN = "DD67";
"DDR3_DQS_DP<9>":   PN = "CP85"  !CDS_PN = "CP85";
"DDR3_DQS_DP<10>":   PN = "DL84"  !CDS_PN = "DL84";
"DDR3_DQS_DP<11>":   PN = "DP79"  !CDS_PN = "DP79";
"DDR3_DQS_DP<12>":   PN = "DM75"  !CDS_PN = "DM75";
"DDR3_DQS_DP<13>":   PN = "DW38"  !CDS_PN = "DW38";
"DDR3_DQS_DP<14>":   PN = "DM35"  !CDS_PN = "DM35";
"DDR3_DQS_DP<15>":   PN = "DP29"  !CDS_PN = "DP29";
"DDR3_DQS_DP<16>":   PN = "DP23"  !CDS_PN = "DP23";
"DDR3_DQS_DP<17>":   PN = "CY67"  !CDS_PN = "CY67";
"DDR3_ECC<0>":   PN = "DA68"  !CDS_PN = "DA68";
"DDR3_ECC<1>":   PN = "DE68"  !CDS_PN = "DE68";
"DDR3_ECC<2>":   PN = "DB65"  !CDS_PN = "DB65";
"DDR3_ECC<3>":   PN = "DD65"  !CDS_PN = "DD65";
"DDR3_ECC<4>":   PN = "DB69"  !CDS_PN = "DB69";
"DDR3_ECC<5>":   PN = "DD69"  !CDS_PN = "DD69";
"DDR3_ECC<6>":   PN = "DA66"  !CDS_PN = "DA66";
"DDR3_ECC<7>":   PN = "DE66"  !CDS_PN = "DE66";
"DDR3_MA<0>":   PN = "EB53"  !CDS_PN = "EB53";
"DDR3_MA<1>":   PN = "ED57"  !CDS_PN = "ED57";
"DDR3_MA<2>":   PN = "EE58"  !CDS_PN = "EE58";
"DDR3_MA<3>":   PN = "EB57"  !CDS_PN = "EB57";
"DDR3_MA<4>":   PN = "ED59"  !CDS_PN = "ED59";
"DDR3_MA<5>":   PN = "EA58"  !CDS_PN = "EA58";
"DDR3_MA<6>":   PN = "EE60"  !CDS_PN = "EE60";
"DDR3_MA<7>":   PN = "EA60"  !CDS_PN = "EA60";
"DDR3_MA<8>":   PN = "EB59"  !CDS_PN = "EB59";
"DDR3_MA<9>":   PN = "EF61"  !CDS_PN = "EF61";
"DDR3_MA<10>":   PN = "DW54"  !CDS_PN = "DW54";
"DDR3_MA<11>":   PN = "EB61"  !CDS_PN = "EB61";
"DDR3_MA<12>":   PN = "DT63"  !CDS_PN = "DT63";
"DDR3_MA<13>":   PN = "DW48"  !CDS_PN = "DW48";
"DDR3_MA<14>":   PN = "ED51"  !CDS_PN = "ED51";
"DDR3_MA<15>":   PN = "DV49"  !CDS_PN = "DV49";
"DDR3_MA<16>":   PN = "EA52"  !CDS_PN = "EA52";
"DDR3_MA<17>":   PN = "EA46"  !CDS_PN = "EA46";
"DDR3_ODT<0>":   PN = "EE50"  !CDS_PN = "EE50";
"DDR3_ODT<1>":   PN = "EE48"  !CDS_PN = "EE48";
"DDR3_ODT<2>":   PN = "EA50"  !CDS_PN = "EA50";
"DDR3_ODT<3>":   PN = "EA48"  !CDS_PN = "EA48";
"DDR3_PAR":   PN = "ED53"  !CDS_PN = "ED53";
DRAWING = "@baseboard_fab2_lib.baseboard_fab2(sch_1):page27";
BODY = "SKX_EXT_B","I172": #LOCATION = "U5D1" !CDS_LOCATION = "U5D1" #SEC = "7" !CDS_SEC = "7";
"DDR4_ACT_N":   PN = "DR62"  !CDS_PN = "DR62";
"DDR4_ALERT_N":   PN = "DT61"  !CDS_PN = "DT61";
"DDR4_BA<0>":   PN = "DM53"  !CDS_PN = "DM53";
"DDR4_BA<1>":   PN = "DV55"  !CDS_PN = "DV55";
"DDR4_BG<0>":   PN = "DJ62"  !CDS_PN = "DJ62";
"DDR4_BG<1>":   PN = "DM61"  !CDS_PN = "DM61";
"DDR4_CID<2>":   PN = "DT47"  !CDS_PN = "DT47";
"DDR4_CKE<0>":   PN = "DM63"  !CDS_PN = "DM63";
"DDR4_CKE<1>":   PN = "DN64"  !CDS_PN = "DN64";
"DDR4_CKE<2>":   PN = "DL64"  !CDS_PN = "DL64";
"DDR4_CKE<3>":   PN = "DR64"  !CDS_PN = "DR64";
"DDR4_CLK_DN<0>":   PN = "DM55"  !CDS_PN = "DM55";
"DDR4_CLK_DN<1>":   PN = "DR54"  !CDS_PN = "DR54";
"DDR4_CLK_DN<2>":   PN = "DM57"  !CDS_PN = "DM57";
"DDR4_CLK_DN<3>":   PN = "DT57"  !CDS_PN = "DT57";
"DDR4_CLK_DP<0>":   PN = "DN54"  !CDS_PN = "DN54";
"DDR4_CLK_DP<1>":   PN = "DT53"  !CDS_PN = "DT53";
"DDR4_CLK_DP<2>":   PN = "DN56"  !CDS_PN = "DN56";
"DDR4_CLK_DP<3>":   PN = "DR56"  !CDS_PN = "DR56";
"DDR4_CS<0>_N":   PN = "DV51"  !CDS_PN = "DV51";
"DDR4_CS<1>_N":   PN = "DN50"  !CDS_PN = "DN50";
"DDR4_CS<2>_N":   PN = "DR46"  !CDS_PN = "DR46";
"DDR4_CS<3>_N":   PN = "DK47"  !CDS_PN = "DK47";
"DDR4_CS<4>_N":   PN = "DW50"  !CDS_PN = "DW50";
"DDR4_CS<5>_N":   PN = "DM49"  !CDS_PN = "DM49";
"DDR4_CS<6>_N":   PN = "DT45"  !CDS_PN = "DT45";
"DDR4_CS<7>_N":   PN = "DN46"  !CDS_PN = "DN46";
"DDR4_DQ<0>":   PN = "CM79"  !CDS_PN = "CM79";
"DDR4_DQ<1>":   PN = "CK81"  !CDS_PN = "CK81";
"DDR4_DQ<2>":   PN = "CT81"  !CDS_PN = "CT81";
"DDR4_DQ<3>":   PN = "CR82"  !CDS_PN = "CR82";
"DDR4_DQ<4>":   PN = "CK79"  !CDS_PN = "CK79";
"DDR4_DQ<5>":   PN = "CJ80"  !CDS_PN = "CJ80";
"DDR4_DQ<6>":   PN = "CR80"  !CDS_PN = "CR80";
"DDR4_DQ<7>":   PN = "CN82"  !CDS_PN = "CN82";
"DDR4_DQ<8>":   PN = "DB79"  !CDS_PN = "DB79";
"DDR4_DQ<9>":   PN = "CY81"  !CDS_PN = "CY81";
"DDR4_DQ<10>":   PN = "DE80"  !CDS_PN = "DE80";
"DDR4_DQ<11>":   PN = "DF81"  !CDS_PN = "DF81";
"DDR4_DQ<12>":   PN = "CY79"  !CDS_PN = "CY79";
"DDR4_DQ<13>":   PN = "CW80"  !CDS_PN = "CW80";
"DDR4_DQ<14>":   PN = "DC82"  !CDS_PN = "DC82";
"DDR4_DQ<15>":   PN = "DE82"  !CDS_PN = "DE82";
"DDR4_DQ<16>":   PN = "DW80"  !CDS_PN = "DW80";
"DDR4_DQ<17>":   PN = "EC80"  !CDS_PN = "EC80";
"DDR4_DQ<18>":   PN = "DY77"  !CDS_PN = "DY77";
"DDR4_DQ<19>":   PN = "EB77"  !CDS_PN = "EB77";
"DDR4_DQ<20>":   PN = "DY81"  !CDS_PN = "DY81";
"DDR4_DQ<21>":   PN = "EB81"  !CDS_PN = "EB81";
"DDR4_DQ<22>":   PN = "DW78"  !CDS_PN = "DW78";
"DDR4_DQ<23>":   PN = "EC78"  !CDS_PN = "EC78";
"DDR4_DQ<24>":   PN = "ED75"  !CDS_PN = "ED75";
"DDR4_DQ<25>":   PN = "EE74"  !CDS_PN = "EE74";
"DDR4_DQ<26>":   PN = "EB71"  !CDS_PN = "EB71";
"DDR4_DQ<27>":   PN = "ED71"  !CDS_PN = "ED71";
"DDR4_DQ<28>":   PN = "EA74"  !CDS_PN = "EA74";
"DDR4_DQ<29>":   PN = "EB75"  !CDS_PN = "EB75";
"DDR4_DQ<30>":   PN = "EA72"  !CDS_PN = "EA72";
"DDR4_DQ<31>":   PN = "EE72"  !CDS_PN = "EE72";
"DDR4_DQ<32>":   PN = "DU42"  !CDS_PN = "DU42";
"DDR4_DQ<33>":   PN = "DW42"  !CDS_PN = "DW42";
"DDR4_DQ<34>":   PN = "DP39"  !CDS_PN = "DP39";
"DDR4_DQ<35>":   PN = "DT39"  !CDS_PN = "DT39";
"DDR4_DQ<36>":   PN = "DL42"  !CDS_PN = "DL42";
"DDR4_DQ<37>":   PN = "DN42"  !CDS_PN = "DN42";
"DDR4_DQ<38>":   PN = "DN40"  !CDS_PN = "DN40";
"DDR4_DQ<39>":   PN = "DU40"  !CDS_PN = "DU40";
"DDR4_DQ<40>":   PN = "EC34"  !CDS_PN = "EC34";
"DDR4_DQ<41>":   PN = "ED33"  !CDS_PN = "ED33";
"DDR4_DQ<42>":   PN = "EA30"  !CDS_PN = "EA30";
"DDR4_DQ<43>":   PN = "EC30"  !CDS_PN = "EC30";
"DDR4_DQ<44>":   PN = "DY33"  !CDS_PN = "DY33";
"DDR4_DQ<45>":   PN = "EA34"  !CDS_PN = "EA34";
"DDR4_DQ<46>":   PN = "DY31"  !CDS_PN = "DY31";
"DDR4_DQ<47>":   PN = "ED31"  !CDS_PN = "ED31";
"DDR4_DQ<48>":   PN = "EC28"  !CDS_PN = "EC28";
"DDR4_DQ<49>":   PN = "ED27"  !CDS_PN = "ED27";
"DDR4_DQ<50>":   PN = "EA24"  !CDS_PN = "EA24";
"DDR4_DQ<51>":   PN = "EC24"  !CDS_PN = "EC24";
"DDR4_DQ<52>":   PN = "DY27"  !CDS_PN = "DY27";
"DDR4_DQ<53>":   PN = "EA28"  !CDS_PN = "EA28";
"DDR4_DQ<54>":   PN = "DY25"  !CDS_PN = "DY25";
"DDR4_DQ<55>":   PN = "ED25"  !CDS_PN = "ED25";
"DDR4_DQ<56>":   PN = "DF27"  !CDS_PN = "DF27";
"DDR4_DQ<57>":   PN = "DK27"  !CDS_PN = "DK27";
"DDR4_DQ<58>":   PN = "DD25"  !CDS_PN = "DD25";
"DDR4_DQ<59>":   PN = "DJ24"  !CDS_PN = "DJ24";
"DDR4_DQ<60>":   PN = "DG28"  !CDS_PN = "DG28";
"DDR4_DQ<61>":   PN = "DJ28"  !CDS_PN = "DJ28";
"DDR4_DQ<62>":   PN = "DF25"  !CDS_PN = "DF25";
"DDR4_DQ<63>":   PN = "DK25"  !CDS_PN = "DK25";
"DDR4_DQS_DN<0>":   PN = "CL82"  !CDS_PN = "CL82";
"DDR4_DQS_DN<1>":   PN = "DA82"  !CDS_PN = "DA82";
"DDR4_DQS_DN<2>":   PN = "ED79"  !CDS_PN = "ED79";
"DDR4_DQS_DN<3>":   PN = "EF73"  !CDS_PN = "EF73";
"DDR4_DQS_DN<4>":   PN = "DV41"  !CDS_PN = "DV41";
"DDR4_DQS_DN<5>":   PN = "EE32"  !CDS_PN = "EE32";
"DDR4_DQS_DN<6>":   PN = "EE26"  !CDS_PN = "EE26";
"DDR4_DQS_DN<7>":   PN = "DL26"  !CDS_PN = "DL26";
"DDR4_DQS_DN<8>":   PN = "EB67"  !CDS_PN = "EB67";
"DDR4_DQS_DN<9>":   PN = "CN80"  !CDS_PN = "CN80";
"DDR4_DQS_DN<10>":   PN = "DC80"  !CDS_PN = "DC80";
"DDR4_DQS_DN<11>":   PN = "DY79"  !CDS_PN = "DY79";
"DDR4_DQS_DN<12>":   PN = "EB73"  !CDS_PN = "EB73";
"DDR4_DQS_DN<13>":   PN = "DP41"  !CDS_PN = "DP41";
"DDR4_DQS_DN<14>":   PN = "EA32"  !CDS_PN = "EA32";
"DDR4_DQS_DN<15>":   PN = "EA26"  !CDS_PN = "EA26";
"DDR4_DQS_DN<16>":   PN = "DG26"  !CDS_PN = "DG26";
"DDR4_DQS_DN<17>":   PN = "DV67"  !CDS_PN = "DV67";
"DDR4_DQS_DP<0>":   PN = "CM81"  !CDS_PN = "CM81";
"DDR4_DQS_DP<1>":   PN = "DB81"  !CDS_PN = "DB81";
"DDR4_DQS_DP<2>":   PN = "EB79"  !CDS_PN = "EB79";
"DDR4_DQS_DP<3>":   PN = "ED73"  !CDS_PN = "ED73";
"DDR4_DQS_DP<4>":   PN = "DT41"  !CDS_PN = "DT41";
"DDR4_DQS_DP<5>":   PN = "EC32"  !CDS_PN = "EC32";
"DDR4_DQS_DP<6>":   PN = "EC26"  !CDS_PN = "EC26";
"DDR4_DQS_DP<7>":   PN = "DJ26"  !CDS_PN = "DJ26";
"DDR4_DQS_DP<8>":   PN = "DY67"  !CDS_PN = "DY67";
"DDR4_DQS_DP<9>":   PN = "CP79"  !CDS_PN = "CP79";
"DDR4_DQS_DP<10>":   PN = "DD79"  !CDS_PN = "DD79";
"DDR4_DQS_DP<11>":   PN = "DV79"  !CDS_PN = "DV79";
"DDR4_DQS_DP<12>":   PN = "DY73"  !CDS_PN = "DY73";
"DDR4_DQS_DP<13>":   PN = "DM41"  !CDS_PN = "DM41";
"DDR4_DQS_DP<14>":   PN = "DW32"  !CDS_PN = "DW32";
"DDR4_DQS_DP<15>":   PN = "DW26"  !CDS_PN = "DW26";
"DDR4_DQS_DP<16>":   PN = "DE26"  !CDS_PN = "DE26";
"DDR4_DQS_DP<17>":   PN = "DT67"  !CDS_PN = "DT67";
"DDR4_ECC<0>":   PN = "DY69"  !CDS_PN = "DY69";
"DDR4_ECC<1>":   PN = "EA68"  !CDS_PN = "EA68";
"DDR4_ECC<2>":   PN = "DV65"  !CDS_PN = "DV65";
"DDR4_ECC<3>":   PN = "DY65"  !CDS_PN = "DY65";
"DDR4_ECC<4>":   PN = "DU68"  !CDS_PN = "DU68";
"DDR4_ECC<5>":   PN = "DV69"  !CDS_PN = "DV69";
"DDR4_ECC<6>":   PN = "DU66"  !CDS_PN = "DU66";
"DDR4_ECC<7>":   PN = "EA66"  !CDS_PN = "EA66";
"DDR4_MA<0>":   PN = "DW52"  !CDS_PN = "DW52";
"DDR4_MA<1>":   PN = "DW58"  !CDS_PN = "DW58";
"DDR4_MA<2>":   PN = "DV57"  !CDS_PN = "DV57";
"DDR4_MA<3>":   PN = "DR58"  !CDS_PN = "DR58";
"DDR4_MA<4>":   PN = "DT59"  !CDS_PN = "DT59";
"DDR4_MA<5>":   PN = "DN58"  !CDS_PN = "DN58";
"DDR4_MA<6>":   PN = "DM59"  !CDS_PN = "DM59";
"DDR4_MA<7>":   PN = "DK61"  !CDS_PN = "DK61";
"DDR4_MA<8>":   PN = "DJ60"  !CDS_PN = "DJ60";
"DDR4_MA<9>":   PN = "DV59"  !CDS_PN = "DV59";
"DDR4_MA<10>":   PN = "DT55"  !CDS_PN = "DT55";
"DDR4_MA<11>":   PN = "DR60"  !CDS_PN = "DR60";
"DDR4_MA<12>":   PN = "DN60"  !CDS_PN = "DN60";
"DDR4_MA<13>":   PN = "DT51"  !CDS_PN = "DT51";
"DDR4_MA<14>":   PN = "DM51"  !CDS_PN = "DM51";
"DDR4_MA<15>":   PN = "DR52"  !CDS_PN = "DR52";
"DDR4_MA<16>":   PN = "DN52"  !CDS_PN = "DN52";
"DDR4_MA<17>":   PN = "DR48"  !CDS_PN = "DR48";
"DDR4_ODT<0>":   PN = "DR50"  !CDS_PN = "DR50";
"DDR4_ODT<1>":   PN = "DN48"  !CDS_PN = "DN48";
"DDR4_ODT<2>":   PN = "DT49"  !CDS_PN = "DT49";
"DDR4_ODT<3>":   PN = "DM47"  !CDS_PN = "DM47";
"DDR4_PAR":   PN = "DV53"  !CDS_PN = "DV53";
DRAWING = "@baseboard_fab2_lib.baseboard_fab2(sch_1):page28";
BODY = "SKX_EXT_B","I172": #LOCATION = "U5D1" !CDS_LOCATION = "U5D1" #SEC = "8" !CDS_SEC = "8";
"DDR5_ACT_N":   PN = "DC62"  !CDS_PN = "DC62";
"DDR5_ALERT_N":   PN = "DD61"  !CDS_PN = "DD61";
"DDR5_BA<0>":   PN = "DJ52"  !CDS_PN = "DJ52";
"DDR5_BA<1>":   PN = "DC56"  !CDS_PN = "DC56";
"DDR5_BG<0>":   PN = "DA62"  !CDS_PN = "DA62";
"DDR5_BG<1>":   PN = "DF61"  !CDS_PN = "DF61";
"DDR5_CID<2>":   PN = "DF45"  !CDS_PN = "DF45";
"DDR5_CKE<0>":   PN = "DG62"  !CDS_PN = "DG62";
"DDR5_CKE<1>":   PN = "DD63"  !CDS_PN = "DD63";
"DDR5_CKE<2>":   PN = "DK63"  !CDS_PN = "DK63";
"DDR5_CKE<3>":   PN = "DF63"  !CDS_PN = "DF63";
"DDR5_CLK_DN<0>":   PN = "DK55"  !CDS_PN = "DK55";
"DDR5_CLK_DN<1>":   PN = "DF55"  !CDS_PN = "DF55";
"DDR5_CLK_DN<2>":   PN = "DK57"  !CDS_PN = "DK57";
"DDR5_CLK_DN<3>":   PN = "DF57"  !CDS_PN = "DF57";
"DDR5_CLK_DP<0>":   PN = "DJ54"  !CDS_PN = "DJ54";
"DDR5_CLK_DP<1>":   PN = "DG54"  !CDS_PN = "DG54";
"DDR5_CLK_DP<2>":   PN = "DJ56"  !CDS_PN = "DJ56";
"DDR5_CLK_DP<3>":   PN = "DG56"  !CDS_PN = "DG56";
"DDR5_CS<0>_N":   PN = "DK51"  !CDS_PN = "DK51";
"DDR5_CS<1>_N":   PN = "DF49"  !CDS_PN = "DF49";
"DDR5_CS<2>_N":   PN = "DJ46"  !CDS_PN = "DJ46";
"DDR5_CS<3>_N":   PN = "DG46"  !CDS_PN = "DG46";
"DDR5_CS<4>_N":   PN = "DF51"  !CDS_PN = "DF51";
"DDR5_CS<5>_N":   PN = "DJ48"  !CDS_PN = "DJ48";
"DDR5_CS<6>_N":   PN = "DM45"  !CDS_PN = "DM45";
"DDR5_CS<7>_N":   PN = "DK45"  !CDS_PN = "DK45";
"DDR5_DQ<0>":   PN = "CR74"  !CDS_PN = "CR74";
"DDR5_DQ<1>":   PN = "CN76"  !CDS_PN = "CN76";
"DDR5_DQ<2>":   PN = "CW76"  !CDS_PN = "CW76";
"DDR5_DQ<3>":   PN = "CV77"  !CDS_PN = "CV77";
"DDR5_DQ<4>":   PN = "CN74"  !CDS_PN = "CN74";
"DDR5_DQ<5>":   PN = "CM75"  !CDS_PN = "CM75";
"DDR5_DQ<6>":   PN = "CV75"  !CDS_PN = "CV75";
"DDR5_DQ<7>":   PN = "CT77"  !CDS_PN = "CT77";
"DDR5_DQ<8>":   PN = "DE74"  !CDS_PN = "DE74";
"DDR5_DQ<9>":   PN = "DC76"  !CDS_PN = "DC76";
"DDR5_DQ<10>":   PN = "DH75"  !CDS_PN = "DH75";
"DDR5_DQ<11>":   PN = "DJ76"  !CDS_PN = "DJ76";
"DDR5_DQ<12>":   PN = "DC74"  !CDS_PN = "DC74";
"DDR5_DQ<13>":   PN = "DB75"  !CDS_PN = "DB75";
"DDR5_DQ<14>":   PN = "DF77"  !CDS_PN = "DF77";
"DDR5_DQ<15>":   PN = "DH77"  !CDS_PN = "DH77";
"DDR5_DQ<16>":   PN = "DG70"  !CDS_PN = "DG70";
"DDR5_DQ<17>":   PN = "DJ72"  !CDS_PN = "DJ72";
"DDR5_DQ<18>":   PN = "DM69"  !CDS_PN = "DM69";
"DDR5_DQ<19>":   PN = "DN70"  !CDS_PN = "DN70";
"DDR5_DQ<20>":   PN = "DF71"  !CDS_PN = "DF71";
"DDR5_DQ<21>":   PN = "DG72"  !CDS_PN = "DG72";
"DDR5_DQ<22>":   PN = "DK69"  !CDS_PN = "DK69";
"DDR5_DQ<23>":   PN = "DM71"  !CDS_PN = "DM71";
"DDR5_DQ<24>":   PN = "CN66"  !CDS_PN = "CN66";
"DDR5_DQ<25>":   PN = "CU66"  !CDS_PN = "CU66";
"DDR5_DQ<26>":   PN = "CP63"  !CDS_PN = "CP63";
"DDR5_DQ<27>":   PN = "CT63"  !CDS_PN = "CT63";
"DDR5_DQ<28>":   PN = "CP67"  !CDS_PN = "CP67";
"DDR5_DQ<29>":   PN = "CT67"  !CDS_PN = "CT67";
"DDR5_DQ<30>":   PN = "CN64"  !CDS_PN = "CN64";
"DDR5_DQ<31>":   PN = "CU64"  !CDS_PN = "CU64";
"DDR5_DQ<32>":   PN = "DD41"  !CDS_PN = "DD41";
"DDR5_DQ<33>":   PN = "DG42"  !CDS_PN = "DG42";
"DDR5_DQ<34>":   PN = "DE38"  !CDS_PN = "DE38";
"DDR5_DQ<35>":   PN = "DG38"  !CDS_PN = "DG38";
"DDR5_DQ<36>":   PN = "DA42"  !CDS_PN = "DA42";
"DDR5_DQ<37>":   PN = "DE42"  !CDS_PN = "DE42";
"DDR5_DQ<38>":   PN = "DD39"  !CDS_PN = "DD39";
"DDR5_DQ<39>":   PN = "DH39"  !CDS_PN = "DH39";
"DDR5_DQ<40>":   PN = "DF33"  !CDS_PN = "DF33";
"DDR5_DQ<41>":   PN = "DK33"  !CDS_PN = "DK33";
"DDR5_DQ<42>":   PN = "DG30"  !CDS_PN = "DG30";
"DDR5_DQ<43>":   PN = "DJ30"  !CDS_PN = "DJ30";
"DDR5_DQ<44>":   PN = "DG34"  !CDS_PN = "DG34";
"DDR5_DQ<45>":   PN = "DJ34"  !CDS_PN = "DJ34";
"DDR5_DQ<46>":   PN = "DF31"  !CDS_PN = "DF31";
"DDR5_DQ<47>":   PN = "DK31"  !CDS_PN = "DK31";
"DDR5_DQ<48>":   PN = "CW36"  !CDS_PN = "CW36";
"DDR5_DQ<49>":   PN = "DC36"  !CDS_PN = "DC36";
"DDR5_DQ<50>":   PN = "CY33"  !CDS_PN = "CY33";
"DDR5_DQ<51>":   PN = "DB33"  !CDS_PN = "DB33";
"DDR5_DQ<52>":   PN = "CY37"  !CDS_PN = "CY37";
"DDR5_DQ<53>":   PN = "DB37"  !CDS_PN = "DB37";
"DDR5_DQ<54>":   PN = "CW34"  !CDS_PN = "CW34";
"DDR5_DQ<55>":   PN = "DC34"  !CDS_PN = "DC34";
"DDR5_DQ<56>":   PN = "CW30"  !CDS_PN = "CW30";
"DDR5_DQ<57>":   PN = "DC30"  !CDS_PN = "DC30";
"DDR5_DQ<58>":   PN = "CY27"  !CDS_PN = "CY27";
"DDR5_DQ<59>":   PN = "DB27"  !CDS_PN = "DB27";
"DDR5_DQ<60>":   PN = "CY31"  !CDS_PN = "CY31";
"DDR5_DQ<61>":   PN = "DB31"  !CDS_PN = "DB31";
"DDR5_DQ<62>":   PN = "CW28"  !CDS_PN = "CW28";
"DDR5_DQ<63>":   PN = "DC28"  !CDS_PN = "DC28";
"DDR5_DQS_DN<0>":   PN = "CP77"  !CDS_PN = "CP77";
"DDR5_DQS_DN<1>":   PN = "DD77"  !CDS_PN = "DD77";
"DDR5_DQS_DN<2>":   PN = "DL72"  !CDS_PN = "DL72";
"DDR5_DQS_DN<3>":   PN = "CV65"  !CDS_PN = "CV65";
"DDR5_DQS_DN<4>":   PN = "DG40"  !CDS_PN = "DG40";
"DDR5_DQS_DN<5>":   PN = "DL32"  !CDS_PN = "DL32";
"DDR5_DQS_DN<6>":   PN = "DD35"  !CDS_PN = "DD35";
"DDR5_DQS_DN<7>":   PN = "DD29"  !CDS_PN = "DD29";
"DDR5_DQS_DN<8>":   PN = "CN70"  !CDS_PN = "CN70";
"DDR5_DQS_DN<9>":   PN = "CT75"  !CDS_PN = "CT75";
"DDR5_DQS_DN<10>":   PN = "DF75"  !CDS_PN = "DF75";
"DDR5_DQS_DN<11>":   PN = "DJ70"  !CDS_PN = "DJ70";
"DDR5_DQS_DN<12>":   PN = "CP65"  !CDS_PN = "CP65";
"DDR5_DQS_DN<13>":   PN = "DE40"  !CDS_PN = "DE40";
"DDR5_DQS_DN<14>":   PN = "DG32"  !CDS_PN = "DG32";
"DDR5_DQS_DN<15>":   PN = "CY35"  !CDS_PN = "CY35";
"DDR5_DQS_DN<16>":   PN = "CY29"  !CDS_PN = "CY29";
"DDR5_DQS_DN<17>":   PN = "CJ70"  !CDS_PN = "CJ70";
"DDR5_DQS_DP<0>":   PN = "CR76"  !CDS_PN = "CR76";
"DDR5_DQS_DP<1>":   PN = "DE76"  !CDS_PN = "DE76";
"DDR5_DQS_DP<2>":   PN = "DK71"  !CDS_PN = "DK71";
"DDR5_DQS_DP<3>":   PN = "CT65"  !CDS_PN = "CT65";
"DDR5_DQS_DP<4>":   PN = "DJ40"  !CDS_PN = "DJ40";
"DDR5_DQS_DP<5>":   PN = "DJ32"  !CDS_PN = "DJ32";
"DDR5_DQS_DP<6>":   PN = "DB35"  !CDS_PN = "DB35";
"DDR5_DQS_DP<7>":   PN = "DB29"  !CDS_PN = "DB29";
"DDR5_DQS_DP<8>":   PN = "CL70"  !CDS_PN = "CL70";
"DDR5_DQS_DP<9>":   PN = "CU74"  !CDS_PN = "CU74";
"DDR5_DQS_DP<10>":   PN = "DG74"  !CDS_PN = "DG74";
"DDR5_DQS_DP<11>":   PN = "DH69"  !CDS_PN = "DH69";
"DDR5_DQS_DP<12>":   PN = "CM65"  !CDS_PN = "CM65";
"DDR5_DQS_DP<13>":   PN = "DC40"  !CDS_PN = "DC40";
"DDR5_DQS_DP<14>":   PN = "DE32"  !CDS_PN = "DE32";
"DDR5_DQS_DP<15>":   PN = "CV35"  !CDS_PN = "CV35";
"DDR5_DQS_DP<16>":   PN = "CV29"  !CDS_PN = "CV29";
"DDR5_DQS_DP<17>":   PN = "CG70"  !CDS_PN = "CG70";
"DDR5_ECC<0>":   PN = "CH71"  !CDS_PN = "CH71";
"DDR5_ECC<1>":   PN = "CM71"  !CDS_PN = "CM71";
"DDR5_ECC<2>":   PN = "CJ68"  !CDS_PN = "CJ68";
"DDR5_ECC<3>":   PN = "CL68"  !CDS_PN = "CL68";
"DDR5_ECC<4>":   PN = "CJ72"  !CDS_PN = "CJ72";
"DDR5_ECC<5>":   PN = "CL72"  !CDS_PN = "CL72";
"DDR5_ECC<6>":   PN = "CH69"  !CDS_PN = "CH69";
"DDR5_ECC<7>":   PN = "CM69"  !CDS_PN = "CM69";
"DDR5_MA<0>":   PN = "DF53"  !CDS_PN = "DF53";
"DDR5_MA<1>":   PN = "DC58"  !CDS_PN = "DC58";
"DDR5_MA<2>":   PN = "DD57"  !CDS_PN = "DD57";
"DDR5_MA<3>":   PN = "DG58"  !CDS_PN = "DG58";
"DDR5_MA<4>":   PN = "DJ58"  !CDS_PN = "DJ58";
"DDR5_MA<5>":   PN = "DF59"  !CDS_PN = "DF59";
"DDR5_MA<6>":   PN = "DK59"  !CDS_PN = "DK59";
"DDR5_MA<7>":   PN = "DC60"  !CDS_PN = "DC60";
"DDR5_MA<8>":   PN = "DD59"  !CDS_PN = "DD59";
"DDR5_MA<9>":   PN = "DA58"  !CDS_PN = "DA58";
"DDR5_MA<10>":   PN = "DD55"  !CDS_PN = "DD55";
"DDR5_MA<11>":   PN = "DA60"  !CDS_PN = "DA60";
"DDR5_MA<12>":   PN = "DG60"  !CDS_PN = "DG60";
"DDR5_MA<13>":   PN = "DD53"  !CDS_PN = "DD53";
"DDR5_MA<14>":   PN = "DJ50"  !CDS_PN = "DJ50";
"DDR5_MA<15>":   PN = "DC54"  !CDS_PN = "DC54";
"DDR5_MA<16>":   PN = "DG52"  !CDS_PN = "DG52";
"DDR5_MA<17>":   PN = "DE46"  !CDS_PN = "DE46";
"DDR5_ODT<0>":   PN = "DG50"  !CDS_PN = "DG50";
"DDR5_ODT<1>":   PN = "DG48"  !CDS_PN = "DG48";
"DDR5_ODT<2>":   PN = "DK49"  !CDS_PN = "DK49";
"DDR5_ODT<3>":   PN = "DF47"  !CDS_PN = "DF47";
"DDR5_PAR":   PN = "DK53"  !CDS_PN = "DK53";
DRAWING = "@baseboard_fab2_lib.baseboard_fab2(sch_1):page29";
BODY = "SKX_EXT_B","I61": #LOCATION = "U5D1" !CDS_LOCATION = "U5D1" #SEC = "9" !CDS_SEC = "9";
"CD_HFI0_I2CCLK":   PN = "BN22"  !CDS_PN = "BN22";
"CD_HFI0_I2CDAT":   PN = "BP23"  !CDS_PN = "BP23";
"CD_HFI0_INT_N":   PN = "BP19"  !CDS_PN = "BP19";
"CD_HFI0_LED_N":   PN = "BK21"  !CDS_PN = "BK21";
"CD_HFI0_MODPRST_N":   PN = "BR20"  !CDS_PN = "BR20";
"CD_HFI0_RESET_N":   PN = "BN24"  !CDS_PN = "BN24";
"CD_HFI1_I2CCLK":   PN = "BJ22"  !CDS_PN = "BJ22";
"CD_HFI1_I2CDAT":   PN = "BH23"  !CDS_PN = "BH23";
"CD_HFI1_INT_N":   PN = "BM21"  !CDS_PN = "BM21";
"CD_HFI1_LED_N":   PN = "BM23"  !CDS_PN = "BM23";
"CD_HFI1_MODPRST_N":   PN = "BT19"  !CDS_PN = "BT19";
"CD_HFI1_RESET_N":   PN = "BK23"  !CDS_PN = "BK23";
"CD_HFI_REFCLK_DN":   PN = "BE16"  !CDS_PN = "BE16";
"CD_HFI_REFCLK_DP":   PN = "BG16"  !CDS_PN = "BG16";
"CD_PE_REFCLK_DN":   PN = "BU24"  !CDS_PN = "BU24";
"CD_PE_REFCLK_DP":   PN = "BW24"  !CDS_PN = "BW24";
"CD_POR_N":   PN = "CF25"  !CDS_PN = "CF25";
"CD_TCLK":   PN = "CB23"  !CDS_PN = "CB23";
"CD_TDI":   PN = "BY21"  !CDS_PN = "BY21";
"CD_TDO":   PN = "CC22"  !CDS_PN = "CC22";
"CD_TMS":   PN = "CE24"  !CDS_PN = "CE24";
"CD_TRST_N":   PN = "CD23"  !CDS_PN = "CD23";
"DMI_RX_DN<0>":   PN = "CK9"  !CDS_PN = "CK9";
"DMI_RX_DN<1>":   PN = "CM11"  !CDS_PN = "CM11";
"DMI_RX_DN<2>":   PN = "CR12"  !CDS_PN = "CR12";
"DMI_RX_DN<3>":   PN = "CT11"  !CDS_PN = "CT11";
"DMI_RX_DP<0>":   PN = "CL10"  !CDS_PN = "CL10";
"DMI_RX_DP<1>":   PN = "CN10"  !CDS_PN = "CN10";
"DMI_RX_DP<2>":   PN = "CP11"  !CDS_PN = "CP11";
"DMI_RX_DP<3>":   PN = "CV11"  !CDS_PN = "CV11";
"DMI_TX_DN<0>":   PN = "CG4"  !CDS_PN = "CG4";
"DMI_TX_DN<1>":   PN = "CJ4"  !CDS_PN = "CJ4";
"DMI_TX_DN<2>":   PN = "CN4"  !CDS_PN = "CN4";
"DMI_TX_DN<3>":   PN = "CP5"  !CDS_PN = "CP5";
"DMI_TX_DP<0>":   PN = "CH5"  !CDS_PN = "CH5";
"DMI_TX_DP<1>":   PN = "CL4"  !CDS_PN = "CL4";
"DMI_TX_DP<2>":   PN = "CM3"  !CDS_PN = "CM3";
"DMI_TX_DP<3>":   PN = "CR4"  !CDS_PN = "CR4";
"RSVD<172>":   PN = "BA76"  !CDS_PN = "BA76";
"RSVD<173>":   PN = "BA66"  !CDS_PN = "BA66";
"RSVD<174>":   PN = "BA64"  !CDS_PN = "BA64";
"RSVD<175>":   PN = "BA22"  !CDS_PN = "BA22";
"RSVD<176>":   PN = "BA18"  !CDS_PN = "BA18";
"RSVD<177>":   PN = "BA16"  !CDS_PN = "BA16";
"RSVD<178>":   PN = "BA14"  !CDS_PN = "BA14";
"RSVD<179>":   PN = "AY77"  !CDS_PN = "AY77";
"RSVD<180>":   PN = "AY75"  !CDS_PN = "AY75";
"RSVD<181>":   PN = "AY67"  !CDS_PN = "AY67";
"RSVD<182>":   PN = "AY65"  !CDS_PN = "AY65";
"RSVD<183>":   PN = "AW76"  !CDS_PN = "AW76";
"RSVD<184>":   PN = "AW64"  !CDS_PN = "AW64";
"RSVD<186>":   PN = "AV77"  !CDS_PN = "AV77";
"RSVD<187>":   PN = "AT25"  !CDS_PN = "AT25";
"RSVD<188>":   PN = "AT23"  !CDS_PN = "AT23";
"RSVD<189>":   PN = "AT13"  !CDS_PN = "AT13";
"RSVD<190>":   PN = "AR62"  !CDS_PN = "AR62";
"RSVD<191>":   PN = "AR26"  !CDS_PN = "AR26";
"RSVD<192>":   PN = "AR22"  !CDS_PN = "AR22";
"RSVD<193>":   PN = "AR20"  !CDS_PN = "AR20";
DRAWING = "@baseboard_fab2_lib.baseboard_fab2(sch_1):page30";
BODY = "SKX_EXT_B","I84": #LOCATION = "U5D1" !CDS_LOCATION = "U5D1" #SEC = "10" !CDS_SEC = "10";
"PE1_RX_DN<0>":   PN = "CW8"  !CDS_PN = "CW8";
"PE1_RX_DN<1>":   PN = "DA8"  !CDS_PN = "DA8";
"PE1_RX_DN<2>":   PN = "DC8"  !CDS_PN = "DC8";
"PE1_RX_DN<3>":   PN = "DC10"  !CDS_PN = "DC10";
"PE1_RX_DN<4>":   PN = "DE10"  !CDS_PN = "DE10";
"PE1_RX_DN<5>":   PN = "DH9"  !CDS_PN = "DH9";
"PE1_RX_DN<6>":   PN = "DK9"  !CDS_PN = "DK9";
"PE1_RX_DN<7>":   PN = "DM9"  !CDS_PN = "DM9";
"PE1_RX_DN<8>":   PN = "DM11"  !CDS_PN = "DM11";
"PE1_RX_DN<9>":   PN = "DP11"  !CDS_PN = "DP11";
"PE1_RX_DN<10>":   PN = "DT11"  !CDS_PN = "DT11";
"PE1_RX_DN<11>":   PN = "DT13"  !CDS_PN = "DT13";
"PE1_RX_DN<12>":   PN = "DV13"  !CDS_PN = "DV13";
"PE1_RX_DN<13>":   PN = "DW14"  !CDS_PN = "DW14";
"PE1_RX_DN<14>":   PN = "DY15"  !CDS_PN = "DY15";
"PE1_RX_DN<15>":   PN = "DU16"  !CDS_PN = "DU16";
"PE1_RX_DP<0>":   PN = "CU8"  !CDS_PN = "CU8";
"PE1_RX_DP<1>":   PN = "CY7"  !CDS_PN = "CY7";
"PE1_RX_DP<2>":   PN = "DB9"  !CDS_PN = "DB9";
"PE1_RX_DP<3>":   PN = "DA10"  !CDS_PN = "DA10";
"PE1_RX_DP<4>":   PN = "DD9"  !CDS_PN = "DD9";
"PE1_RX_DP<5>":   PN = "DF9"  !CDS_PN = "DF9";
"PE1_RX_DP<6>":   PN = "DJ8"  !CDS_PN = "DJ8";
"PE1_RX_DP<7>":   PN = "DL10"  !CDS_PN = "DL10";
"PE1_RX_DP<8>":   PN = "DK11"  !CDS_PN = "DK11";
"PE1_RX_DP<9>":   PN = "DN10"  !CDS_PN = "DN10";
"PE1_RX_DP<10>":   PN = "DR12"  !CDS_PN = "DR12";
"PE1_RX_DP<11>":   PN = "DP13"  !CDS_PN = "DP13";
"PE1_RX_DP<12>":   PN = "DU12"  !CDS_PN = "DU12";
"PE1_RX_DP<13>":   PN = "DY13"  !CDS_PN = "DY13";
"PE1_RX_DP<14>":   PN = "DV15"  !CDS_PN = "DV15";
"PE1_RX_DP<15>":   PN = "DT15"  !CDS_PN = "DT15";
"PE1_TX_DN<0>":   PN = "DA2"  !CDS_PN = "DA2";
"PE1_TX_DN<1>":   PN = "DC2"  !CDS_PN = "DC2";
"PE1_TX_DN<2>":   PN = "DE2"  !CDS_PN = "DE2";
"PE1_TX_DN<3>":   PN = "DE4"  !CDS_PN = "DE4";
"PE1_TX_DN<4>":   PN = "DG4"  !CDS_PN = "DG4";
"PE1_TX_DN<5>":   PN = "DK3"  !CDS_PN = "DK3";
"PE1_TX_DN<6>":   PN = "DM3"  !CDS_PN = "DM3";
"PE1_TX_DN<7>":   PN = "DN4"  !CDS_PN = "DN4";
"PE1_TX_DN<8>":   PN = "DT5"  !CDS_PN = "DT5";
"PE1_TX_DN<9>":   PN = "DV3"  !CDS_PN = "DV3";
"PE1_TX_DN<10>":   PN = "DW4"  !CDS_PN = "DW4";
"PE1_TX_DN<11>":   PN = "DU6"  !CDS_PN = "DU6";
"PE1_TX_DN<12>":   PN = "DV7"  !CDS_PN = "DV7";
"PE1_TX_DN<13>":   PN = "DY7"  !CDS_PN = "DY7";
"PE1_TX_DN<14>":   PN = "EA8"  !CDS_PN = "EA8";
"PE1_TX_DN<15>":   PN = "ED9"  !CDS_PN = "ED9";
"PE1_TX_DP<0>":   PN = "CW2"  !CDS_PN = "CW2";
"PE1_TX_DP<1>":   PN = "DB1"  !CDS_PN = "DB1";
"PE1_TX_DP<2>":   PN = "DD3"  !CDS_PN = "DD3";
"PE1_TX_DP<3>":   PN = "DC4"  !CDS_PN = "DC4";
"PE1_TX_DP<4>":   PN = "DF3"  !CDS_PN = "DF3";
"PE1_TX_DP<5>":   PN = "DH3"  !CDS_PN = "DH3";
"PE1_TX_DP<6>":   PN = "DL2"  !CDS_PN = "DL2";
"PE1_TX_DP<7>":   PN = "DP3"  !CDS_PN = "DP3";
"PE1_TX_DP<8>":   PN = "DR4"  !CDS_PN = "DR4";
"PE1_TX_DP<9>":   PN = "DU2"  !CDS_PN = "DU2";
"PE1_TX_DP<10>":   PN = "DU4"  !CDS_PN = "DU4";
"PE1_TX_DP<11>":   PN = "DV5"  !CDS_PN = "DV5";
"PE1_TX_DP<12>":   PN = "DT7"  !CDS_PN = "DT7";
"PE1_TX_DP<13>":   PN = "DW6"  !CDS_PN = "DW6";
"PE1_TX_DP<14>":   PN = "EB7"  !CDS_PN = "EB7";
"PE1_TX_DP<15>":   PN = "EC8"  !CDS_PN = "EC8";
DRAWING = "@baseboard_fab2_lib.baseboard_fab2(sch_1):page31";
BODY = "SKX_EXT_B","I106": #LOCATION = "U5D1" !CDS_LOCATION = "U5D1" #SEC = "11" !CDS_SEC = "11";
"PE2_RX_DN<0>":   PN = "CT9"  !CDS_PN = "CT9";
"PE2_RX_DN<1>":   PN = "CP9"  !CDS_PN = "CP9";
"PE2_RX_DN<2>":   PN = "CP7"  !CDS_PN = "CP7";
"PE2_RX_DN<3>":   PN = "CM7"  !CDS_PN = "CM7";
"PE2_RX_DN<4>":   PN = "CK7"  !CDS_PN = "CK7";
"PE2_RX_DN<5>":   PN = "CG8"  !CDS_PN = "CG8";
"PE2_RX_DN<6>":   PN = "CE6"  !CDS_PN = "CE6";
"PE2_RX_DN<7>":   PN = "CE8"  !CDS_PN = "CE8";
"PE2_RX_DN<8>":   PN = "BY9"  !CDS_PN = "BY9";
"PE2_RX_DN<9>":   PN = "BY7"  !CDS_PN = "BY7";
"PE2_RX_DN<10>":   PN = "BV7"  !CDS_PN = "BV7";
"PE2_RX_DN<11>":   PN = "BT7"  !CDS_PN = "BT7";
"PE2_RX_DN<12>":   PN = "BR8"  !CDS_PN = "BR8";
"PE2_RX_DN<13>":   PN = "BN8"  !CDS_PN = "BN8";
"PE2_RX_DN<14>":   PN = "BL8"  !CDS_PN = "BL8";
"PE2_RX_DN<15>":   PN = "BK9"  !CDS_PN = "BK9";
"PE2_RX_DP<0>":   PN = "CR8"  !CDS_PN = "CR8";
"PE2_RX_DP<1>":   PN = "CM9"  !CDS_PN = "CM9";
"PE2_RX_DP<2>":   PN = "CN8"  !CDS_PN = "CN8";
"PE2_RX_DP<3>":   PN = "CL6"  !CDS_PN = "CL6";
"PE2_RX_DP<4>":   PN = "CH7"  !CDS_PN = "CH7";
"PE2_RX_DP<5>":   PN = "CF7"  !CDS_PN = "CF7";
"PE2_RX_DP<6>":   PN = "CD7"  !CDS_PN = "CD7";
"PE2_RX_DP<7>":   PN = "CC8"  !CDS_PN = "CC8";
"PE2_RX_DP<8>":   PN = "BV9"  !CDS_PN = "BV9";
"PE2_RX_DP<9>":   PN = "BW8"  !CDS_PN = "BW8";
"PE2_RX_DP<10>":   PN = "BU6"  !CDS_PN = "BU6";
"PE2_RX_DP<11>":   PN = "BP7"  !CDS_PN = "BP7";
"PE2_RX_DP<12>":   PN = "BP9"  !CDS_PN = "BP9";
"PE2_RX_DP<13>":   PN = "BM7"  !CDS_PN = "BM7";
"PE2_RX_DP<14>":   PN = "BJ8"  !CDS_PN = "BJ8";
"PE2_RX_DP<15>":   PN = "BJ10"  !CDS_PN = "BJ10";
"PE2_TX_DN<0>":   PN = "CY3"  !CDS_PN = "CY3";
"PE2_TX_DN<1>":   PN = "CV3"  !CDS_PN = "CV3";
"PE2_TX_DN<2>":   PN = "CT1"  !CDS_PN = "CT1";
"PE2_TX_DN<3>":   PN = "CT3"  !CDS_PN = "CT3";
"PE2_TX_DN<4>":   PN = "CM1"  !CDS_PN = "CM1";
"PE2_TX_DN<5>":   PN = "CL2"  !CDS_PN = "CL2";
"PE2_TX_DN<6>":   PN = "CG2"  !CDS_PN = "CG2";
"PE2_TX_DN<7>":   PN = "CF3"  !CDS_PN = "CF3";
"PE2_TX_DN<8>":   PN = "CC2"  !CDS_PN = "CC2";
"PE2_TX_DN<9>":   PN = "CB3"  !CDS_PN = "CB3";
"PE2_TX_DN<10>":   PN = "CA4"  !CDS_PN = "CA4";
"PE2_TX_DN<11>":   PN = "BW4"  !CDS_PN = "BW4";
"PE2_TX_DN<12>":   PN = "BU4"  !CDS_PN = "BU4";
"PE2_TX_DN<13>":   PN = "BP5"  !CDS_PN = "BP5";
"PE2_TX_DN<14>":   PN = "BL4"  !CDS_PN = "BL4";
"PE2_TX_DN<15>":   PN = "BM5"  !CDS_PN = "BM5";
"PE2_TX_DP<0>":   PN = "CW4"  !CDS_PN = "CW4";
"PE2_TX_DP<1>":   PN = "CU2"  !CDS_PN = "CU2";
"PE2_TX_DP<2>":   PN = "CR2"  !CDS_PN = "CR2";
"PE2_TX_DP<3>":   PN = "CP3"  !CDS_PN = "CP3";
"PE2_TX_DP<4>":   PN = "CK1"  !CDS_PN = "CK1";
"PE2_TX_DP<5>":   PN = "CK3"  !CDS_PN = "CK3";
"PE2_TX_DP<6>":   PN = "CE2"  !CDS_PN = "CE2";
"PE2_TX_DP<7>":   PN = "CE4"  !CDS_PN = "CE4";
"PE2_TX_DP<8>":   PN = "CD3"  !CDS_PN = "CD3";
"PE2_TX_DP<9>":   PN = "BY3"  !CDS_PN = "BY3";
"PE2_TX_DP<10>":   PN = "BY5"  !CDS_PN = "BY5";
"PE2_TX_DP<11>":   PN = "BV3"  !CDS_PN = "BV3";
"PE2_TX_DP<12>":   PN = "BR4"  !CDS_PN = "BR4";
"PE2_TX_DP<13>":   PN = "BN4"  !CDS_PN = "BN4";
"PE2_TX_DP<14>":   PN = "BM3"  !CDS_PN = "BM3";
"PE2_TX_DP<15>":   PN = "BK5"  !CDS_PN = "BK5";
DRAWING = "@baseboard_fab2_lib.baseboard_fab2(sch_1):page32";
BODY = "SKX_EXT_B","I89": #LOCATION = "U5D1" !CDS_LOCATION = "U5D1" #SEC = "12" !CDS_SEC = "12";
"PE3_RX_DN<0>":   PN = "EA18"  !CDS_PN = "EA18";
"PE3_RX_DN<1>":   PN = "DW18"  !CDS_PN = "DW18";
"PE3_RX_DN<2>":   PN = "DW16"  !CDS_PN = "DW16";
"PE3_RX_DN<3>":   PN = "DT19"  !CDS_PN = "DT19";
"PE3_RX_DN<4>":   PN = "DR16"  !CDS_PN = "DR16";
"PE3_RX_DN<5>":   PN = "DR14"  !CDS_PN = "DR14";
"PE3_RX_DN<6>":   PN = "DN14"  !CDS_PN = "DN14";
"PE3_RX_DN<7>":   PN = "DL14"  !CDS_PN = "DL14";
"PE3_RX_DN<8>":   PN = "DL12"  !CDS_PN = "DL12";
"PE3_RX_DN<9>":   PN = "DJ12"  !CDS_PN = "DJ12";
"PE3_RX_DN<10>":   PN = "DG12"  !CDS_PN = "DG12";
"PE3_RX_DN<11>":   PN = "DG10"  !CDS_PN = "DG10";
"PE3_RX_DN<12>":   PN = "DD13"  !CDS_PN = "DD13";
"PE3_RX_DN<13>":   PN = "DB11"  !CDS_PN = "DB11";
"PE3_RX_DN<14>":   PN = "CY11"  !CDS_PN = "CY11";
"PE3_RX_DN<15>":   PN = "CV9"  !CDS_PN = "CV9";
"PE3_RX_DP<0>":   PN = "DY17"  !CDS_PN = "DY17";
"PE3_RX_DP<1>":   PN = "DU18"  !CDS_PN = "DU18";
"PE3_RX_DP<2>":   PN = "DV17"  !CDS_PN = "DV17";
"PE3_RX_DP<3>":   PN = "DR18"  !CDS_PN = "DR18";
"PE3_RX_DP<4>":   PN = "DN16"  !CDS_PN = "DN16";
"PE3_RX_DP<5>":   PN = "DP15"  !CDS_PN = "DP15";
"PE3_RX_DP<6>":   PN = "DM13"  !CDS_PN = "DM13";
"PE3_RX_DP<7>":   PN = "DJ14"  !CDS_PN = "DJ14";
"PE3_RX_DP<8>":   PN = "DK13"  !CDS_PN = "DK13";
"PE3_RX_DP<9>":   PN = "DH11"  !CDS_PN = "DH11";
"PE3_RX_DP<10>":   PN = "DE12"  !CDS_PN = "DE12";
"PE3_RX_DP<11>":   PN = "DF11"  !CDS_PN = "DF11";
"PE3_RX_DP<12>":   PN = "DC12"  !CDS_PN = "DC12";
"PE3_RX_DP<13>":   PN = "DA12"  !CDS_PN = "DA12";
"PE3_RX_DP<14>":   PN = "CW10"  !CDS_PN = "CW10";
"PE3_RX_DP<15>":   PN = "CU10"  !CDS_PN = "CU10";
"PE3_TX_DN<0>":   PN = "EE14"  !CDS_PN = "EE14";
"PE3_TX_DN<1>":   PN = "EE12"  !CDS_PN = "EE12";
"PE3_TX_DN<2>":   PN = "EC12"  !CDS_PN = "EC12";
"PE3_TX_DN<3>":   PN = "DY11"  !CDS_PN = "DY11";
"PE3_TX_DN<4>":   PN = "EB9"  !CDS_PN = "EB9";
"PE3_TX_DN<5>":   PN = "DW10"  !CDS_PN = "DW10";
"PE3_TX_DN<6>":   PN = "DU8"  !CDS_PN = "DU8";
"PE3_TX_DN<7>":   PN = "DR8"  !CDS_PN = "DR8";
"PE3_TX_DN<8>":   PN = "DM7"  !CDS_PN = "DM7";
"PE3_TX_DN<9>":   PN = "DP5"  !CDS_PN = "DP5";
"PE3_TX_DN<10>":   PN = "DL6"  !CDS_PN = "DL6";
"PE3_TX_DN<11>":   PN = "DJ4"  !CDS_PN = "DJ4";
"PE3_TX_DN<12>":   PN = "DJ6"  !CDS_PN = "DJ6";
"PE3_TX_DN<13>":   PN = "DD5"  !CDS_PN = "DD5";
"PE3_TX_DN<14>":   PN = "DB5"  !CDS_PN = "DB5";
"PE3_TX_DN<15>":   PN = "CY5"  !CDS_PN = "CY5";
"PE3_TX_DP<0>":   PN = "EC14"  !CDS_PN = "EC14";
"PE3_TX_DP<1>":   PN = "ED13"  !CDS_PN = "ED13";
"PE3_TX_DP<2>":   PN = "EB11"  !CDS_PN = "EB11";
"PE3_TX_DP<3>":   PN = "EA10"  !CDS_PN = "EA10";
"PE3_TX_DP<4>":   PN = "DY9"  !CDS_PN = "DY9";
"PE3_TX_DP<5>":   PN = "DV9"  !CDS_PN = "DV9";
"PE3_TX_DP<6>":   PN = "DT9"  !CDS_PN = "DT9";
"PE3_TX_DP<7>":   PN = "DP7"  !CDS_PN = "DP7";
"PE3_TX_DP<8>":   PN = "DN6"  !CDS_PN = "DN6";
"PE3_TX_DP<9>":   PN = "DM5"  !CDS_PN = "DM5";
"PE3_TX_DP<10>":   PN = "DK5"  !CDS_PN = "DK5";
"PE3_TX_DP<11>":   PN = "DH5"  !CDS_PN = "DH5";
"PE3_TX_DP<12>":   PN = "DG6"  !CDS_PN = "DG6";
"PE3_TX_DP<13>":   PN = "DC6"  !CDS_PN = "DC6";
"PE3_TX_DP<14>":   PN = "DA4"  !CDS_PN = "DA4";
"PE3_TX_DP<15>":   PN = "CV5"  !CDS_PN = "CV5";
DRAWING = "@baseboard_fab2_lib.baseboard_fab2(sch_1):page33";
BODY = "SKX_EXT_B","I86": #LOCATION = "U5D1" !CDS_LOCATION = "U5D1" #SEC = "13" !CDS_SEC = "13";
"UPI0_RX_DN<0>":   PN = "AC10"  !CDS_PN = "AC10";
"UPI0_RX_DN<1>":   PN = "AA8"  !CDS_PN = "AA8";
"UPI0_RX_DN<2>":   PN = "AB7"  !CDS_PN = "AB7";
"UPI0_RX_DN<3>":   PN = "AD5"  !CDS_PN = "AD5";
"UPI0_RX_DN<4>":   PN = "AE6"  !CDS_PN = "AE6";
"UPI0_RX_DN<5>":   PN = "AG8"  !CDS_PN = "AG8";
"UPI0_RX_DN<6>":   PN = "AJ6"  !CDS_PN = "AJ6";
"UPI0_RX_DN<7>":   PN = "AL6"  !CDS_PN = "AL6";
"UPI0_RX_DN<8>":   PN = "AK7"  !CDS_PN = "AK7";
"UPI0_RX_DN<9>":   PN = "AM9"  !CDS_PN = "AM9";
"UPI0_RX_DN<10>":   PN = "AP7"  !CDS_PN = "AP7";
"UPI0_RX_DN<11>":   PN = "AR8"  !CDS_PN = "AR8";
"UPI0_RX_DN<12>":   PN = "AU10"  !CDS_PN = "AU10";
"UPI0_RX_DN<13>":   PN = "BA8"  !CDS_PN = "BA8";
"UPI0_RX_DN<14>":   PN = "BC6"  !CDS_PN = "BC6";
"UPI0_RX_DN<15>":   PN = "BD7"  !CDS_PN = "BD7";
"UPI0_RX_DN<16>":   PN = "AW8"  !CDS_PN = "AW8";
"UPI0_RX_DN<17>":   PN = "AY9"  !CDS_PN = "AY9";
"UPI0_RX_DN<18>":   PN = "BD9"  !CDS_PN = "BD9";
"UPI0_RX_DN<19>":   PN = "BB11"  !CDS_PN = "BB11";
"UPI0_RX_DP<0>":   PN = "AB9"  !CDS_PN = "AB9";
"UPI0_RX_DP<1>":   PN = "AC8"  !CDS_PN = "AC8";
"UPI0_RX_DP<2>":   PN = "AA6"  !CDS_PN = "AA6";
"UPI0_RX_DP<3>":   PN = "AC6"  !CDS_PN = "AC6";
"UPI0_RX_DP<4>":   PN = "AG6"  !CDS_PN = "AG6";
"UPI0_RX_DP<5>":   PN = "AF7"  !CDS_PN = "AF7";
"UPI0_RX_DP<6>":   PN = "AH7"  !CDS_PN = "AH7";
"UPI0_RX_DP<7>":   PN = "AK5"  !CDS_PN = "AK5";
"UPI0_RX_DP<8>":   PN = "AM7"  !CDS_PN = "AM7";
"UPI0_RX_DP<9>":   PN = "AL8"  !CDS_PN = "AL8";
"UPI0_RX_DP<10>":   PN = "AN8"  !CDS_PN = "AN8";
"UPI0_RX_DP<11>":   PN = "AU8"  !CDS_PN = "AU8";
"UPI0_RX_DP<12>":   PN = "AT9"  !CDS_PN = "AT9";
"UPI0_RX_DP<13>":   PN = "AY7"  !CDS_PN = "AY7";
"UPI0_RX_DP<14>":   PN = "BB7"  !CDS_PN = "BB7";
"UPI0_RX_DP<15>":   PN = "BF7"  !CDS_PN = "BF7";
"UPI0_RX_DP<16>":   PN = "AV9"  !CDS_PN = "AV9";
"UPI0_RX_DP<17>":   PN = "BB9"  !CDS_PN = "BB9";
"UPI0_RX_DP<18>":   PN = "BC10"  !CDS_PN = "BC10";
"UPI0_RX_DP<19>":   PN = "BA10"  !CDS_PN = "BA10";
"UPI0_TX_DN<0>":   PN = "N2"  !CDS_PN = "N2";
"UPI0_TX_DN<1>":   PN = "P1"  !CDS_PN = "P1";
"UPI0_TX_DN<2>":   PN = "V3"  !CDS_PN = "V3";
"UPI0_TX_DN<3>":   PN = "Y1"  !CDS_PN = "Y1";
"UPI0_TX_DN<4>":   PN = "AB3"  !CDS_PN = "AB3";
"UPI0_TX_DN<5>":   PN = "AC2"  !CDS_PN = "AC2";
"UPI0_TX_DN<6>":   PN = "AG4"  !CDS_PN = "AG4";
"UPI0_TX_DN<7>":   PN = "AE2"  !CDS_PN = "AE2";
"UPI0_TX_DN<8>":   PN = "AH3"  !CDS_PN = "AH3";
"UPI0_TX_DN<9>":   PN = "AL2"  !CDS_PN = "AL2";
"UPI0_TX_DN<10>":   PN = "AM3"  !CDS_PN = "AM3";
"UPI0_TX_DN<11>":   PN = "AN4"  !CDS_PN = "AN4";
"UPI0_TX_DN<12>":   PN = "AT1"  !CDS_PN = "AT1";
"UPI0_TX_DN<13>":   PN = "AT3"  !CDS_PN = "AT3";
"UPI0_TX_DN<14>":   PN = "AU4"  !CDS_PN = "AU4";
"UPI0_TX_DN<15>":   PN = "AV5"  !CDS_PN = "AV5";
"UPI0_TX_DN<16>":   PN = "BA4"  !CDS_PN = "BA4";
"UPI0_TX_DN<17>":   PN = "BB3"  !CDS_PN = "BB3";
"UPI0_TX_DN<18>":   PN = "BF3"  !CDS_PN = "BF3";
"UPI0_TX_DN<19>":   PN = "BG4"  !CDS_PN = "BG4";
"UPI0_TX_DP<0>":   PN = "M1"  !CDS_PN = "M1";
"UPI0_TX_DP<1>":   PN = "T1"  !CDS_PN = "T1";
"UPI0_TX_DP<2>":   PN = "Y3"  !CDS_PN = "Y3";
"UPI0_TX_DP<3>":   PN = "W2"  !CDS_PN = "W2";
"UPI0_TX_DP<4>":   PN = "AA2"  !CDS_PN = "AA2";
"UPI0_TX_DP<5>":   PN = "AD1"  !CDS_PN = "AD1";
"UPI0_TX_DP<6>":   PN = "AF3"  !CDS_PN = "AF3";
"UPI0_TX_DP<7>":   PN = "AG2"  !CDS_PN = "AG2";
"UPI0_TX_DP<8>":   PN = "AJ2"  !CDS_PN = "AJ2";
"UPI0_TX_DP<9>":   PN = "AK1"  !CDS_PN = "AK1";
"UPI0_TX_DP<10>":   PN = "AK3"  !CDS_PN = "AK3";
"UPI0_TX_DP<11>":   PN = "AP3"  !CDS_PN = "AP3";
"UPI0_TX_DP<12>":   PN = "AP1"  !CDS_PN = "AP1";
"UPI0_TX_DP<13>":   PN = "AR2"  !CDS_PN = "AR2";
"UPI0_TX_DP<14>":   PN = "AR4"  !CDS_PN = "AR4";
"UPI0_TX_DP<15>":   PN = "AW4"  !CDS_PN = "AW4";
"UPI0_TX_DP<16>":   PN = "AY3"  !CDS_PN = "AY3";
"UPI0_TX_DP<17>":   PN = "BC2"  !CDS_PN = "BC2";
"UPI0_TX_DP<18>":   PN = "BD3"  !CDS_PN = "BD3";
"UPI0_TX_DP<19>":   PN = "BH3"  !CDS_PN = "BH3";
DRAWING = "@baseboard_fab2_lib.baseboard_fab2(sch_1):page34";
BODY = "SKX_EXT_B","I86": #LOCATION = "U5D1" !CDS_LOCATION = "U5D1" #SEC = "14" !CDS_SEC = "14";
"UPI1_RX_DN<0>":   PN = "T5"  !CDS_PN = "T5";
"UPI1_RX_DN<1>":   PN = "P7"  !CDS_PN = "P7";
"UPI1_RX_DN<2>":   PN = "V7"  !CDS_PN = "V7";
"UPI1_RX_DN<3>":   PN = "T9"  !CDS_PN = "T9";
"UPI1_RX_DN<4>":   PN = "P9"  !CDS_PN = "P9";
"UPI1_RX_DN<5>":   PN = "R10"  !CDS_PN = "R10";
"UPI1_RX_DN<6>":   PN = "U12"  !CDS_PN = "U12";
"UPI1_RX_DN<7>":   PN = "L12"  !CDS_PN = "L12";
"UPI1_RX_DN<8>":   PN = "N14"  !CDS_PN = "N14";
"UPI1_RX_DN<9>":   PN = "R12"  !CDS_PN = "R12";
"UPI1_RX_DN<10>":   PN = "R16"  !CDS_PN = "R16";
"UPI1_RX_DN<11>":   PN = "P17"  !CDS_PN = "P17";
"UPI1_RX_DN<12>":   PN = "U16"  !CDS_PN = "U16";
"UPI1_RX_DN<13>":   PN = "W18"  !CDS_PN = "W18";
"UPI1_RX_DN<14>":   PN = "R20"  !CDS_PN = "R20";
"UPI1_RX_DN<15>":   PN = "U18"  !CDS_PN = "U18";
"UPI1_RX_DN<16>":   PN = "P21"  !CDS_PN = "P21";
"UPI1_RX_DN<17>":   PN = "V19"  !CDS_PN = "V19";
"UPI1_RX_DN<18>":   PN = "Y21"  !CDS_PN = "Y21";
"UPI1_RX_DN<19>":   PN = "AB19"  !CDS_PN = "AB19";
"UPI1_RX_DP<0>":   PN = "R6"  !CDS_PN = "R6";
"UPI1_RX_DP<1>":   PN = "T7"  !CDS_PN = "T7";
"UPI1_RX_DP<2>":   PN = "U8"  !CDS_PN = "U8";
"UPI1_RX_DP<3>":   PN = "R8"  !CDS_PN = "R8";
"UPI1_RX_DP<4>":   PN = "N10"  !CDS_PN = "N10";
"UPI1_RX_DP<5>":   PN = "U10"  !CDS_PN = "U10";
"UPI1_RX_DP<6>":   PN = "T11"  !CDS_PN = "T11";
"UPI1_RX_DP<7>":   PN = "N12"  !CDS_PN = "N12";
"UPI1_RX_DP<8>":   PN = "M13"  !CDS_PN = "M13";
"UPI1_RX_DP<9>":   PN = "P13"  !CDS_PN = "P13";
"UPI1_RX_DP<10>":   PN = "T15"  !CDS_PN = "T15";
"UPI1_RX_DP<11>":   PN = "N16"  !CDS_PN = "N16";
"UPI1_RX_DP<12>":   PN = "W16"  !CDS_PN = "W16";
"UPI1_RX_DP<13>":   PN = "V17"  !CDS_PN = "V17";
"UPI1_RX_DP<14>":   PN = "P19"  !CDS_PN = "P19";
"UPI1_RX_DP<15>":   PN = "T19"  !CDS_PN = "T19";
"UPI1_RX_DP<16>":   PN = "T21"  !CDS_PN = "T21";
"UPI1_RX_DP<17>":   PN = "Y19"  !CDS_PN = "Y19";
"UPI1_RX_DP<18>":   PN = "W20"  !CDS_PN = "W20";
"UPI1_RX_DP<19>":   PN = "AA20"  !CDS_PN = "AA20";
"UPI1_TX_DN<0>":   PN = "M3"  !CDS_PN = "M3";
"UPI1_TX_DN<1>":   PN = "L4"  !CDS_PN = "L4";
"UPI1_TX_DN<2>":   PN = "K5"  !CDS_PN = "K5";
"UPI1_TX_DN<3>":   PN = "J6"  !CDS_PN = "J6";
"UPI1_TX_DN<4>":   PN = "G6"  !CDS_PN = "G6";
"UPI1_TX_DN<5>":   PN = "H7"  !CDS_PN = "H7";
"UPI1_TX_DN<6>":   PN = "K9"  !CDS_PN = "K9";
"UPI1_TX_DN<7>":   PN = "D9"  !CDS_PN = "D9";
"UPI1_TX_DN<8>":   PN = "F11"  !CDS_PN = "F11";
"UPI1_TX_DN<9>":   PN = "G10"  !CDS_PN = "G10";
"UPI1_TX_DN<10>":   PN = "E12"  !CDS_PN = "E12";
"UPI1_TX_DN<11>":   PN = "G14"  !CDS_PN = "G14";
"UPI1_TX_DN<12>":   PN = "D15"  !CDS_PN = "D15";
"UPI1_TX_DN<13>":   PN = "F15"  !CDS_PN = "F15";
"UPI1_TX_DN<14>":   PN = "H17"  !CDS_PN = "H17";
"UPI1_TX_DN<15>":   PN = "K19"  !CDS_PN = "K19";
"UPI1_TX_DN<16>":   PN = "G18"  !CDS_PN = "G18";
"UPI1_TX_DN<17>":   PN = "J20"  !CDS_PN = "J20";
"UPI1_TX_DN<18>":   PN = "F21"  !CDS_PN = "F21";
"UPI1_TX_DN<19>":   PN = "H21"  !CDS_PN = "H21";
"UPI1_TX_DP<0>":   PN = "P3"  !CDS_PN = "P3";
"UPI1_TX_DP<1>":   PN = "K3"  !CDS_PN = "K3";
"UPI1_TX_DP<2>":   PN = "M5"  !CDS_PN = "M5";
"UPI1_TX_DP<3>":   PN = "H5"  !CDS_PN = "H5";
"UPI1_TX_DP<4>":   PN = "F7"  !CDS_PN = "F7";
"UPI1_TX_DP<5>":   PN = "K7"  !CDS_PN = "K7";
"UPI1_TX_DP<6>":   PN = "J8"  !CDS_PN = "J8";
"UPI1_TX_DP<7>":   PN = "F9"  !CDS_PN = "F9";
"UPI1_TX_DP<8>":   PN = "E10"  !CDS_PN = "E10";
"UPI1_TX_DP<9>":   PN = "H9"  !CDS_PN = "H9";
"UPI1_TX_DP<10>":   PN = "G12"  !CDS_PN = "G12";
"UPI1_TX_DP<11>":   PN = "F13"  !CDS_PN = "F13";
"UPI1_TX_DP<12>":   PN = "E14"  !CDS_PN = "E14";
"UPI1_TX_DP<13>":   PN = "H15"  !CDS_PN = "H15";
"UPI1_TX_DP<14>":   PN = "G16"  !CDS_PN = "G16";
"UPI1_TX_DP<15>":   PN = "L18"  !CDS_PN = "L18";
"UPI1_TX_DP<16>":   PN = "J18"  !CDS_PN = "J18";
"UPI1_TX_DP<17>":   PN = "H19"  !CDS_PN = "H19";
"UPI1_TX_DP<18>":   PN = "G20"  !CDS_PN = "G20";
"UPI1_TX_DP<19>":   PN = "K21"  !CDS_PN = "K21";
DRAWING = "@baseboard_fab2_lib.baseboard_fab2(sch_1):page35";
BODY = "SKX_EXT_B","I3": #LOCATION = "U5D1" !CDS_LOCATION = "U5D1" #SEC = "15" !CDS_SEC = "15";
"UPI2_RX_DN<0>":   PN = "DF23"  !CDS_PN = "DF23";
"UPI2_RX_DN<1>":   PN = "DE22"  !CDS_PN = "DE22";
"UPI2_RX_DN<2>":   PN = "DC22"  !CDS_PN = "DC22";
"UPI2_RX_DN<3>":   PN = "DB21"  !CDS_PN = "DB21";
"UPI2_RX_DN<4>":   PN = "DD19"  !CDS_PN = "DD19";
"UPI2_RX_DN<5>":   PN = "DA20"  !CDS_PN = "DA20";
"UPI2_RX_DN<6>":   PN = "CW20"  !CDS_PN = "CW20";
"UPI2_RX_DN<7>":   PN = "CV19"  !CDS_PN = "CV19";
"UPI2_RX_DN<8>":   PN = "CT21"  !CDS_PN = "CT21";
"UPI2_RX_DN<9>":   PN = "CR18"  !CDS_PN = "CR18";
"UPI2_RX_DN<10>":   PN = "CN20"  !CDS_PN = "CN20";
"UPI2_RX_DN<11>":   PN = "CP21"  !CDS_PN = "CP21";
"UPI2_RX_DN<12>":   PN = "CL16"  !CDS_PN = "CL16";
"UPI2_RX_DN<13>":   PN = "CJ18"  !CDS_PN = "CJ18";
"UPI2_RX_DN<14>":   PN = "CH17"  !CDS_PN = "CH17";
"UPI2_RX_DN<15>":   PN = "CE16"  !CDS_PN = "CE16";
"UPI2_RX_DN<16>":   PN = "CD15"  !CDS_PN = "CD15";
"UPI2_RX_DN<17>":   PN = "CF17"  !CDS_PN = "CF17";
"UPI2_RX_DN<18>":   PN = "CB15"  !CDS_PN = "CB15";
"UPI2_RX_DN<19>":   PN = "BY17"  !CDS_PN = "BY17";
"UPI2_RX_DP<0>":   PN = "DG22"  !CDS_PN = "DG22";
"UPI2_RX_DP<1>":   PN = "DD21"  !CDS_PN = "DD21";
"UPI2_RX_DP<2>":   PN = "DA22"  !CDS_PN = "DA22";
"UPI2_RX_DP<3>":   PN = "DC20"  !CDS_PN = "DC20";
"UPI2_RX_DP<4>":   PN = "DB19"  !CDS_PN = "DB19";
"UPI2_RX_DP<5>":   PN = "CY19"  !CDS_PN = "CY19";
"UPI2_RX_DP<6>":   PN = "CU20"  !CDS_PN = "CU20";
"UPI2_RX_DP<7>":   PN = "CW18"  !CDS_PN = "CW18";
"UPI2_RX_DP<8>":   PN = "CR20"  !CDS_PN = "CR20";
"UPI2_RX_DP<9>":   PN = "CN18"  !CDS_PN = "CN18";
"UPI2_RX_DP<10>":   PN = "CP19"  !CDS_PN = "CP19";
"UPI2_RX_DP<11>":   PN = "CM21"  !CDS_PN = "CM21";
"UPI2_RX_DP<12>":   PN = "CJ16"  !CDS_PN = "CJ16";
"UPI2_RX_DP<13>":   PN = "CK17"  !CDS_PN = "CK17";
"UPI2_RX_DP<14>":   PN = "CG16"  !CDS_PN = "CG16";
"UPI2_RX_DP<15>":   PN = "CF15"  !CDS_PN = "CF15";
"UPI2_RX_DP<16>":   PN = "CC14"  !CDS_PN = "CC14";
"UPI2_RX_DP<17>":   PN = "CD17"  !CDS_PN = "CD17";
"UPI2_RX_DP<18>":   PN = "BY15"  !CDS_PN = "BY15";
"UPI2_RX_DP<19>":   PN = "CA16"  !CDS_PN = "CA16";
"UPI2_TX_DN<0>":   PN = "DT21"  !CDS_PN = "DT21";
"UPI2_TX_DN<1>":   PN = "DM21"  !CDS_PN = "DM21";
"UPI2_TX_DN<2>":   PN = "DL20"  !CDS_PN = "DL20";
"UPI2_TX_DN<3>":   PN = "DG20"  !CDS_PN = "DG20";
"UPI2_TX_DN<4>":   PN = "DH19"  !CDS_PN = "DH19";
"UPI2_TX_DN<5>":   PN = "DK17"  !CDS_PN = "DK17";
"UPI2_TX_DN<6>":   PN = "DG18"  !CDS_PN = "DG18";
"UPI2_TX_DN<7>":   PN = "DD17"  !CDS_PN = "DD17";
"UPI2_TX_DN<8>":   PN = "DF15"  !CDS_PN = "DF15";
"UPI2_TX_DN<9>":   PN = "DC16"  !CDS_PN = "DC16";
"UPI2_TX_DN<10>":   PN = "DA16"  !CDS_PN = "DA16";
"UPI2_TX_DN<11>":   PN = "CW14"  !CDS_PN = "CW14";
"UPI2_TX_DN<12>":   PN = "CU14"  !CDS_PN = "CU14";
"UPI2_TX_DN<13>":   PN = "CM13"  !CDS_PN = "CM13";
"UPI2_TX_DN<14>":   PN = "CJ14"  !CDS_PN = "CJ14";
"UPI2_TX_DN<15>":   PN = "CF13"  !CDS_PN = "CF13";
"UPI2_TX_DN<16>":   PN = "CH11"  !CDS_PN = "CH11";
"UPI2_TX_DN<17>":   PN = "CE12"  !CDS_PN = "CE12";
"UPI2_TX_DN<18>":   PN = "CC10"  !CDS_PN = "CC10";
"UPI2_TX_DN<19>":   PN = "CC12"  !CDS_PN = "CC12";
"UPI2_TX_DP<0>":   PN = "DP21"  !CDS_PN = "DP21";
"UPI2_TX_DP<1>":   PN = "DN20"  !CDS_PN = "DN20";
"UPI2_TX_DP<2>":   PN = "DK19"  !CDS_PN = "DK19";
"UPI2_TX_DP<3>":   PN = "DJ20"  !CDS_PN = "DJ20";
"UPI2_TX_DP<4>":   PN = "DJ18"  !CDS_PN = "DJ18";
"UPI2_TX_DP<5>":   PN = "DH17"  !CDS_PN = "DH17";
"UPI2_TX_DP<6>":   PN = "DF17"  !CDS_PN = "DF17";
"UPI2_TX_DP<7>":   PN = "DE16"  !CDS_PN = "DE16";
"UPI2_TX_DP<8>":   PN = "DD15"  !CDS_PN = "DD15";
"UPI2_TX_DP<9>":   PN = "DB15"  !CDS_PN = "DB15";
"UPI2_TX_DP<10>":   PN = "CW16"  !CDS_PN = "CW16";
"UPI2_TX_DP<11>":   PN = "CV13"  !CDS_PN = "CV13";
"UPI2_TX_DP<12>":   PN = "CR14"  !CDS_PN = "CR14";
"UPI2_TX_DP<13>":   PN = "CK13"  !CDS_PN = "CK13";
"UPI2_TX_DP<14>":   PN = "CH13"  !CDS_PN = "CH13";
"UPI2_TX_DP<15>":   PN = "CG12"  !CDS_PN = "CG12";
"UPI2_TX_DP<16>":   PN = "CF11"  !CDS_PN = "CF11";
"UPI2_TX_DP<17>":   PN = "CD11"  !CDS_PN = "CD11";
"UPI2_TX_DP<18>":   PN = "CB11"  !CDS_PN = "CB11";
"UPI2_TX_DP<19>":   PN = "CA12"  !CDS_PN = "CA12";
DRAWING = "@baseboard_fab2_lib.baseboard_fab2(sch_1):page36";
BODY = "SKX_EXT_B","I15": #LOCATION = "U5D1" !CDS_LOCATION = "U5D1" #SEC = "16" !CDS_SEC = "16";
"RSVD<92>":   PN = "CH23"  !CDS_PN = "CH23";
"RSVD<93>":   PN = "CH21"  !CDS_PN = "CH21";
"RSVD<94>":   PN = "CG82"  !CDS_PN = "CG82";
"RSVD<95>":   PN = "CG78"  !CDS_PN = "CG78";
"RSVD<96>":   PN = "CG26"  !CDS_PN = "CG26";
"RSVD<97>":   PN = "CG24"  !CDS_PN = "CG24";
"RSVD<98>":   PN = "CG20"  !CDS_PN = "CG20";
"RSVD<99>":   PN = "CG10"  !CDS_PN = "CG10";
"RSVD<100>":   PN = "CF81"  !CDS_PN = "CF81";
"RSVD<101>":   PN = "CF79"  !CDS_PN = "CF79";
"RSVD<102>":   PN = "CF23"  !CDS_PN = "CF23";
"RSVD<103>":   PN = "CF21"  !CDS_PN = "CF21";
"RSVD<104>":   PN = "CF19"  !CDS_PN = "CF19";
"RSVD<105>":   PN = "CE80"  !CDS_PN = "CE80";
"RSVD<106>":   PN = "CE78"  !CDS_PN = "CE78";
"RSVD<107>":   PN = "CE22"  !CDS_PN = "CE22";
"RSVD<108>":   PN = "CD25"  !CDS_PN = "CD25";
"RSVD<109>":   PN = "CD21"  !CDS_PN = "CD21";
"RSVD<110>":   PN = "CD19"  !CDS_PN = "CD19";
"RSVD<111>":   PN = "CC6"  !CDS_PN = "CC6";
"RSVD<112>":   PN = "CC20"  !CDS_PN = "CC20";
"RSVD<113>":   PN = "CB5"  !CDS_PN = "CB5";
"RSVD<114>":   PN = "CB25"  !CDS_PN = "CB25";
"RSVD<115>":   PN = "CB21"  !CDS_PN = "CB21";
"RSVD<116>":   PN = "CB19"  !CDS_PN = "CB19";
"RSVD<117>":   PN = "CA24"  !CDS_PN = "CA24";
"RSVD<118>":   PN = "CA22"  !CDS_PN = "CA22";
"RSVD<119>":   PN = "BY25"  !CDS_PN = "BY25";
"RSVD<120>":   PN = "BY19"  !CDS_PN = "BY19";
"RSVD<121>":   PN = "BW22"  !CDS_PN = "BW22";
"RSVD<122>":   PN = "BW20"  !CDS_PN = "BW20";
"RSVD<123>":   PN = "BW10"  !CDS_PN = "BW10";
"RSVD<124>":   PN = "BV23"  !CDS_PN = "BV23";
"RSVD<125>":   PN = "BV21"  !CDS_PN = "BV21";
"RSVD<126>":   PN = "BV19"  !CDS_PN = "BV19";
"RSVD<127>":   PN = "BU22"  !CDS_PN = "BU22";
"RSVD<128>":   PN = "BU20"  !CDS_PN = "BU20";
"RSVD<129>":   PN = "BU18"  !CDS_PN = "BU18";
"RSVD<130>":   PN = "BR24"  !CDS_PN = "BR24";
"RSVD<131>":   PN = "BR22"  !CDS_PN = "BR22";
"RSVD<132>":   PN = "BP21"  !CDS_PN = "BP21";
"RSVD<133>":   PN = "BP17"  !CDS_PN = "BP17";
"RSVD<134>":   PN = "BN18"  !CDS_PN = "BN18";
"RSVD<135>":   PN = "BM19"  !CDS_PN = "BM19";
"RSVD<136>":   PN = "BM17"  !CDS_PN = "BM17";
"RSVD<137>":   PN = "BL20"  !CDS_PN = "BL20";
"RSVD<138>":   PN = "BL18"  !CDS_PN = "BL18";
"RSVD<139>":   PN = "BK17"  !CDS_PN = "BK17";
"RSVD<140>":   PN = "BJ20"  !CDS_PN = "BJ20";
"RSVD<141>":   PN = "BJ18"  !CDS_PN = "BJ18";
"RSVD<142>":   PN = "BJ16"  !CDS_PN = "BJ16";
"RSVD<143>":   PN = "BH19"  !CDS_PN = "BH19";
"RSVD<144>":   PN = "BG20"  !CDS_PN = "BG20";
"RSVD<145>":   PN = "BG18"  !CDS_PN = "BG18";
"RSVD<146>":   PN = "BF21"  !CDS_PN = "BF21";
"RSVD<147>":   PN = "BE22"  !CDS_PN = "BE22";
"RSVD<148>":   PN = "BE20"  !CDS_PN = "BE20";
"RSVD<149>":   PN = "BE18"  !CDS_PN = "BE18";
"RSVD<150>":   PN = "BD69"  !CDS_PN = "BD69";
"RSVD<151>":   PN = "BD67"  !CDS_PN = "BD67";
"RSVD<152>":   PN = "BD65"  !CDS_PN = "BD65";
"RSVD<153>":   PN = "BD25"  !CDS_PN = "BD25";
"RSVD<154>":   PN = "BD19"  !CDS_PN = "BD19";
"RSVD<155>":   PN = "BD17"  !CDS_PN = "BD17";
"RSVD<156>":   PN = "BC68"  !CDS_PN = "BC68";
"RSVD<157>":   PN = "BC66"  !CDS_PN = "BC66";
"RSVD<158>":   PN = "BC64"  !CDS_PN = "BC64";
"RSVD<159>":   PN = "BC22"  !CDS_PN = "BC22";
"RSVD<160>":   PN = "BC20"  !CDS_PN = "BC20";
"RSVD<161>":   PN = "BC18"  !CDS_PN = "BC18";
"RSVD<162>":   PN = "BC14"  !CDS_PN = "BC14";
"RSVD<163>":   PN = "BB67"  !CDS_PN = "BB67";
"RSVD<164>":   PN = "BB65"  !CDS_PN = "BB65";
"RSVD<165>":   PN = "BB25"  !CDS_PN = "BB25";
"RSVD<166>":   PN = "BB21"  !CDS_PN = "BB21";
"RSVD<167>":   PN = "BB17"  !CDS_PN = "BB17";
"RSVD<168>":   PN = "BB15"  !CDS_PN = "BB15";
"RSVD<169>":   PN = "BB13"  !CDS_PN = "BB13";
"RSVD<170>":   PN = "BA82"  !CDS_PN = "BA82";
"RSVD<171>":   PN = "BA78"  !CDS_PN = "BA78";
"RSVD<255>":   PN = "AY83"  !CDS_PN = "AY83";
BODY = "SKX_EXT_B","I16": #LOCATION = "U5D1" !CDS_LOCATION = "U5D1" #SEC = "17" !CDS_SEC = "17";
"RSVD<81>":   PN = "CL24"  !CDS_PN = "CL24";
"RSVD<82>":   PN = "CK77"  !CDS_PN = "CK77";
"RSVD<83>":   PN = "CK25"  !CDS_PN = "CK25";
"RSVD<84>":   PN = "CK23"  !CDS_PN = "CK23";
"RSVD<85>":   PN = "CK19"  !CDS_PN = "CK19";
"RSVD<86>":   PN = "CJ26"  !CDS_PN = "CJ26";
"RSVD<87>":   PN = "CJ24"  !CDS_PN = "CJ24";
"RSVD<88>":   PN = "CJ22"  !CDS_PN = "CJ22";
"RSVD<89>":   PN = "CJ20"  !CDS_PN = "CJ20";
"RSVD<90>":   PN = "CH77"  !CDS_PN = "CH77";
"RSVD<91>":   PN = "CH25"  !CDS_PN = "CH25";
"TEST_6":   PN = "AR16"  !CDS_PN = "AR16";
"TEST_7":   PN = "AU18"  !CDS_PN = "AU18";
"TEST_8":   PN = "AW16"  !CDS_PN = "AW16";
"TEST_9":   PN = "AW20"  !CDS_PN = "AW20";
"TEST_10":   PN = "AW22"  !CDS_PN = "AW22";
DRAWING = "@baseboard_fab2_lib.baseboard_fab2(sch_1):page37";
BODY = "RES","I303": #LOCATION = "R5D5" !CDS_LOCATION = "R5D5" #SEC = "1" !CDS_SEC = "1";
"A":   PN = "1"  !CDS_PN = "1";
"B":   PN = "2"  !CDS_PN = "2";
BODY = "RES","I309": #LOCATION = "R5P1" !CDS_LOCATION = "R5P1" #SEC = "1" !CDS_SEC = "1";
"A":   PN = "1"  !CDS_PN = "1";
"B":   PN = "2"  !CDS_PN = "2";
BODY = "SKX_EXT_B","I310": #LOCATION = "U5D1" !CDS_LOCATION = "U5D1" #SEC = "18" !CDS_SEC = "18";
"VCCIN<130>":   PN = "BN78"  !CDS_PN = "BN78";
"VCCIN<131>":   PN = "BN76"  !CDS_PN = "BN76";
"VCCIN<132>":   PN = "BN74"  !CDS_PN = "BN74";
"VCCIN<133>":   PN = "BN72"  !CDS_PN = "BN72";
"VCCIN<134>":   PN = "BN70"  !CDS_PN = "BN70";
"VCCIN<135>":   PN = "BN68"  !CDS_PN = "BN68";
"VCCIN<136>":   PN = "BN66"  !CDS_PN = "BN66";
"VCCIN<137>":   PN = "BN64"  !CDS_PN = "BN64";
"VCCIN<138>":   PN = "BN62"  !CDS_PN = "BN62";
"VCCIN<139>":   PN = "BN60"  !CDS_PN = "BN60";
"VCCIN<140>":   PN = "BM83"  !CDS_PN = "BM83";
"VCCIN<141>":   PN = "BM81"  !CDS_PN = "BM81";
"VCCIN<142>":   PN = "BM79"  !CDS_PN = "BM79";
"VCCIN<143>":   PN = "BM77"  !CDS_PN = "BM77";
"VCCIN<144>":   PN = "BM75"  !CDS_PN = "BM75";
"VCCIN<145>":   PN = "BM73"  !CDS_PN = "BM73";
"VCCIN<146>":   PN = "BM71"  !CDS_PN = "BM71";
"VCCIN<147>":   PN = "BM69"  !CDS_PN = "BM69";
"VCCIN<148>":   PN = "BM67"  !CDS_PN = "BM67";
"VCCIN<149>":   PN = "BM65"  !CDS_PN = "BM65";
"VCCIN<150>":   PN = "BM63"  !CDS_PN = "BM63";
"VCCIN<151>":   PN = "BM61"  !CDS_PN = "BM61";
"VCCIN<152>":   PN = "BL84"  !CDS_PN = "BL84";
"VCCIN<153>":   PN = "BL62"  !CDS_PN = "BL62";
"VCCIN<154>":   PN = "BL60"  !CDS_PN = "BL60";
"VCCIN<155>":   PN = "BK83"  !CDS_PN = "BK83";
"VCCIN<156>":   PN = "BK81"  !CDS_PN = "BK81";
"VCCIN<157>":   PN = "BK79"  !CDS_PN = "BK79";
"VCCIN<158>":   PN = "BK77"  !CDS_PN = "BK77";
"VCCIN<159>":   PN = "BK75"  !CDS_PN = "BK75";
"VCCIN<160>":   PN = "BK73"  !CDS_PN = "BK73";
"VCCIN<161>":   PN = "BK71"  !CDS_PN = "BK71";
"VCCIN<162>":   PN = "BK69"  !CDS_PN = "BK69";
"VCCIN<163>":   PN = "BK67"  !CDS_PN = "BK67";
"VCCIN<164>":   PN = "BK65"  !CDS_PN = "BK65";
"VCCIN<165>":   PN = "BK63"  !CDS_PN = "BK63";
"VCCIN<166>":   PN = "BK61"  !CDS_PN = "BK61";
"VCCIN<167>":   PN = "BJ84"  !CDS_PN = "BJ84";
"VCCIN<168>":   PN = "BJ82"  !CDS_PN = "BJ82";
"VCCIN<169>":   PN = "BJ80"  !CDS_PN = "BJ80";
"VCCIN<170>":   PN = "BJ78"  !CDS_PN = "BJ78";
"VCCIN<171>":   PN = "BJ76"  !CDS_PN = "BJ76";
"VCCIN<172>":   PN = "BJ74"  !CDS_PN = "BJ74";
"VCCIN<173>":   PN = "BJ72"  !CDS_PN = "BJ72";
"VCCIN<174>":   PN = "BJ70"  !CDS_PN = "BJ70";
"VCCIN<175>":   PN = "BJ68"  !CDS_PN = "BJ68";
"VCCIN<176>":   PN = "BJ66"  !CDS_PN = "BJ66";
"VCCIN<177>":   PN = "BJ64"  !CDS_PN = "BJ64";
"VCCIN<178>":   PN = "BJ62"  !CDS_PN = "BJ62";
"VCCIN<179>":   PN = "BJ60"  !CDS_PN = "BJ60";
"VCCIN<180>":   PN = "BH83"  !CDS_PN = "BH83";
"VCCIN<181>":   PN = "BH81"  !CDS_PN = "BH81";
"VCCIN<182>":   PN = "BH79"  !CDS_PN = "BH79";
"VCCIN<183>":   PN = "BH77"  !CDS_PN = "BH77";
"VCCIN<184>":   PN = "BH75"  !CDS_PN = "BH75";
"VCCIN<185>":   PN = "BH73"  !CDS_PN = "BH73";
"VCCIN<186>":   PN = "BH71"  !CDS_PN = "BH71";
"VCCIN<187>":   PN = "BH69"  !CDS_PN = "BH69";
"VCCIN<188>":   PN = "BH67"  !CDS_PN = "BH67";
"VCCIN<189>":   PN = "BH65"  !CDS_PN = "BH65";
"VCCIN<190>":   PN = "BH63"  !CDS_PN = "BH63";
"VCCIN<191>":   PN = "BH61"  !CDS_PN = "BH61";
"VCCIN<192>":   PN = "BG84"  !CDS_PN = "BG84";
"VCCIN<193>":   PN = "BG70"  !CDS_PN = "BG70";
"VCCIN<194>":   PN = "BG68"  !CDS_PN = "BG68";
"VCCIN<195>":   PN = "BG66"  !CDS_PN = "BG66";
"VCCIN<196>":   PN = "BG64"  !CDS_PN = "BG64";
"VCCIN<197>":   PN = "BG62"  !CDS_PN = "BG62";
"VCCIN<198>":   PN = "BG60"  !CDS_PN = "BG60";
"VCCIN<199>":   PN = "BF85"  !CDS_PN = "BF85";
"VCCIN<200>":   PN = "BF83"  !CDS_PN = "BF83";
"VCCIN<201>":   PN = "BF81"  !CDS_PN = "BF81";
"VCCIN<202>":   PN = "BF79"  !CDS_PN = "BF79";
"VCCIN<203>":   PN = "BF77"  !CDS_PN = "BF77";
"VCCIN<204>":   PN = "BF75"  !CDS_PN = "BF75";
"VCCIN<205>":   PN = "BF73"  !CDS_PN = "BF73";
"VCCIN<206>":   PN = "BF61"  !CDS_PN = "BF61";
"VCCIN<207>":   PN = "BE84"  !CDS_PN = "BE84";
"VCCIN<208>":   PN = "BE82"  !CDS_PN = "BE82";
"VCCIN<209>":   PN = "BE80"  !CDS_PN = "BE80";
"VCCIN<210>":   PN = "BE78"  !CDS_PN = "BE78";
"VCCIN<211>":   PN = "BE76"  !CDS_PN = "BE76";
"VCCIN<212>":   PN = "BE74"  !CDS_PN = "BE74";
"VCCIN<213>":   PN = "BE72"  !CDS_PN = "BE72";
"VCCIN<214>":   PN = "BE62"  !CDS_PN = "BE62";
"VCCIN<215>":   PN = "BE60"  !CDS_PN = "BE60";
"VCCIN<216>":   PN = "BD85"  !CDS_PN = "BD85";
"VCCIN<217>":   PN = "BD83"  !CDS_PN = "BD83";
"VCCIN<218>":   PN = "BD81"  !CDS_PN = "BD81";
"VCCIN<219>":   PN = "BD79"  !CDS_PN = "BD79";
"VCCIN<220>":   PN = "BD77"  !CDS_PN = "BD77";
"VCCIN<221>":   PN = "BD75"  !CDS_PN = "BD75";
"VCCIN<222>":   PN = "BD73"  !CDS_PN = "BD73";
"VCCIN<223>":   PN = "BD61"  !CDS_PN = "BD61";
"VCCIN<224>":   PN = "BC84"  !CDS_PN = "BC84";
"VCCIN<225>":   PN = "BC62"  !CDS_PN = "BC62";
"VCCIN<226>":   PN = "BC60"  !CDS_PN = "BC60";
"VCCIN<227>":   PN = "BB85"  !CDS_PN = "BB85";
"VCCIN<228>":   PN = "BB61"  !CDS_PN = "BB61";
"VCCIN<229>":   PN = "BA60"  !CDS_PN = "BA60";
"VCCIN<230>":   PN = "AY61"  !CDS_PN = "AY61";
"VCCIN<231>":   PN = "AW60"  !CDS_PN = "AW60";
"VCCIN<232>":   PN = "AV61"  !CDS_PN = "AV61";
"VCCIN<233>":   PN = "AV59"  !CDS_PN = "AV59";
"VCCIN<234>":   PN = "AU60"  !CDS_PN = "AU60";
"VCCIN<235>":   PN = "AU58"  !CDS_PN = "AU58";
"VCCIN<236>":   PN = "AT59"  !CDS_PN = "AT59";
"VCCIN<237>":   PN = "AT57"  !CDS_PN = "AT57";
"VCCIN<238>":   PN = "AR58"  !CDS_PN = "AR58";
"VCCIN<239>":   PN = "AR56"  !CDS_PN = "AR56";
"VCCIN<240>":   PN = "AP57"  !CDS_PN = "AP57";
"VCCIN<241>":   PN = "AP55"  !CDS_PN = "AP55";
"VCCIN<242>":   PN = "AN56"  !CDS_PN = "AN56";
"VCCIN<243>":   PN = "AN54"  !CDS_PN = "AN54";
"VCCIN<244>":   PN = "AN32"  !CDS_PN = "AN32";
"VCCIN<245>":   PN = "AM55"  !CDS_PN = "AM55";
"VCCIN<246>":   PN = "AM53"  !CDS_PN = "AM53";
"VCCIN<247>":   PN = "AM33"  !CDS_PN = "AM33";
"VCCIN<248>":   PN = "AL54"  !CDS_PN = "AL54";
"VCCIN<249>":   PN = "AL52"  !CDS_PN = "AL52";
"VCCIN<250>":   PN = "AL50"  !CDS_PN = "AL50";
"VCCIN<251>":   PN = "AL48"  !CDS_PN = "AL48";
"VCCIN<252>":   PN = "AL46"  !CDS_PN = "AL46";
"VCCIN<253>":   PN = "AL34"  !CDS_PN = "AL34";
"VCCIN<254>":   PN = "AK53"  !CDS_PN = "AK53";
"VCCIN<255>":   PN = "AK51"  !CDS_PN = "AK51";
"VCCIN<256>":   PN = "AK49"  !CDS_PN = "AK49";
"VCCIN<257>":   PN = "AK47"  !CDS_PN = "AK47";
"VCCIN<258>":   PN = "AK45"  !CDS_PN = "AK45";
"VCCIN<259>":   PN = "AK35"  !CDS_PN = "AK35";
"VCCIN<260>":   PN = "AJ36"  !CDS_PN = "AJ36";
"VCCIN<261>":   PN = "AH41"  !CDS_PN = "AH41";
"VCCIN<262>":   PN = "AH39"  !CDS_PN = "AH39";
"VCCIN<263>":   PN = "AH37"  !CDS_PN = "AH37";
"VCCIN<264>":   PN = "AG42"  !CDS_PN = "AG42";
"VCCIN<265>":   PN = "AG40"  !CDS_PN = "AG40";
"VCCIN<266>":   PN = "AG38"  !CDS_PN = "AG38";
"VCCIN<267>":   PN = "AF43"  !CDS_PN = "AF43";
BODY = "SKX_EXT_B","I311": #LOCATION = "U5D1" !CDS_LOCATION = "U5D1" #SEC = "19" !CDS_SEC = "19";
"VCCIN<0>":   PN = "CY49"  !CDS_PN = "CY49";
"VCCIN<1>":   PN = "CY47"  !CDS_PN = "CY47";
"VCCIN<2>":   PN = "CW50"  !CDS_PN = "CW50";
"VCCIN<3>":   PN = "CW48"  !CDS_PN = "CW48";
"VCCIN<4>":   PN = "CW46"  !CDS_PN = "CW46";
"VCCIN<5>":   PN = "CV51"  !CDS_PN = "CV51";
"VCCIN<6>":   PN = "CU54"  !CDS_PN = "CU54";
"VCCIN<7>":   PN = "CU52"  !CDS_PN = "CU52";
"VCCIN<8>":   PN = "CU42"  !CDS_PN = "CU42";
"VCCIN<9>":   PN = "CU40"  !CDS_PN = "CU40";
"VCCIN<10>":   PN = "CU38"  !CDS_PN = "CU38";
"VCCIN<11>":   PN = "CT55"  !CDS_PN = "CT55";
"VCCIN<12>":   PN = "CT53"  !CDS_PN = "CT53";
"VCCIN<13>":   PN = "CT41"  !CDS_PN = "CT41";
"VCCIN<14>":   PN = "CT39"  !CDS_PN = "CT39";
"VCCIN<15>":   PN = "CT37"  !CDS_PN = "CT37";
"VCCIN<16>":   PN = "CR56"  !CDS_PN = "CR56";
"VCCIN<17>":   PN = "CR54"  !CDS_PN = "CR54";
"VCCIN<18>":   PN = "CR34"  !CDS_PN = "CR34";
"VCCIN<19>":   PN = "CP57"  !CDS_PN = "CP57";
"VCCIN<20>":   PN = "CP55"  !CDS_PN = "CP55";
"VCCIN<21>":   PN = "CP33"  !CDS_PN = "CP33";
"VCCIN<22>":   PN = "CN58"  !CDS_PN = "CN58";
"VCCIN<23>":   PN = "CN56"  !CDS_PN = "CN56";
"VCCIN<24>":   PN = "CM59"  !CDS_PN = "CM59";
"VCCIN<25>":   PN = "CM57"  !CDS_PN = "CM57";
"VCCIN<26>":   PN = "CL60"  !CDS_PN = "CL60";
"VCCIN<27>":   PN = "CL58"  !CDS_PN = "CL58";
"VCCIN<28>":   PN = "CK61"  !CDS_PN = "CK61";
"VCCIN<29>":   PN = "CK59"  !CDS_PN = "CK59";
"VCCIN<30>":   PN = "CJ60"  !CDS_PN = "CJ60";
"VCCIN<31>":   PN = "CH85"  !CDS_PN = "CH85";
"VCCIN<32>":   PN = "CH61"  !CDS_PN = "CH61";
"VCCIN<33>":   PN = "CG84"  !CDS_PN = "CG84";
"VCCIN<34>":   PN = "CG60"  !CDS_PN = "CG60";
"VCCIN<35>":   PN = "CF85"  !CDS_PN = "CF85";
"VCCIN<36>":   PN = "CF61"  !CDS_PN = "CF61";
"VCCIN<37>":   PN = "CE84"  !CDS_PN = "CE84";
"VCCIN<38>":   PN = "CE60"  !CDS_PN = "CE60";
"VCCIN<39>":   PN = "CD85"  !CDS_PN = "CD85";
"VCCIN<40>":   PN = "CD83"  !CDS_PN = "CD83";
"VCCIN<41>":   PN = "CD61"  !CDS_PN = "CD61";
"VCCIN<42>":   PN = "CC84"  !CDS_PN = "CC84";
"VCCIN<43>":   PN = "CC62"  !CDS_PN = "CC62";
"VCCIN<44>":   PN = "CC60"  !CDS_PN = "CC60";
"VCCIN<45>":   PN = "CB83"  !CDS_PN = "CB83";
"VCCIN<46>":   PN = "CB81"  !CDS_PN = "CB81";
"VCCIN<47>":   PN = "CB79"  !CDS_PN = "CB79";
"VCCIN<48>":   PN = "CB77"  !CDS_PN = "CB77";
"VCCIN<49>":   PN = "CB75"  !CDS_PN = "CB75";
"VCCIN<50>":   PN = "CB73"  !CDS_PN = "CB73";
"VCCIN<51>":   PN = "CB61"  !CDS_PN = "CB61";
"VCCIN<52>":   PN = "CA84"  !CDS_PN = "CA84";
"VCCIN<53>":   PN = "CA82"  !CDS_PN = "CA82";
"VCCIN<54>":   PN = "CA80"  !CDS_PN = "CA80";
"VCCIN<55>":   PN = "CA78"  !CDS_PN = "CA78";
"VCCIN<56>":   PN = "CA76"  !CDS_PN = "CA76";
"VCCIN<57>":   PN = "CA74"  !CDS_PN = "CA74";
"VCCIN<58>":   PN = "CA72"  !CDS_PN = "CA72";
"VCCIN<59>":   PN = "CA62"  !CDS_PN = "CA62";
"VCCIN<60>":   PN = "CA60"  !CDS_PN = "CA60";
"VCCIN<61>":   PN = "BY83"  !CDS_PN = "BY83";
"VCCIN<62>":   PN = "BY81"  !CDS_PN = "BY81";
"VCCIN<63>":   PN = "BY79"  !CDS_PN = "BY79";
"VCCIN<64>":   PN = "BY77"  !CDS_PN = "BY77";
"VCCIN<65>":   PN = "BY75"  !CDS_PN = "BY75";
"VCCIN<66>":   PN = "BY73"  !CDS_PN = "BY73";
"VCCIN<67>":   PN = "BY61"  !CDS_PN = "BY61";
"VCCIN<68>":   PN = "BW84"  !CDS_PN = "BW84";
"VCCIN<69>":   PN = "BW70"  !CDS_PN = "BW70";
"VCCIN<70>":   PN = "BW68"  !CDS_PN = "BW68";
"VCCIN<71>":   PN = "BW66"  !CDS_PN = "BW66";
"VCCIN<72>":   PN = "BW64"  !CDS_PN = "BW64";
"VCCIN<73>":   PN = "BW62"  !CDS_PN = "BW62";
"VCCIN<74>":   PN = "BW60"  !CDS_PN = "BW60";
"VCCIN<75>":   PN = "BV83"  !CDS_PN = "BV83";
"VCCIN<76>":   PN = "BV81"  !CDS_PN = "BV81";
"VCCIN<77>":   PN = "BV79"  !CDS_PN = "BV79";
"VCCIN<78>":   PN = "BV77"  !CDS_PN = "BV77";
"VCCIN<79>":   PN = "BV75"  !CDS_PN = "BV75";
"VCCIN<80>":   PN = "BV73"  !CDS_PN = "BV73";
"VCCIN<81>":   PN = "BV71"  !CDS_PN = "BV71";
"VCCIN<82>":   PN = "BV69"  !CDS_PN = "BV69";
"VCCIN<83>":   PN = "BV67"  !CDS_PN = "BV67";
"VCCIN<84>":   PN = "BV65"  !CDS_PN = "BV65";
"VCCIN<85>":   PN = "BV63"  !CDS_PN = "BV63";
"VCCIN<86>":   PN = "BV61"  !CDS_PN = "BV61";
"VCCIN<87>":   PN = "BU84"  !CDS_PN = "BU84";
"VCCIN<88>":   PN = "BU82"  !CDS_PN = "BU82";
"VCCIN<89>":   PN = "BU80"  !CDS_PN = "BU80";
"VCCIN<90>":   PN = "BU78"  !CDS_PN = "BU78";
"VCCIN<91>":   PN = "BU76"  !CDS_PN = "BU76";
"VCCIN<92>":   PN = "BU74"  !CDS_PN = "BU74";
"VCCIN<93>":   PN = "BU72"  !CDS_PN = "BU72";
"VCCIN<94>":   PN = "BU70"  !CDS_PN = "BU70";
"VCCIN<95>":   PN = "BU68"  !CDS_PN = "BU68";
"VCCIN<96>":   PN = "BU66"  !CDS_PN = "BU66";
"VCCIN<97>":   PN = "BU64"  !CDS_PN = "BU64";
"VCCIN<98>":   PN = "BU62"  !CDS_PN = "BU62";
"VCCIN<99>":   PN = "BU60"  !CDS_PN = "BU60";
"VCCIN<100>":   PN = "BT83"  !CDS_PN = "BT83";
"VCCIN<101>":   PN = "BT81"  !CDS_PN = "BT81";
"VCCIN<102>":   PN = "BT79"  !CDS_PN = "BT79";
"VCCIN<103>":   PN = "BT77"  !CDS_PN = "BT77";
"VCCIN<104>":   PN = "BT75"  !CDS_PN = "BT75";
"VCCIN<105>":   PN = "BT73"  !CDS_PN = "BT73";
"VCCIN<106>":   PN = "BT71"  !CDS_PN = "BT71";
"VCCIN<107>":   PN = "BT69"  !CDS_PN = "BT69";
"VCCIN<108>":   PN = "BT67"  !CDS_PN = "BT67";
"VCCIN<109>":   PN = "BT65"  !CDS_PN = "BT65";
"VCCIN<110>":   PN = "BT63"  !CDS_PN = "BT63";
"VCCIN<111>":   PN = "BT61"  !CDS_PN = "BT61";
"VCCIN<112>":   PN = "BR84"  !CDS_PN = "BR84";
"VCCIN<113>":   PN = "BR62"  !CDS_PN = "BR62";
"VCCIN<114>":   PN = "BR60"  !CDS_PN = "BR60";
"VCCIN<115>":   PN = "BP83"  !CDS_PN = "BP83";
"VCCIN<116>":   PN = "BP81"  !CDS_PN = "BP81";
"VCCIN<117>":   PN = "BP79"  !CDS_PN = "BP79";
"VCCIN<118>":   PN = "BP77"  !CDS_PN = "BP77";
"VCCIN<119>":   PN = "BP75"  !CDS_PN = "BP75";
"VCCIN<120>":   PN = "BP73"  !CDS_PN = "BP73";
"VCCIN<121>":   PN = "BP71"  !CDS_PN = "BP71";
"VCCIN<122>":   PN = "BP69"  !CDS_PN = "BP69";
"VCCIN<123>":   PN = "BP67"  !CDS_PN = "BP67";
"VCCIN<124>":   PN = "BP65"  !CDS_PN = "BP65";
"VCCIN<125>":   PN = "BP63"  !CDS_PN = "BP63";
"VCCIN<126>":   PN = "BP61"  !CDS_PN = "BP61";
"VCCIN<127>":   PN = "BN84"  !CDS_PN = "BN84";
"VCCIN<128>":   PN = "BN82"  !CDS_PN = "BN82";
"VCCIN<129>":   PN = "BN80"  !CDS_PN = "BN80";
"VCCIN_SENSE":   PN = "BA86"  !CDS_PN = "BA86";
"VCCINPMAX<0>":   PN = "AW86"  !CDS_PN = "AW86";
"VCCINPMAX<1>":   PN = "AV85"  !CDS_PN = "AV85";
"VSENSEPMAX":   PN = "AD41"  !CDS_PN = "AD41";
"VSS_VCCIN_SENSE":   PN = "AY85"  !CDS_PN = "AY85";
BODY = "RES","I312": #LOCATION = "R5D6" !CDS_LOCATION = "R5D6" #SEC = "1" !CDS_SEC = "1";
"A":   PN = "1"  !CDS_PN = "1";
"B":   PN = "2"  !CDS_PN = "2";
DRAWING = "@baseboard_fab2_lib.baseboard_fab2(sch_1):page38";
BODY = "CAP","I19": #LOCATION = "C6D1" !CDS_LOCATION = "C6D1" #SEC = "1" !CDS_SEC = "1";
"A":   PN = "1"  !CDS_PN = "1";
"B":   PN = "2"  !CDS_PN = "2";
BODY = "SKX_EXT_B","I33": #LOCATION = "U5D1" !CDS_LOCATION = "U5D1" #SEC = "20" !CDS_SEC = "20";
"VCCD012<0>":   PN = "B49"  !CDS_PN = "B49";
"VCCD012<1>":   PN = "B53"  !CDS_PN = "B53";
"VCCD012<2>":   PN = "B59"  !CDS_PN = "B59";
"VCCD012<3>":   PN = "E46"  !CDS_PN = "E46";
"VCCD012<4>":   PN = "E48"  !CDS_PN = "E48";
"VCCD012<5>":   PN = "E50"  !CDS_PN = "E50";
"VCCD012<6>":   PN = "E52"  !CDS_PN = "E52";
"VCCD012<7>":   PN = "E54"  !CDS_PN = "E54";
"VCCD012<8>":   PN = "E56"  !CDS_PN = "E56";
"VCCD012<9>":   PN = "E58"  !CDS_PN = "E58";
"VCCD012<10>":   PN = "E60"  !CDS_PN = "E60";
"VCCD012<11>":   PN = "E62"  !CDS_PN = "E62";
"VCCD012<12>":   PN = "E64"  !CDS_PN = "E64";
"VCCD012<13>":   PN = "L46"  !CDS_PN = "L46";
"VCCD012<14>":   PN = "L48"  !CDS_PN = "L48";
"VCCD012<15>":   PN = "L50"  !CDS_PN = "L50";
"VCCD012<16>":   PN = "L52"  !CDS_PN = "L52";
"VCCD012<17>":   PN = "L54"  !CDS_PN = "L54";
"VCCD012<18>":   PN = "L56"  !CDS_PN = "L56";
"VCCD012<19>":   PN = "L58"  !CDS_PN = "L58";
"VCCD012<20>":   PN = "L60"  !CDS_PN = "L60";
"VCCD012<21>":   PN = "L62"  !CDS_PN = "L62";
"VCCD012<22>":   PN = "N64"  !CDS_PN = "N64";
"VCCD012<23>":   PN = "U46"  !CDS_PN = "U46";
"VCCD012<24>":   PN = "U48"  !CDS_PN = "U48";
"VCCD012<25>":   PN = "U50"  !CDS_PN = "U50";
"VCCD012<26>":   PN = "U52"  !CDS_PN = "U52";
"VCCD012<27>":   PN = "U54"  !CDS_PN = "U54";
"VCCD012<28>":   PN = "U56"  !CDS_PN = "U56";
"VCCD012<29>":   PN = "U58"  !CDS_PN = "U58";
"VCCD012<30>":   PN = "U60"  !CDS_PN = "U60";
"VCCD012<31>":   PN = "U62"  !CDS_PN = "U62";
"VCCD012<32>":   PN = "W64"  !CDS_PN = "W64";
"VCCD012<33>":   PN = "Y45"  !CDS_PN = "Y45";
"VCCD012<34>":   PN = "Y47"  !CDS_PN = "Y47";
"VCCD012<35>":   PN = "Y49"  !CDS_PN = "Y49";
"VCCD012<36>":   PN = "Y51"  !CDS_PN = "Y51";
"VCCD012<37>":   PN = "Y53"  !CDS_PN = "Y53";
"VCCD012<38>":   PN = "Y55"  !CDS_PN = "Y55";
"VCCD012<39>":   PN = "Y57"  !CDS_PN = "Y57";
"VCCD012<40>":   PN = "Y59"  !CDS_PN = "Y59";
"VCCD012<41>":   PN = "Y61"  !CDS_PN = "Y61";
"VCCD012<42>":   PN = "Y63"  !CDS_PN = "Y63";
"VCCD012<43>":   PN = "AD45"  !CDS_PN = "AD45";
"VCCD012<44>":   PN = "AF55"  !CDS_PN = "AF55";
"VCCD012<45>":   PN = "AF57"  !CDS_PN = "AF57";
"VCCD012<46>":   PN = "AF59"  !CDS_PN = "AF59";
"VCCD012<47>":   PN = "AF61"  !CDS_PN = "AF61";
"VCCD012<48>":   PN = "AF63"  !CDS_PN = "AF63";
"VCCD012<49>":   PN = "D45"  !CDS_PN = "D45";
"VCCD012<50>":   PN = "C46"  !CDS_PN = "C46";
"VCCD012<51>":   PN = "B47"  !CDS_PN = "B47";
"VCCD345<0>":   PN = "EF59"  !CDS_PN = "EF59";
"VCCD345<1>":   PN = "EF53"  !CDS_PN = "EF53";
"VCCD345<2>":   PN = "EF49"  !CDS_PN = "EF49";
"VCCD345<3>":   PN = "EC62"  !CDS_PN = "EC62";
"VCCD345<4>":   PN = "EC60"  !CDS_PN = "EC60";
"VCCD345<5>":   PN = "EC58"  !CDS_PN = "EC58";
"VCCD345<6>":   PN = "EC56"  !CDS_PN = "EC56";
"VCCD345<7>":   PN = "EC54"  !CDS_PN = "EC54";
"VCCD345<8>":   PN = "EC52"  !CDS_PN = "EC52";
"VCCD345<9>":   PN = "EC50"  !CDS_PN = "EC50";
"VCCD345<10>":   PN = "EC48"  !CDS_PN = "EC48";
"VCCD345<11>":   PN = "EC46"  !CDS_PN = "EC46";
"VCCD345<12>":   PN = "DU64"  !CDS_PN = "DU64";
"VCCD345<13>":   PN = "DU62"  !CDS_PN = "DU62";
"VCCD345<14>":   PN = "DU60"  !CDS_PN = "DU60";
"VCCD345<15>":   PN = "DU58"  !CDS_PN = "DU58";
"VCCD345<16>":   PN = "DU56"  !CDS_PN = "DU56";
"VCCD345<17>":   PN = "DU54"  !CDS_PN = "DU54";
"VCCD345<18>":   PN = "DU52"  !CDS_PN = "DU52";
"VCCD345<19>":   PN = "DU50"  !CDS_PN = "DU50";
"VCCD345<20>":   PN = "DU48"  !CDS_PN = "DU48";
"VCCD345<21>":   PN = "DU46"  !CDS_PN = "DU46";
"VCCD345<22>":   PN = "DL62"  !CDS_PN = "DL62";
"VCCD345<23>":   PN = "DL60"  !CDS_PN = "DL60";
"VCCD345<24>":   PN = "DL58"  !CDS_PN = "DL58";
"VCCD345<25>":   PN = "DL56"  !CDS_PN = "DL56";
"VCCD345<26>":   PN = "DL54"  !CDS_PN = "DL54";
"VCCD345<27>":   PN = "DL52"  !CDS_PN = "DL52";
"VCCD345<28>":   PN = "DL50"  !CDS_PN = "DL50";
"VCCD345<29>":   PN = "DL48"  !CDS_PN = "DL48";
"VCCD345<30>":   PN = "DL46"  !CDS_PN = "DL46";
"VCCD345<31>":   PN = "DJ64"  !CDS_PN = "DJ64";
"VCCD345<32>":   PN = "DH63"  !CDS_PN = "DH63";
"VCCD345<33>":   PN = "DH61"  !CDS_PN = "DH61";
"VCCD345<34>":   PN = "DH59"  !CDS_PN = "DH59";
"VCCD345<35>":   PN = "DH57"  !CDS_PN = "DH57";
"VCCD345<36>":   PN = "DH55"  !CDS_PN = "DH55";
"VCCD345<37>":   PN = "DH53"  !CDS_PN = "DH53";
"VCCD345<38>":   PN = "DH51"  !CDS_PN = "DH51";
"VCCD345<39>":   PN = "DH49"  !CDS_PN = "DH49";
"VCCD345<40>":   PN = "DH47"  !CDS_PN = "DH47";
"VCCD345<41>":   PN = "DH45"  !CDS_PN = "DH45";
"VCCD345<42>":   PN = "DD45"  !CDS_PN = "DD45";
"VCCD345<43>":   PN = "DB63"  !CDS_PN = "DB63";
"VCCD345<44>":   PN = "DB61"  !CDS_PN = "DB61";
"VCCD345<45>":   PN = "DB59"  !CDS_PN = "DB59";
"VCCD345<46>":   PN = "DB57"  !CDS_PN = "DB57";
"VCCD345<47>":   PN = "DB55"  !CDS_PN = "DB55";
"VCCD345<48>":   PN = "DB53"  !CDS_PN = "DB53";
"VCCD345<49>":   PN = "EF45"  !CDS_PN = "EF45";
"VCCD345<50>":   PN = "EE44"  !CDS_PN = "EE44";
BODY = "SKX_EXT_B","I34": #LOCATION = "U5D1" !CDS_LOCATION = "U5D1" #SEC = "21" !CDS_SEC = "21";
"CD_VCC_CORE<0>":   PN = "BL14"  !CDS_PN = "BL14";
"CD_VCC_CORE<1>":   PN = "BK15"  !CDS_PN = "BK15";
"CD_VCC_CORE<2>":   PN = "BK13"  !CDS_PN = "BK13";
"CD_VCC_CORE<3>":   PN = "BJ14"  !CDS_PN = "BJ14";
"CD_VCC_CORE<4>":   PN = "BJ12"  !CDS_PN = "BJ12";
"CD_VCC_CORE<5>":   PN = "BH13"  !CDS_PN = "BH13";
"CD_VCC_CORE<6>":   PN = "BG14"  !CDS_PN = "BG14";
"CD_VCC_CORE<7>":   PN = "BG12"  !CDS_PN = "BG12";
"CD_VCC_CORE<8>":   PN = "BF13"  !CDS_PN = "BF13";
"CD_VCC_CORE<9>":   PN = "BF11"  !CDS_PN = "BF11";
"CD_VCC_CORE<10>":   PN = "BE14"  !CDS_PN = "BE14";
"CD_VCC_CORE<11>":   PN = "BE12"  !CDS_PN = "BE12";
"CD_VCC_CORE<12>":   PN = "BD13"  !CDS_PN = "BD13";
"CD_VCCIN<0>":   PN = "BT27"  !CDS_PN = "BT27";
"CD_VCCIN<1>":   PN = "BU26"  !CDS_PN = "BU26";
"CD_VCCIN<2>":   PN = "BV27"  !CDS_PN = "BV27";
"CD_VCCIN<3>":   PN = "BY27"  !CDS_PN = "BY27";
"CD_VCCP<0>":   PN = "BV15"  !CDS_PN = "BV15";
"CD_VCCP<1>":   PN = "BV13"  !CDS_PN = "BV13";
"CD_VCCP<2>":   PN = "BV11"  !CDS_PN = "BV11";
"CD_VCCP<3>":   PN = "BU14"  !CDS_PN = "BU14";
"CD_VCCP<4>":   PN = "BU12"  !CDS_PN = "BU12";
"CD_VCCP<5>":   PN = "BT15"  !CDS_PN = "BT15";
"CD_VCCP<6>":   PN = "BT13"  !CDS_PN = "BT13";
"CD_VCCP<7>":   PN = "BT11"  !CDS_PN = "BT11";
"CD_VCCP<8>":   PN = "BR14"  !CDS_PN = "BR14";
"CD_VCCP<9>":   PN = "BR12"  !CDS_PN = "BR12";
"CD_VCCP<10>":   PN = "BP15"  !CDS_PN = "BP15";
"CD_VCCP<11>":   PN = "BP13"  !CDS_PN = "BP13";
"CD_VCCP<12>":   PN = "BP11"  !CDS_PN = "BP11";
"CD_VCCP<13>":   PN = "BN14"  !CDS_PN = "BN14";
"CD_VCCP<14>":   PN = "BN12"  !CDS_PN = "BN12";
"CD_VCCP<15>":   PN = "BM11"  !CDS_PN = "BM11";
"CD_VPP<0>":   PN = "B11"  !CDS_PN = "B11";
"CD_VPP<1>":   PN = "A12"  !CDS_PN = "A12";
"CD_VPP<2>":   PN = "A10"  !CDS_PN = "A10";
"CD_VPP<3>":   PN = "A8"  !CDS_PN = "A8";
"VCC33":   PN = "CY55"  !CDS_PN = "CY55";
"VCCIO<20>":   PN = "CM15"  !CDS_PN = "CM15";
"VCCIO<21>":   PN = "CL12"  !CDS_PN = "CL12";
"VCCIO<22>":   PN = "CK5"  !CDS_PN = "CK5";
"VCCIO<23>":   PN = "CV7"  !CDS_PN = "CV7";
"VCCIO<24>":   PN = "CH9"  !CDS_PN = "CH9";
"VCCIO<25>":   PN = "D7"  !CDS_PN = "D7";
"VCCIO<26>":   PN = "CE18"  !CDS_PN = "CE18";
"VCCIO<27>":   PN = "CD9"  !CDS_PN = "CD9";
"VCCIO<28>":   PN = "CB17"  !CDS_PN = "CB17";
"VCCIO<29>":   PN = "CB13"  !CDS_PN = "CB13";
"VCCIO<30>":   PN = "BP25"  !CDS_PN = "BP25";
"VCCIO<31>":   PN = "BJ24"  !CDS_PN = "BJ24";
"VCCIO<32>":   PN = "BF23"  !CDS_PN = "BF23";
"VCCIO<33>":   PN = "DA14"  !CDS_PN = "DA14";
"VCCIO<34>":   PN = "BB5"  !CDS_PN = "BB5";
"VCCIO<35>":   PN = "BA24"  !CDS_PN = "BA24";
"VCCIO<36>":   PN = "AY11"  !CDS_PN = "AY11";
"VCCIO<37>":   PN = "AW6"  !CDS_PN = "AW6";
"VCCIO<38>":   PN = "AT11"  !CDS_PN = "AT11";
"VCCIO<39>":   PN = "DD7"  !CDS_PN = "DD7";
"VCCIO<40>":   PN = "AN10"  !CDS_PN = "AN10";
"VCCIO<41>":   PN = "DF13"  !CDS_PN = "DF13";
"VCCIO<42>":   PN = "AH9"  !CDS_PN = "AH9";
"VCCIO<43>":   PN = "AC4"  !CDS_PN = "AC4";
"VCCIO<44>":   PN = "AC20"  !CDS_PN = "AC20";
"VCCIO<45>":   PN = "AA10"  !CDS_PN = "AA10";
"VCCIO<46>":   PN = "W6"  !CDS_PN = "W6";
"VCCIO<47>":   PN = "W4"  !CDS_PN = "W4";
"VCCIO<48>":   PN = "DF21"  !CDS_PN = "DF21";
"VCCIO<49>":   PN = "U14"  !CDS_PN = "U14";
"VCCIO<50>":   PN = "T3"  !CDS_PN = "T3";
"VCCIO<51>":   PN = "P5"  !CDS_PN = "P5";
"VCCIO<52>":   PN = "M21"  !CDS_PN = "M21";
"VCCIO<53>":   PN = "M11"  !CDS_PN = "M11";
"VCCIO<54>":   PN = "DG8"  !CDS_PN = "DG8";
"VCCIO<55>":   PN = "DH7"  !CDS_PN = "DH7";
"VCCIO<56>":   PN = "L16"  !CDS_PN = "L16";
"VCCIO<57>":   PN = "L14"  !CDS_PN = "L14";
"VCCIO<58>":   PN = "J10"  !CDS_PN = "J10";
"VCCIO<59>":   PN = "H13"  !CDS_PN = "H13";
"VCCIO<60>":   PN = "DJ16"  !CDS_PN = "DJ16";
"VCCIO<61>":   PN = "DM17"  !CDS_PN = "DM17";
"VCCIO<62>":   PN = "DN8"  !CDS_PN = "DN8";
"VCCIO<63>":   PN = "DP19"  !CDS_PN = "DP19";
"VCCIO<64>":   PN = "DR10"  !CDS_PN = "DR10";
"VCCIO<65>":   PN = "DR2"  !CDS_PN = "DR2";
"VCCIO<66>":   PN = "DU20"  !CDS_PN = "DU20";
"VCCIO<67>":   PN = "EA12"  !CDS_PN = "EA12";
"VCCIO<68>":   PN = "EB15"  !CDS_PN = "EB15";
"VCCIO<69>":   PN = "J2"  !CDS_PN = "J2";
"VCCIO<70>":   PN = "K15"  !CDS_PN = "K15";
"VCCIO<71>":   PN = "M7"  !CDS_PN = "M7";
"VCCIO<72>":   PN = "M9"  !CDS_PN = "M9";
"VCCIO<73>":   PN = "N18"  !CDS_PN = "N18";
"VCCIO<74>":   PN = "W10"  !CDS_PN = "W10";
"VCCIO<75>":   PN = "BC26"  !CDS_PN = "BC26";
"VCCIO<76>":   PN = "BB27"  !CDS_PN = "BB27";
"VCCIO<77>":   PN = "BA26"  !CDS_PN = "BA26";
"VCCIO<78>":   PN = "AY27"  !CDS_PN = "AY27";
"VCCIO<79>":   PN = "AW26"  !CDS_PN = "AW26";
"VCCIO<80>":   PN = "AV27"  !CDS_PN = "AV27";
"VCCIO<81>":   PN = "CF27"  !CDS_PN = "CF27";
"VCCIO<82>":   PN = "CD27"  !CDS_PN = "CD27";
"VCCIO<83>":   PN = "CC26"  !CDS_PN = "CC26";
"VCCIO<84>":   PN = "CJ28"  !CDS_PN = "CJ28";
"VCCIO<85>":   PN = "CH27"  !CDS_PN = "CH27";
"VCCIO<86>":   PN = "BM27"  !CDS_PN = "BM27";
"VCCIO<87>":   PN = "BL26"  !CDS_PN = "BL26";
"VCCIO<88>":   PN = "BK27"  !CDS_PN = "BK27";
"VCCIO<89>":   PN = "BK25"  !CDS_PN = "BK25";
"VCCIO<90>":   PN = "BJ26"  !CDS_PN = "BJ26";
"VCCIO<91>":   PN = "BH27"  !CDS_PN = "BH27";
"VCCIO<92>":   PN = "BH25"  !CDS_PN = "BH25";
"VCCIO<93>":   PN = "BG26"  !CDS_PN = "BG26";
"VCCIO<94>":   PN = "BF27"  !CDS_PN = "BF27";
"VCCIO<95>":   PN = "AE36"  !CDS_PN = "AE36";
"VCCIO<96>":   PN = "AD37"  !CDS_PN = "AD37";
"VCCIO<97>":   PN = "AC36"  !CDS_PN = "AC36";
"VCCIO<98>":   PN = "AF35"  !CDS_PN = "AF35";
"VCCIO<99>":   PN = "AD35"  !CDS_PN = "AD35";
"VCCIO<100>":   PN = "AE34"  !CDS_PN = "AE34";
"VCCIO<101>":   PN = "AG34"  !CDS_PN = "AG34";
"VCCIO<102>":   PN = "AM29"  !CDS_PN = "AM29";
"VCCIO<103>":   PN = "AL28"  !CDS_PN = "AL28";
"VCCIO<104>":   PN = "AR28"  !CDS_PN = "AR28";
"VCCSA<0>":   PN = "CJ66"  !CDS_PN = "CJ66";
"VCCSA<1>":   PN = "CJ64"  !CDS_PN = "CJ64";
"VCCSA<2>":   PN = "CH75"  !CDS_PN = "CH75";
"VCCSA<3>":   PN = "CH65"  !CDS_PN = "CH65";
"VCCSA<4>":   PN = "CG74"  !CDS_PN = "CG74";
"VCCSA<5>":   PN = "CG66"  !CDS_PN = "CG66";
"VCCSA<6>":   PN = "CG64"  !CDS_PN = "CG64";
"VCCSA<7>":   PN = "CF75"  !CDS_PN = "CF75";
"VCCSA<8>":   PN = "CF73"  !CDS_PN = "CF73";
"VCCSA<9>":   PN = "CF67"  !CDS_PN = "CF67";
"VCCSA<10>":   PN = "CF65"  !CDS_PN = "CF65";
"VCCSA<11>":   PN = "CE74"  !CDS_PN = "CE74";
"VCCSA<12>":   PN = "CE72"  !CDS_PN = "CE72";
"VCCSA<13>":   PN = "CE68"  !CDS_PN = "CE68";
"VCCSA<14>":   PN = "CE66"  !CDS_PN = "CE66";
"VCCSA<15>":   PN = "CE64"  !CDS_PN = "CE64";
"VCCSA<16>":   PN = "CD71"  !CDS_PN = "CD71";
"VCCSA<17>":   PN = "CD69"  !CDS_PN = "CD69";
"VCCSA<18>":   PN = "CD67"  !CDS_PN = "CD67";
"VCCSA<19>":   PN = "CD65"  !CDS_PN = "CD65";
"VCCSA<20>":   PN = "CC70"  !CDS_PN = "CC70";
"VCCSA<21>":   PN = "CC68"  !CDS_PN = "CC68";
"VCCSA<22>":   PN = "CC66"  !CDS_PN = "CC66";
"VCCSA<23>":   PN = "CB69"  !CDS_PN = "CB69";
"VCCSA<24>":   PN = "CB67"  !CDS_PN = "CB67";
"VCCSA<25>":   PN = "CB65"  !CDS_PN = "CB65";
DRAWING = "@baseboard_fab2_lib.baseboard_fab2(sch_1):page39";
BODY = "SKX_EXT_B","I127": #LOCATION = "U5D1" !CDS_LOCATION = "U5D1" #SEC = "22" !CDS_SEC = "22";
"CD_VCC_CORE_SENSE":   PN = "BN16"  !CDS_PN = "BN16";
"CD_VCCP_SENSE<0>":   PN = "BU16"  !CDS_PN = "BU16";
"CD_VCCP_SENSE<1>":   PN = "BT17"  !CDS_PN = "BT17";
"CD_VSS_VCC_CORE_SENSE":   PN = "BL16"  !CDS_PN = "BL16";
"RSVD<0>":   PN = "EF83"  !CDS_PN = "EF83";
"RSVD<1>":   PN = "EF81"  !CDS_PN = "EF81";
"RSVD<2>":   PN = "EF77"  !CDS_PN = "EF77";
"RSVD<3>":   PN = "EF47"  !CDS_PN = "EF47";
"RSVD<4>":   PN = "EE84"  !CDS_PN = "EE84";
"RSVD<5>":   PN = "EE82"  !CDS_PN = "EE82";
"RSVD<6>":   PN = "EE6"  !CDS_PN = "EE6";
"RSVD<7>":   PN = "EE46"  !CDS_PN = "EE46";
"RSVD<8>":   PN = "EE16"  !CDS_PN = "EE16";
"RSVD<9>":   PN = "ED83"  !CDS_PN = "ED83";
"RSVD<10>":   PN = "ED5"  !CDS_PN = "ED5";
"RSVD<11>":   PN = "ED45"  !CDS_PN = "ED45";
"RSVD<12>":   PN = "EC84"  !CDS_PN = "EC84";
"RSVD<13>":   PN = "EC44"  !CDS_PN = "EC44";
"RSVD<14>":   PN = "EC4"  !CDS_PN = "EC4";
"RSVD<15>":   PN = "EC16"  !CDS_PN = "EC16";
"RSVD<16>":   PN = "EB85"  !CDS_PN = "EB85";
"RSVD<17>":   PN = "EB5"  !CDS_PN = "EB5";
"RSVD<18>":   PN = "EB3"  !CDS_PN = "EB3";
"RSVD<19>":   PN = "EA44"  !CDS_PN = "EA44";
"RSVD<20>":   PN = "EA4"  !CDS_PN = "EA4";
"RSVD<21>":   PN = "DY3"  !CDS_PN = "DY3";
"RSVD<22>":   PN = "DW46"  !CDS_PN = "DW46";
"RSVD<23>":   PN = "DW44"  !CDS_PN = "DW44";
"RSVD<24>":   PN = "DV71"  !CDS_PN = "DV71";
"RSVD<25>":   PN = "DV61"  !CDS_PN = "DV61";
"RSVD<26>":   PN = "DU44"  !CDS_PN = "DU44";
"RSVD<27>":   PN = "DT71"  !CDS_PN = "DT71";
"RSVD<28>":   PN = "DR44"  !CDS_PN = "DR44";
"RSVD<29>":   PN = "DP65"  !CDS_PN = "DP65";
"RSVD<30>":   PN = "DP17"  !CDS_PN = "DP17";
"RSVD<31>":   PN = "DN66"  !CDS_PN = "DN66";
"RSVD<32>":   PN = "DN62"  !CDS_PN = "DN62";
"RSVD<33>":   PN = "DM67"  !CDS_PN = "DM67";
"RSVD<34>":   PN = "DL66"  !CDS_PN = "DL66";
"RSVD<35>":   PN = "DL38"  !CDS_PN = "DL38";
"RSVD<36>":   PN = "DK67"  !CDS_PN = "DK67";
"RSVD<37>":   PN = "DK65"  !CDS_PN = "DK65";
"RSVD<38>":   PN = "DK37"  !CDS_PN = "DK37";
"RSVD<39>":   PN = "DK15"  !CDS_PN = "DK15";
"RSVD<40>":   PN = "DJ66"  !CDS_PN = "DJ66";
"RSVD<41>":   PN = "DJ36"  !CDS_PN = "DJ36";
"RSVD<42>":   PN = "DH65"  !CDS_PN = "DH65";
"RSVD<43>":   PN = "DG64"  !CDS_PN = "DG64";
"RSVD<44>":   PN = "DG36"  !CDS_PN = "DG36";
"RSVD<45>":   PN = "DD51"  !CDS_PN = "DD51";
"RSVD<46>":   PN = "DC52"  !CDS_PN = "DC52";
"RSVD<47>":   PN = "DC46"  !CDS_PN = "DC46";
"RSVD<48>":   PN = "DA56"  !CDS_PN = "DA56";
"RSVD<49>":   PN = "DA54"  !CDS_PN = "DA54";
"RSVD<50>":   PN = "DA52"  !CDS_PN = "DA52";
"RSVD<51>":   PN = "DA40"  !CDS_PN = "DA40";
"RSVD<52>":   PN = "DA24"  !CDS_PN = "DA24";
"RSVD<53>":   PN = "CY73"  !CDS_PN = "CY73";
"RSVD<54>":   PN = "CY63"  !CDS_PN = "CY63";
"RSVD<55>":   PN = "CY57"  !CDS_PN = "CY57";
"RSVD<56>":   PN = "CY53"  !CDS_PN = "CY53";
"RSVD<57>":   PN = "CY39"  !CDS_PN = "CY39";
"RSVD<58>":   PN = "CY25"  !CDS_PN = "CY25";
"RSVD<59>":   PN = "CY23"  !CDS_PN = "CY23";
"RSVD<60>":   PN = "CW62"  !CDS_PN = "CW62";
"RSVD<61>":   PN = "CW60"  !CDS_PN = "CW60";
"RSVD<62>":   PN = "CW24"  !CDS_PN = "CW24";
"RSVD<63>":   PN = "CW22"  !CDS_PN = "CW22";
"RSVD<64>":   PN = "CV69"  !CDS_PN = "CV69";
"RSVD<65>":   PN = "CV23"  !CDS_PN = "CV23";
"RSVD<66>":   PN = "CU60"  !CDS_PN = "CU60";
"RSVD<67>":   PN = "CU6"  !CDS_PN = "CU6";
"RSVD<68>":   PN = "CU24"  !CDS_PN = "CU24";
"RSVD<69>":   PN = "CT69"  !CDS_PN = "CT69";
"RSVD<70>":   PN = "CT5"  !CDS_PN = "CT5";
"RSVD<71>":   PN = "CT23"  !CDS_PN = "CT23";
"RSVD<72>":   PN = "CR60"  !CDS_PN = "CR60";
"RSVD<73>":   PN = "CP31"  !CDS_PN = "CP31";
"RSVD<74>":   PN = "CP23"  !CDS_PN = "CP23";
"RSVD<75>":   PN = "CN28"  !CDS_PN = "CN28";
"RSVD<76>":   PN = "CN24"  !CDS_PN = "CN24";
"RSVD<77>":   PN = "CN22"  !CDS_PN = "CN22";
"RSVD<78>":   PN = "CM25"  !CDS_PN = "CM25";
"RSVD<79>":   PN = "CM23"  !CDS_PN = "CM23";
"RSVD<80>":   PN = "CL26"  !CDS_PN = "CL26";
"VCCIO<0>":   PN = "EE10"  !CDS_PN = "EE10";
"VCCIO<1>":   PN = "AE10"  !CDS_PN = "AE10";
"VCCIO<2>":   PN = "AF5"  !CDS_PN = "AF5";
"VCCIO<3>":   PN = "DV11"  !CDS_PN = "DV11";
"VCCIO<4>":   PN = "AM5"  !CDS_PN = "AM5";
"VCCIO<5>":   PN = "AT5"  !CDS_PN = "AT5";
"VCCIO<6>":   PN = "AT7"  !CDS_PN = "AT7";
"VCCIO<7>":   PN = "BE24"  !CDS_PN = "BE24";
"VCCIO<8>":   PN = "DK21"  !CDS_PN = "DK21";
"VCCIO<9>":   PN = "CF5"  !CDS_PN = "CF5";
"VCCIO<10>":   PN = "CG14"  !CDS_PN = "CG14";
"VCCIO<11>":   PN = "CL20"  !CDS_PN = "CL20";
"VCCIO<12>":   PN = "CP13"  !CDS_PN = "CP13";
"VCCIO<13>":   PN = "DE14"  !CDS_PN = "DE14";
"VCCIO<14>":   PN = "DC18"  !CDS_PN = "DC18";
"VCCIO<15>":   PN = "CY17"  !CDS_PN = "CY17";
"VCCIO<16>":   PN = "CU18"  !CDS_PN = "CU18";
"VCCIO<17>":   PN = "CV21"  !CDS_PN = "CV21";
"VCCIO<18>":   PN = "CU12"  !CDS_PN = "CU12";
"VCCIO<19>":   PN = "CN6"  !CDS_PN = "CN6";
"VCCIO_SENSE":   PN = "BH5"  !CDS_PN = "BH5";
"VCCSA_SENSE":   PN = "CE76"  !CDS_PN = "CE76";
"VSS_VCCIO_SENSE":   PN = "BF5"  !CDS_PN = "BF5";
"VSS_VCCSA_SENSE":   PN = "CG76"  !CDS_PN = "CG76";
DRAWING = "@baseboard_fab2_lib.baseboard_fab2(sch_1):page40";
BODY = "SKX_EXT_B","I20": #LOCATION = "U5D1" !CDS_LOCATION = "U5D1" #SEC = "23" !CDS_SEC = "23";
"VSS<1094>":   PN = "J74"  !CDS_PN = "J74";
"VSS<1095>":   PN = "J72"  !CDS_PN = "J72";
"VSS<1096>":   PN = "J40"  !CDS_PN = "J40";
"VSS<1097>":   PN = "J38"  !CDS_PN = "J38";
"VSS<1098>":   PN = "J34"  !CDS_PN = "J34";
"VSS<1099>":   PN = "J32"  !CDS_PN = "J32";
"VSS<1100>":   PN = "J28"  !CDS_PN = "J28";
"VSS<1101>":   PN = "J26"  !CDS_PN = "J26";
"VSS<1102>":   PN = "J22"  !CDS_PN = "J22";
"VSS<1103>":   PN = "J14"  !CDS_PN = "J14";
"VSS<1104>":   PN = "J12"  !CDS_PN = "J12";
"VSS<1105>":   PN = "J4"  !CDS_PN = "J4";
"VSS<1106>":   PN = "DN44"  !CDS_PN = "DN44";
"VSS<1107>":   PN = "H75"  !CDS_PN = "H75";
"VSS<1108>":   PN = "H71"  !CDS_PN = "H71";
"VSS<1109>":   PN = "H65"  !CDS_PN = "H65";
"VSS<1110>":   PN = "H41"  !CDS_PN = "H41";
"VSS<1111>":   PN = "H39"  !CDS_PN = "H39";
"VSS<1112>":   PN = "H37"  !CDS_PN = "H37";
"VSS<1113>":   PN = "H35"  !CDS_PN = "H35";
"VSS<1114>":   PN = "H33"  !CDS_PN = "H33";
"VSS<1115>":   PN = "H31"  !CDS_PN = "H31";
"VSS<1116>":   PN = "H29"  !CDS_PN = "H29";
"VSS<1117>":   PN = "H27"  !CDS_PN = "H27";
"VSS<1118>":   PN = "H25"  !CDS_PN = "H25";
"VSS<1119>":   PN = "H11"  !CDS_PN = "H11";
"VSS<1120>":   PN = "H3"  !CDS_PN = "H3";
"VSS<1121>":   PN = "G82"  !CDS_PN = "G82";
"VSS<1122>":   PN = "G80"  !CDS_PN = "G80";
"VSS<1123>":   PN = "G78"  !CDS_PN = "G78";
"VSS<1124>":   PN = "G76"  !CDS_PN = "G76";
"VSS<1125>":   PN = "G70"  !CDS_PN = "G70";
"VSS<1126>":   PN = "G66"  !CDS_PN = "G66";
"VSS<1127>":   PN = "G42"  !CDS_PN = "G42";
"VSS<1128>":   PN = "G38"  !CDS_PN = "G38";
"VSS<1129>":   PN = "G36"  !CDS_PN = "G36";
"VSS<1130>":   PN = "G32"  !CDS_PN = "G32";
"VSS<1131>":   PN = "G30"  !CDS_PN = "G30";
"VSS<1132>":   PN = "G26"  !CDS_PN = "G26";
"VSS<1133>":   PN = "G24"  !CDS_PN = "G24";
"VSS<1134>":   PN = "G22"  !CDS_PN = "G22";
"VSS<1135>":   PN = "G8"  !CDS_PN = "G8";
"VSS<1136>":   PN = "G4"  !CDS_PN = "G4";
"VSS<1137>":   PN = "F69"  !CDS_PN = "F69";
"VSS<1138>":   PN = "F67"  !CDS_PN = "F67";
"VSS<1139>":   PN = "F43"  !CDS_PN = "F43";
"VSS<1140>":   PN = "F37"  !CDS_PN = "F37";
"VSS<1141>":   PN = "F31"  !CDS_PN = "F31";
"VSS<1142>":   PN = "F25"  !CDS_PN = "F25";
"VSS<1143>":   PN = "F19"  !CDS_PN = "F19";
"VSS<1144>":   PN = "F17"  !CDS_PN = "F17";
"VSS<1145>":   PN = "F5"  !CDS_PN = "F5";
"VSS<1146>":   PN = "E76"  !CDS_PN = "E76";
"VSS<1147>":   PN = "E74"  !CDS_PN = "E74";
"VSS<1148>":   PN = "E72"  !CDS_PN = "E72";
"VSS<1149>":   PN = "E22"  !CDS_PN = "E22";
"VSS<1150>":   PN = "E20"  !CDS_PN = "E20";
"VSS<1151>":   PN = "E18"  !CDS_PN = "E18";
"VSS<1152>":   PN = "E16"  !CDS_PN = "E16";
"VSS<1153>":   PN = "E8"  !CDS_PN = "E8";
"VSS<1154>":   PN = "E6"  !CDS_PN = "E6";
"VSS<1155>":   PN = "D77"  !CDS_PN = "D77";
"VSS<1156>":   PN = "D43"  !CDS_PN = "D43";
"VSS<1157>":   PN = "D41"  !CDS_PN = "D41";
"VSS<1158>":   PN = "D39"  !CDS_PN = "D39";
"VSS<1159>":   PN = "D37"  !CDS_PN = "D37";
"VSS<1160>":   PN = "D35"  !CDS_PN = "D35";
"VSS<1161>":   PN = "D33"  !CDS_PN = "D33";
"VSS<1162>":   PN = "D31"  !CDS_PN = "D31";
"VSS<1163>":   PN = "D29"  !CDS_PN = "D29";
"VSS<1164>":   PN = "D27"  !CDS_PN = "D27";
"VSS<1165>":   PN = "D25"  !CDS_PN = "D25";
"VSS<1166>":   PN = "D13"  !CDS_PN = "D13";
"VSS<1167>":   PN = "D11"  !CDS_PN = "D11";
"VSS<1168>":   PN = "CM27"  !CDS_PN = "CM27";
"VSS<1169>":   PN = "C78"  !CDS_PN = "C78";
"VSS<1170>":   PN = "C76"  !CDS_PN = "C76";
"VSS<1171>":   PN = "C16"  !CDS_PN = "C16";
"VSS<1172>":   PN = "C14"  !CDS_PN = "C14";
"VSS<1173>":   PN = "C12"  !CDS_PN = "C12";
"VSS<1174>":   PN = "C10"  !CDS_PN = "C10";
"VSS<1175>":   PN = "C8"  !CDS_PN = "C8";
"VSS<1176>":   PN = "B75"  !CDS_PN = "B75";
"VSS<1177>":   PN = "B71"  !CDS_PN = "B71";
"VSS<1178>":   PN = "B37"  !CDS_PN = "B37";
"VSS<1179>":   PN = "B31"  !CDS_PN = "B31";
"VSS<1180>":   PN = "B25"  !CDS_PN = "B25";
"VSS<1181>":   PN = "A38"  !CDS_PN = "A38";
"VSS<1182>":   PN = "A36"  !CDS_PN = "A36";
"VSS<1183>":   PN = "A32"  !CDS_PN = "A32";
"VSS<1184>":   PN = "A30"  !CDS_PN = "A30";
"VSS<1185>":   PN = "A26"  !CDS_PN = "A26";
"VSS<1186>":   PN = "AC58"  !CDS_PN = "AC58";
"VSS<1187>":   PN = "AC60"  !CDS_PN = "AC60";
"VSS<1188>":   PN = "AC62"  !CDS_PN = "AC62";
"VSS<1189>":   PN = "AJ4"  !CDS_PN = "AJ4";
"VSS<1190>":   PN = "AR6"  !CDS_PN = "AR6";
"VSS<1191>":   PN = "CG6"  !CDS_PN = "CG6";
"VSS<1192>":   PN = "CW6"  !CDS_PN = "CW6";
"VSS<1193>":   PN = "DE48"  !CDS_PN = "DE48";
"VSS<1194>":   PN = "DE50"  !CDS_PN = "DE50";
"VSS<1195>":   PN = "DE52"  !CDS_PN = "DE52";
"VSS<1196>":   PN = "DE54"  !CDS_PN = "DE54";
"VSS<1197>":   PN = "DE56"  !CDS_PN = "DE56";
"VSS<1198>":   PN = "DE58"  !CDS_PN = "DE58";
"VSS<1199>":   PN = "DE60"  !CDS_PN = "DE60";
"VSS<1200>":   PN = "DE62"  !CDS_PN = "DE62";
"VSS<1201>":   PN = "DL8"  !CDS_PN = "DL8";
"VSS<1202>":   PN = "DN18"  !CDS_PN = "DN18";
"VSS<1203>":   PN = "DP45"  !CDS_PN = "DP45";
"VSS<1204>":   PN = "DP47"  !CDS_PN = "DP47";
"VSS<1205>":   PN = "DP49"  !CDS_PN = "DP49";
"VSS<1206>":   PN = "DP51"  !CDS_PN = "DP51";
"VSS<1207>":   PN = "DP53"  !CDS_PN = "DP53";
"VSS<1208>":   PN = "DP55"  !CDS_PN = "DP55";
"VSS<1209>":   PN = "DP57"  !CDS_PN = "DP57";
"VSS<1210>":   PN = "DP59"  !CDS_PN = "DP59";
"VSS<1211>":   PN = "DP61"  !CDS_PN = "DP61";
"VSS<1212>":   PN = "DP63"  !CDS_PN = "DP63";
"VSS<1213>":   PN = "DP9"  !CDS_PN = "DP9";
"VSS<1214>":   PN = "DV19"  !CDS_PN = "DV19";
"VSS<1215>":   PN = "DY45"  !CDS_PN = "DY45";
"VSS<1216>":   PN = "DY47"  !CDS_PN = "DY47";
"VSS<1217>":   PN = "DY49"  !CDS_PN = "DY49";
"VSS<1218>":   PN = "DY51"  !CDS_PN = "DY51";
"VSS<1219>":   PN = "DY53"  !CDS_PN = "DY53";
"VSS<1220>":   PN = "DY55"  !CDS_PN = "DY55";
"VSS<1221>":   PN = "DY57"  !CDS_PN = "DY57";
"VSS<1222>":   PN = "DY59"  !CDS_PN = "DY59";
"VSS<1223>":   PN = "DY61"  !CDS_PN = "DY61";
"VSS<1224>":   PN = "DY63"  !CDS_PN = "DY63";
"VSS<1225>":   PN = "EA14"  !CDS_PN = "EA14";
"VSS<1226>":   PN = "L8"  !CDS_PN = "L8";
"VSS<1227>":   PN = "V11"  !CDS_PN = "V11";
"VSS<1228>":   PN = "E66"  !CDS_PN = "E66";
"VSS<1229>":   PN = "ED69"  !CDS_PN = "ED69";
"VSS<1230>":   PN = "EE80"  !CDS_PN = "EE80";
"VSS<1231>":   PN = "EE8"  !CDS_PN = "EE8";
"VSS<1232>":   PN = "EE40"  !CDS_PN = "EE40";
"VSS<1233>":   PN = "ED81"  !CDS_PN = "ED81";
"VSS<1234>":   PN = "ED7"  !CDS_PN = "ED7";
"VSS<1235>":   PN = "ED41"  !CDS_PN = "ED41";
"VSS<1236>":   PN = "EC82"  !CDS_PN = "EC82";
"VSS<1237>":   PN = "EC6"  !CDS_PN = "EC6";
"VSS<1238>":   PN = "EC42"  !CDS_PN = "EC42";
"VSS<1239>":   PN = "DW2"  !CDS_PN = "DW2";
"VSS<1240>":   PN = "EB83"  !CDS_PN = "EB83";
"VSS<1241>":   PN = "EA84"  !CDS_PN = "EA84";
"VSS<1242>":   PN = "DY85"  !CDS_PN = "DY85";
"VSS<1243>":   PN = "J86"  !CDS_PN = "J86";
"VSS<1244>":   PN = "E82"  !CDS_PN = "E82";
"VSS<1245>":   PN = "D81"  !CDS_PN = "D81";
"VSS<1246>":   PN = "D3"  !CDS_PN = "D3";
"VSS<1247>":   PN = "C80"  !CDS_PN = "C80";
"VSS<1248>":   PN = "C4"  !CDS_PN = "C4";
"VSS<1249>":   PN = "B79"  !CDS_PN = "B79";
"VSS<1250>":   PN = "B5"  !CDS_PN = "B5";
"VSS<1251>":   PN = "B43"  !CDS_PN = "B43";
"VSS<1252>":   PN = "A42"  !CDS_PN = "A42";
"VSS<1253>":   PN = "B9"  !CDS_PN = "B9";
BODY = "SKX_EXT_B","I21": #LOCATION = "U5D1" !CDS_LOCATION = "U5D1" #SEC = "24" !CDS_SEC = "24";
"VSS<934>":   PN = "AA16"  !CDS_PN = "AA16";
"VSS<935>":   PN = "AA4"  !CDS_PN = "AA4";
"VSS<936>":   PN = "Y85"  !CDS_PN = "Y85";
"VSS<937>":   PN = "Y83"  !CDS_PN = "Y83";
"VSS<938>":   PN = "Y81"  !CDS_PN = "Y81";
"VSS<939>":   PN = "Y79"  !CDS_PN = "Y79";
"VSS<940>":   PN = "Y73"  !CDS_PN = "Y73";
"VSS<941>":   PN = "Y71"  !CDS_PN = "Y71";
"VSS<942>":   PN = "Y9"  !CDS_PN = "Y9";
"VSS<943>":   PN = "Y7"  !CDS_PN = "Y7";
"VSS<944>":   PN = "Y67"  !CDS_PN = "Y67";
"VSS<945>":   PN = "Y5"  !CDS_PN = "Y5";
"VSS<946>":   PN = "Y17"  !CDS_PN = "Y17";
"VSS<947>":   PN = "Y15"  !CDS_PN = "Y15";
"VSS<948>":   PN = "W82"  !CDS_PN = "W82";
"VSS<949>":   PN = "W78"  !CDS_PN = "W78";
"VSS<950>":   PN = "W74"  !CDS_PN = "W74";
"VSS<951>":   PN = "W68"  !CDS_PN = "W68";
"VSS<952>":   PN = "W42"  !CDS_PN = "W42";
"VSS<953>":   PN = "W40"  !CDS_PN = "W40";
"VSS<954>":   PN = "W38"  !CDS_PN = "W38";
"VSS<955>":   PN = "W36"  !CDS_PN = "W36";
"VSS<956>":   PN = "W34"  !CDS_PN = "W34";
"VSS<957>":   PN = "W32"  !CDS_PN = "W32";
"VSS<958>":   PN = "W30"  !CDS_PN = "W30";
"VSS<959>":   PN = "W28"  !CDS_PN = "W28";
"VSS<960>":   PN = "W26"  !CDS_PN = "W26";
"VSS<961>":   PN = "W24"  !CDS_PN = "W24";
"VSS<962>":   PN = "W22"  !CDS_PN = "W22";
"VSS<963>":   PN = "W12"  !CDS_PN = "W12";
"VSS<964>":   PN = "AC56"  !CDS_PN = "AC56";
"VSS<965>":   PN = "W8"  !CDS_PN = "W8";
"VSS<966>":   PN = "V83"  !CDS_PN = "V83";
"VSS<967>":   PN = "V77"  !CDS_PN = "V77";
"VSS<968>":   PN = "V75"  !CDS_PN = "V75";
"VSS<969>":   PN = "V73"  !CDS_PN = "V73";
"VSS<970>":   PN = "V43"  !CDS_PN = "V43";
"VSS<971>":   PN = "V23"  !CDS_PN = "V23";
"VSS<972>":   PN = "V21"  !CDS_PN = "V21";
"VSS<973>":   PN = "V15"  !CDS_PN = "V15";
"VSS<974>":   PN = "V13"  !CDS_PN = "V13";
"VSS<975>":   PN = "V9"  !CDS_PN = "V9";
"VSS<976>":   PN = "V5"  !CDS_PN = "V5";
"VSS<977>":   PN = "V1"  !CDS_PN = "V1";
"VSS<978>":   PN = "U86"  !CDS_PN = "U86";
"VSS<979>":   PN = "U80"  !CDS_PN = "U80";
"VSS<980>":   PN = "U78"  !CDS_PN = "U78";
"VSS<981>":   PN = "U76"  !CDS_PN = "U76";
"VSS<982>":   PN = "U74"  !CDS_PN = "U74";
"VSS<983>":   PN = "U70"  !CDS_PN = "U70";
"VSS<984>":   PN = "U68"  !CDS_PN = "U68";
"VSS<985>":   PN = "U42"  !CDS_PN = "U42";
"VSS<986>":   PN = "U36"  !CDS_PN = "U36";
"VSS<987>":   PN = "U30"  !CDS_PN = "U30";
"VSS<988>":   PN = "U24"  !CDS_PN = "U24";
"VSS<989>":   PN = "U22"  !CDS_PN = "U22";
"VSS<990>":   PN = "U20"  !CDS_PN = "U20";
"VSS<991>":   PN = "U6"  !CDS_PN = "U6";
"VSS<992>":   PN = "U4"  !CDS_PN = "U4";
"VSS<993>":   PN = "U2"  !CDS_PN = "U2";
"VSS<994>":   PN = "T85"  !CDS_PN = "T85";
"VSS<995>":   PN = "T83"  !CDS_PN = "T83";
"VSS<996>":   PN = "T77"  !CDS_PN = "T77";
"VSS<997>":   PN = "T73"  !CDS_PN = "T73";
"VSS<998>":   PN = "T65"  !CDS_PN = "T65";
"VSS<999>":   PN = "T41"  !CDS_PN = "T41";
"VSS<1000>":   PN = "T37"  !CDS_PN = "T37";
"VSS<1001>":   PN = "T35"  !CDS_PN = "T35";
"VSS<1002>":   PN = "T31"  !CDS_PN = "T31";
"VSS<1003>":   PN = "T29"  !CDS_PN = "T29";
"VSS<1004>":   PN = "T25"  !CDS_PN = "T25";
"VSS<1005>":   PN = "T17"  !CDS_PN = "T17";
"VSS<1006>":   PN = "T13"  !CDS_PN = "T13";
"VSS<1007>":   PN = "R86"  !CDS_PN = "R86";
"VSS<1008>":   PN = "R78"  !CDS_PN = "R78";
"VSS<1009>":   PN = "R72"  !CDS_PN = "R72";
"VSS<1010>":   PN = "R68"  !CDS_PN = "R68";
"VSS<1011>":   PN = "R40"  !CDS_PN = "R40";
"VSS<1012>":   PN = "R38"  !CDS_PN = "R38";
"VSS<1013>":   PN = "R34"  !CDS_PN = "R34";
"VSS<1014>":   PN = "R32"  !CDS_PN = "R32";
"VSS<1015>":   PN = "R28"  !CDS_PN = "R28";
"VSS<1016>":   PN = "R26"  !CDS_PN = "R26";
"VSS<1017>":   PN = "R22"  !CDS_PN = "R22";
"VSS<1018>":   PN = "R4"  !CDS_PN = "R4";
"VSS<1019>":   PN = "R2"  !CDS_PN = "R2";
"VSS<1020>":   PN = "R18"  !CDS_PN = "R18";
"VSS<1021>":   PN = "R14"  !CDS_PN = "R14";
"VSS<1022>":   PN = "P83"  !CDS_PN = "P83";
"VSS<1023>":   PN = "P81"  !CDS_PN = "P81";
"VSS<1024>":   PN = "P71"  !CDS_PN = "P71";
"VSS<1025>":   PN = "P69"  !CDS_PN = "P69";
"VSS<1026>":   PN = "P67"  !CDS_PN = "P67";
"VSS<1027>":   PN = "P39"  !CDS_PN = "P39";
"VSS<1028>":   PN = "P33"  !CDS_PN = "P33";
"VSS<1029>":   PN = "P27"  !CDS_PN = "P27";
"VSS<1030>":   PN = "P15"  !CDS_PN = "P15";
"VSS<1031>":   PN = "P11"  !CDS_PN = "P11";
"VSS<1032>":   PN = "N8"  !CDS_PN = "N8";
"VSS<1033>":   PN = "N4"  !CDS_PN = "N4";
"VSS<1034>":   PN = "N78"  !CDS_PN = "N78";
"VSS<1035>":   PN = "N76"  !CDS_PN = "N76";
"VSS<1036>":   PN = "N74"  !CDS_PN = "N74";
"VSS<1037>":   PN = "N72"  !CDS_PN = "N72";
"VSS<1038>":   PN = "N70"  !CDS_PN = "N70";
"VSS<1039>":   PN = "N66"  !CDS_PN = "N66";
"VSS<1040>":   PN = "N6"  !CDS_PN = "N6";
"VSS<1041>":   PN = "N22"  !CDS_PN = "N22";
"VSS<1042>":   PN = "N20"  !CDS_PN = "N20";
"VSS<1043>":   PN = "DM19"  !CDS_PN = "DM19";
"VSS<1044>":   PN = "M85"  !CDS_PN = "M85";
"VSS<1045>":   PN = "M83"  !CDS_PN = "M83";
"VSS<1046>":   PN = "M79"  !CDS_PN = "M79";
"VSS<1047>":   PN = "M71"  !CDS_PN = "M71";
"VSS<1048>":   PN = "M65"  !CDS_PN = "M65";
"VSS<1049>":   PN = "M43"  !CDS_PN = "M43";
"VSS<1050>":   PN = "M41"  !CDS_PN = "M41";
"VSS<1051>":   PN = "M39"  !CDS_PN = "M39";
"VSS<1052>":   PN = "M37"  !CDS_PN = "M37";
"VSS<1053>":   PN = "M35"  !CDS_PN = "M35";
"VSS<1054>":   PN = "M33"  !CDS_PN = "M33";
"VSS<1055>":   PN = "M31"  !CDS_PN = "M31";
"VSS<1056>":   PN = "M29"  !CDS_PN = "M29";
"VSS<1057>":   PN = "M27"  !CDS_PN = "M27";
"VSS<1058>":   PN = "M25"  !CDS_PN = "M25";
"VSS<1059>":   PN = "M23"  !CDS_PN = "M23";
"VSS<1060>":   PN = "M19"  !CDS_PN = "M19";
"VSS<1061>":   PN = "M17"  !CDS_PN = "M17";
"VSS<1062>":   PN = "M15"  !CDS_PN = "M15";
"VSS<1063>":   PN = "CT7"  !CDS_PN = "CT7";
"VSS<1064>":   PN = "BT9"  !CDS_PN = "BT9";
"VSS<1065>":   PN = "L82"  !CDS_PN = "L82";
"VSS<1066>":   PN = "L80"  !CDS_PN = "L80";
"VSS<1067>":   PN = "L78"  !CDS_PN = "L78";
"VSS<1068>":   PN = "L72"  !CDS_PN = "L72";
"VSS<1069>":   PN = "L22"  !CDS_PN = "L22";
"VSS<1070>":   PN = "L20"  !CDS_PN = "L20";
"VSS<1071>":   PN = "L6"  !CDS_PN = "L6";
"VSS<1072>":   PN = "L2"  !CDS_PN = "L2";
"VSS<1073>":   PN = "L10"  !CDS_PN = "L10";
"VSS<1074>":   PN = "K85"  !CDS_PN = "K85";
"VSS<1075>":   PN = "K83"  !CDS_PN = "K83";
"VSS<1076>":   PN = "K81"  !CDS_PN = "K81";
"VSS<1077>":   PN = "K77"  !CDS_PN = "K77";
"VSS<1078>":   PN = "K73"  !CDS_PN = "K73";
"VSS<1079>":   PN = "K71"  !CDS_PN = "K71";
"VSS<1080>":   PN = "K69"  !CDS_PN = "K69";
"VSS<1081>":   PN = "K67"  !CDS_PN = "K67";
"VSS<1082>":   PN = "K65"  !CDS_PN = "K65";
"VSS<1083>":   PN = "K39"  !CDS_PN = "K39";
"VSS<1084>":   PN = "K33"  !CDS_PN = "K33";
"VSS<1085>":   PN = "K27"  !CDS_PN = "K27";
"VSS<1086>":   PN = "DB7"  !CDS_PN = "DB7";
"VSS<1087>":   PN = "K17"  !CDS_PN = "K17";
"VSS<1088>":   PN = "K13"  !CDS_PN = "K13";
"VSS<1089>":   PN = "K11"  !CDS_PN = "K11";
"VSS<1090>":   PN = "K1"  !CDS_PN = "K1";
"VSS<1091>":   PN = "J84"  !CDS_PN = "J84";
"VSS<1092>":   PN = "J82"  !CDS_PN = "J82";
"VSS<1093>":   PN = "J76"  !CDS_PN = "J76";
BODY = "SKX_EXT_B","I22": #LOCATION = "U5D1" !CDS_LOCATION = "U5D1" #SEC = "25" !CDS_SEC = "25";
"VSS<774>":   PN = "AL68"  !CDS_PN = "AL68";
"VSS<775>":   PN = "AL64"  !CDS_PN = "AL64";
"VSS<776>":   PN = "AL56"  !CDS_PN = "AL56";
"VSS<777>":   PN = "AL32"  !CDS_PN = "AL32";
"VSS<778>":   PN = "AL30"  !CDS_PN = "AL30";
"VSS<779>":   PN = "AL24"  !CDS_PN = "AL24";
"VSS<780>":   PN = "AL10"  !CDS_PN = "AL10";
"VSS<781>":   PN = "AL4"  !CDS_PN = "AL4";
"VSS<782>":   PN = "AK85"  !CDS_PN = "AK85";
"VSS<783>":   PN = "AK83"  !CDS_PN = "AK83";
"VSS<784>":   PN = "AK81"  !CDS_PN = "AK81";
"VSS<785>":   PN = "AK79"  !CDS_PN = "AK79";
"VSS<786>":   PN = "AK73"  !CDS_PN = "AK73";
"VSS<787>":   PN = "AK67"  !CDS_PN = "AK67";
"VSS<788>":   PN = "AK65"  !CDS_PN = "AK65";
"VSS<789>":   PN = "AK55"  !CDS_PN = "AK55";
"VSS<790>":   PN = "AK33"  !CDS_PN = "AK33";
"VSS<791>":   PN = "AK31"  !CDS_PN = "AK31";
"VSS<792>":   PN = "AK29"  !CDS_PN = "AK29";
"VSS<793>":   PN = "AK25"  !CDS_PN = "AK25";
"VSS<794>":   PN = "AK23"  !CDS_PN = "AK23";
"VSS<795>":   PN = "AK19"  !CDS_PN = "AK19";
"VSS<796>":   PN = "AK13"  !CDS_PN = "AK13";
"VSS<797>":   PN = "AK9"  !CDS_PN = "AK9";
"VSS<798>":   PN = "AJ86"  !CDS_PN = "AJ86";
"VSS<799>":   PN = "AJ82"  !CDS_PN = "AJ82";
"VSS<800>":   PN = "AJ78"  !CDS_PN = "AJ78";
"VSS<801>":   PN = "AJ74"  !CDS_PN = "AJ74";
"VSS<802>":   PN = "AJ68"  !CDS_PN = "AJ68";
"VSS<803>":   PN = "AJ66"  !CDS_PN = "AJ66";
"VSS<804>":   PN = "AJ54"  !CDS_PN = "AJ54";
"VSS<805>":   PN = "AJ52"  !CDS_PN = "AJ52";
"VSS<806>":   PN = "AJ50"  !CDS_PN = "AJ50";
"VSS<807>":   PN = "AJ48"  !CDS_PN = "AJ48";
"VSS<808>":   PN = "AJ46"  !CDS_PN = "AJ46";
"VSS<809>":   PN = "AJ34"  !CDS_PN = "AJ34";
"VSS<810>":   PN = "AJ32"  !CDS_PN = "AJ32";
"VSS<811>":   PN = "AJ28"  !CDS_PN = "AJ28";
"VSS<812>":   PN = "AJ26"  !CDS_PN = "AJ26";
"VSS<813>":   PN = "AJ22"  !CDS_PN = "AJ22";
"VSS<814>":   PN = "AJ8"  !CDS_PN = "AJ8";
"VSS<815>":   PN = "AH83"  !CDS_PN = "AH83";
"VSS<816>":   PN = "AH77"  !CDS_PN = "AH77";
"VSS<817>":   PN = "AH75"  !CDS_PN = "AH75";
"VSS<818>":   PN = "AH69"  !CDS_PN = "AH69";
"VSS<819>":   PN = "AH65"  !CDS_PN = "AH65";
"VSS<820>":   PN = "AH61"  !CDS_PN = "AH61";
"VSS<821>":   PN = "AH59"  !CDS_PN = "AH59";
"VSS<822>":   PN = "AH53"  !CDS_PN = "AH53";
"VSS<823>":   PN = "AH51"  !CDS_PN = "AH51";
"VSS<824>":   PN = "AH49"  !CDS_PN = "AH49";
"VSS<825>":   PN = "AH47"  !CDS_PN = "AH47";
"VSS<826>":   PN = "AH45"  !CDS_PN = "AH45";
"VSS<827>":   PN = "AH35"  !CDS_PN = "AH35";
"VSS<828>":   PN = "AH33"  !CDS_PN = "AH33";
"VSS<829>":   PN = "AH27"  !CDS_PN = "AH27";
"VSS<830>":   PN = "AH21"  !CDS_PN = "AH21";
"VSS<831>":   PN = "AH5"  !CDS_PN = "AH5";
"VSS<832>":   PN = "AH1"  !CDS_PN = "AH1";
"VSS<833>":   PN = "AG80"  !CDS_PN = "AG80";
"VSS<834>":   PN = "AG78"  !CDS_PN = "AG78";
"VSS<835>":   PN = "AG76"  !CDS_PN = "AG76";
"VSS<836>":   PN = "AG74"  !CDS_PN = "AG74";
"VSS<837>":   PN = "AG70"  !CDS_PN = "AG70";
"VSS<838>":   PN = "AG64"  !CDS_PN = "AG64";
"VSS<839>":   PN = "AG36"  !CDS_PN = "AG36";
"VSS<840>":   PN = "AG18"  !CDS_PN = "AG18";
"VSS<841>":   PN = "AG14"  !CDS_PN = "AG14";
"VSS<842>":   PN = "AG12"  !CDS_PN = "AG12";
"VSS<843>":   PN = "AF85"  !CDS_PN = "AF85";
"VSS<844>":   PN = "AF83"  !CDS_PN = "AF83";
"VSS<845>":   PN = "AF77"  !CDS_PN = "AF77";
"VSS<846>":   PN = "AF73"  !CDS_PN = "AF73";
"VSS<847>":   PN = "AF41"  !CDS_PN = "AF41";
"VSS<848>":   PN = "AF39"  !CDS_PN = "AF39";
"VSS<849>":   PN = "AF37"  !CDS_PN = "AF37";
"VSS<850>":   PN = "AF33"  !CDS_PN = "AF33";
"VSS<851>":   PN = "AF31"  !CDS_PN = "AF31";
"VSS<852>":   PN = "AF29"  !CDS_PN = "AF29";
"VSS<853>":   PN = "AF27"  !CDS_PN = "AF27";
"VSS<854>":   PN = "AF25"  !CDS_PN = "AF25";
"VSS<855>":   PN = "AF23"  !CDS_PN = "AF23";
"VSS<856>":   PN = "AF21"  !CDS_PN = "AF21";
"VSS<857>":   PN = "AF9"  !CDS_PN = "AF9";
"VSS<858>":   PN = "AC52"  !CDS_PN = "AC52";
"VSS<859>":   PN = "AF1"  !CDS_PN = "AF1";
"VSS<860>":   PN = "AE78"  !CDS_PN = "AE78";
"VSS<861>":   PN = "AE70"  !CDS_PN = "AE70";
"VSS<862>":   PN = "AE68"  !CDS_PN = "AE68";
"VSS<863>":   PN = "AE66"  !CDS_PN = "AE66";
"VSS<864>":   PN = "AE64"  !CDS_PN = "AE64";
"VSS<865>":   PN = "AE42"  !CDS_PN = "AE42";
"VSS<866>":   PN = "AE40"  !CDS_PN = "AE40";
"VSS<867>":   PN = "AE38"  !CDS_PN = "AE38";
"VSS<868>":   PN = "AE16"  !CDS_PN = "AE16";
"VSS<869>":   PN = "AC54"  !CDS_PN = "AC54";
"VSS<870>":   PN = "AE8"  !CDS_PN = "AE8";
"VSS<871>":   PN = "AE4"  !CDS_PN = "AE4";
"VSS<872>":   PN = "AD85"  !CDS_PN = "AD85";
"VSS<873>":   PN = "AD83"  !CDS_PN = "AD83";
"VSS<874>":   PN = "AD81"  !CDS_PN = "AD81";
"VSS<875>":   PN = "AD75"  !CDS_PN = "AD75";
"VSS<876>":   PN = "AD73"  !CDS_PN = "AD73";
"VSS<877>":   PN = "AD71"  !CDS_PN = "AD71";
"VSS<878>":   PN = "AD43"  !CDS_PN = "AD43";
"VSS<879>":   PN = "AD39"  !CDS_PN = "AD39";
"VSS<880>":   PN = "AD33"  !CDS_PN = "AD33";
"VSS<881>":   PN = "AD27"  !CDS_PN = "AD27";
"VSS<882>":   PN = "AD21"  !CDS_PN = "AD21";
"VSS<883>":   PN = "AD19"  !CDS_PN = "AD19";
"VSS<884>":   PN = "AD15"  !CDS_PN = "AD15";
"VSS<885>":   PN = "AD13"  !CDS_PN = "AD13";
"VSS<886>":   PN = "AD11"  !CDS_PN = "AD11";
"VSS<887>":   PN = "AD9"  !CDS_PN = "AD9";
"VSS<888>":   PN = "AD7"  !CDS_PN = "AD7";
"VSS<889>":   PN = "AD3"  !CDS_PN = "AD3";
"VSS<890>":   PN = "AC86"  !CDS_PN = "AC86";
"VSS<891>":   PN = "AC84"  !CDS_PN = "AC84";
"VSS<892>":   PN = "AC78"  !CDS_PN = "AC78";
"VSS<893>":   PN = "AC72"  !CDS_PN = "AC72";
"VSS<894>":   PN = "AC70"  !CDS_PN = "AC70";
"VSS<895>":   PN = "AC64"  !CDS_PN = "AC64";
"VSS<896>":   PN = "AC40"  !CDS_PN = "AC40";
"VSS<897>":   PN = "AC38"  !CDS_PN = "AC38";
"VSS<898>":   PN = "AC34"  !CDS_PN = "AC34";
"VSS<899>":   PN = "AC32"  !CDS_PN = "AC32";
"VSS<900>":   PN = "AC28"  !CDS_PN = "AC28";
"VSS<901>":   PN = "AC26"  !CDS_PN = "AC26";
"VSS<902>":   PN = "AC22"  !CDS_PN = "AC22";
"VSS<903>":   PN = "AC18"  !CDS_PN = "AC18";
"VSS<904>":   PN = "AB85"  !CDS_PN = "AB85";
"VSS<905>":   PN = "AB83"  !CDS_PN = "AB83";
"VSS<906>":   PN = "AB79"  !CDS_PN = "AB79";
"VSS<907>":   PN = "AB73"  !CDS_PN = "AB73";
"VSS<908>":   PN = "AB69"  !CDS_PN = "AB69";
"VSS<909>":   PN = "AB65"  !CDS_PN = "AB65";
"VSS<910>":   PN = "AB41"  !CDS_PN = "AB41";
"VSS<911>":   PN = "AB37"  !CDS_PN = "AB37";
"VSS<912>":   PN = "AB35"  !CDS_PN = "AB35";
"VSS<913>":   PN = "AB31"  !CDS_PN = "AB31";
"VSS<914>":   PN = "AB29"  !CDS_PN = "AB29";
"VSS<915>":   PN = "AB25"  !CDS_PN = "AB25";
"VSS<916>":   PN = "AB23"  !CDS_PN = "AB23";
"VSS<917>":   PN = "AB21"  !CDS_PN = "AB21";
"VSS<918>":   PN = "AB11"  !CDS_PN = "AB11";
"VSS<919>":   PN = "AB5"  !CDS_PN = "AB5";
"VSS<920>":   PN = "AB1"  !CDS_PN = "AB1";
"VSS<921>":   PN = "AA82"  !CDS_PN = "AA82";
"VSS<922>":   PN = "AA80"  !CDS_PN = "AA80";
"VSS<923>":   PN = "AA78"  !CDS_PN = "AA78";
"VSS<924>":   PN = "AA76"  !CDS_PN = "AA76";
"VSS<925>":   PN = "AA68"  !CDS_PN = "AA68";
"VSS<926>":   PN = "AA66"  !CDS_PN = "AA66";
"VSS<927>":   PN = "AA64"  !CDS_PN = "AA64";
"VSS<928>":   PN = "AA42"  !CDS_PN = "AA42";
"VSS<929>":   PN = "AA36"  !CDS_PN = "AA36";
"VSS<930>":   PN = "AA30"  !CDS_PN = "AA30";
"VSS<931>":   PN = "AA24"  !CDS_PN = "AA24";
"VSS<932>":   PN = "AA22"  !CDS_PN = "AA22";
"VSS<933>":   PN = "AA18"  !CDS_PN = "AA18";
BODY = "SKX_EXT_B","I23": #LOCATION = "U5D1" !CDS_LOCATION = "U5D1" #SEC = "26" !CDS_SEC = "26";
"VSS<614>":   PN = "BG72"  !CDS_PN = "BG72";
"VSS<615>":   PN = "BG24"  !CDS_PN = "BG24";
"VSS<616>":   PN = "BG22"  !CDS_PN = "BG22";
"VSS<617>":   PN = "BG10"  !CDS_PN = "BG10";
"VSS<618>":   PN = "BG8"  !CDS_PN = "BG8";
"VSS<619>":   PN = "BG6"  !CDS_PN = "BG6";
"VSS<620>":   PN = "BF71"  !CDS_PN = "BF71";
"VSS<621>":   PN = "BF69"  !CDS_PN = "BF69";
"VSS<622>":   PN = "BF67"  !CDS_PN = "BF67";
"VSS<623>":   PN = "BF65"  !CDS_PN = "BF65";
"VSS<624>":   PN = "BF63"  !CDS_PN = "BF63";
"VSS<625>":   PN = "BF25"  !CDS_PN = "BF25";
"VSS<626>":   PN = "BF19"  !CDS_PN = "BF19";
"VSS<627>":   PN = "BF17"  !CDS_PN = "BF17";
"VSS<628>":   PN = "BF15"  !CDS_PN = "BF15";
"VSS<629>":   PN = "BF9"  !CDS_PN = "BF9";
"VSS<630>":   PN = "BE70"  !CDS_PN = "BE70";
"VSS<631>":   PN = "BE68"  !CDS_PN = "BE68";
"VSS<632>":   PN = "BE66"  !CDS_PN = "BE66";
"VSS<633>":   PN = "BE64"  !CDS_PN = "BE64";
"VSS<634>":   PN = "BE26"  !CDS_PN = "BE26";
"VSS<635>":   PN = "BE10"  !CDS_PN = "BE10";
"VSS<636>":   PN = "BE8"  !CDS_PN = "BE8";
"VSS<637>":   PN = "BE6"  !CDS_PN = "BE6";
"VSS<638>":   PN = "BE4"  !CDS_PN = "BE4";
"VSS<639>":   PN = "BD71"  !CDS_PN = "BD71";
"VSS<640>":   PN = "BD63"  !CDS_PN = "BD63";
"VSS<641>":   PN = "BD27"  !CDS_PN = "BD27";
"VSS<642>":   PN = "BD21"  !CDS_PN = "BD21";
"VSS<643>":   PN = "BD15"  !CDS_PN = "BD15";
"VSS<644>":   PN = "BD11"  !CDS_PN = "BD11";
"VSS<645>":   PN = "BD5"  !CDS_PN = "BD5";
"VSS<646>":   PN = "BC82"  !CDS_PN = "BC82";
"VSS<647>":   PN = "BC80"  !CDS_PN = "BC80";
"VSS<648>":   PN = "BC78"  !CDS_PN = "BC78";
"VSS<649>":   PN = "BC76"  !CDS_PN = "BC76";
"VSS<650>":   PN = "BC74"  !CDS_PN = "BC74";
"VSS<651>":   PN = "BC72"  !CDS_PN = "BC72";
"VSS<652>":   PN = "BC70"  !CDS_PN = "BC70";
"VSS<653>":   PN = "BC16"  !CDS_PN = "BC16";
"VSS<654>":   PN = "BC12"  !CDS_PN = "BC12";
"VSS<655>":   PN = "BC8"  !CDS_PN = "BC8";
"VSS<656>":   PN = "BC4"  !CDS_PN = "BC4";
"VSS<657>":   PN = "BB83"  !CDS_PN = "BB83";
"VSS<658>":   PN = "BB81"  !CDS_PN = "BB81";
"VSS<659>":   PN = "BB79"  !CDS_PN = "BB79";
"VSS<660>":   PN = "BB77"  !CDS_PN = "BB77";
"VSS<661>":   PN = "BB75"  !CDS_PN = "BB75";
"VSS<662>":   PN = "BB73"  !CDS_PN = "BB73";
"VSS<663>":   PN = "BB69"  !CDS_PN = "BB69";
"VSS<664>":   PN = "BB63"  !CDS_PN = "BB63";
"VSS<665>":   PN = "BB23"  !CDS_PN = "BB23";
"VSS<666>":   PN = "BB19"  !CDS_PN = "BB19";
"VSS<667>":   PN = "BA84"  !CDS_PN = "BA84";
"VSS<668>":   PN = "BA80"  !CDS_PN = "BA80";
"VSS<669>":   PN = "BA74"  !CDS_PN = "BA74";
"VSS<670>":   PN = "BA68"  !CDS_PN = "BA68";
"VSS<671>":   PN = "BA62"  !CDS_PN = "BA62";
"VSS<672>":   PN = "BA12"  !CDS_PN = "BA12";
"VSS<673>":   PN = "BA6"  !CDS_PN = "BA6";
"VSS<674>":   PN = "BA2"  !CDS_PN = "BA2";
"VSS<675>":   PN = "AY81"  !CDS_PN = "AY81";
"VSS<676>":   PN = "AY79"  !CDS_PN = "AY79";
"VSS<677>":   PN = "AY63"  !CDS_PN = "AY63";
"VSS<678>":   PN = "AY25"  !CDS_PN = "AY25";
"VSS<679>":   PN = "AY23"  !CDS_PN = "AY23";
"VSS<680>":   PN = "AY21"  !CDS_PN = "AY21";
"VSS<681>":   PN = "AY17"  !CDS_PN = "AY17";
"VSS<682>":   PN = "AY15"  !CDS_PN = "AY15";
"VSS<683>":   PN = "AY5"  !CDS_PN = "AY5";
"VSS<684>":   PN = "AW84"  !CDS_PN = "AW84";
"VSS<685>":   PN = "AW82"  !CDS_PN = "AW82";
"VSS<686>":   PN = "AW78"  !CDS_PN = "AW78";
"VSS<687>":   PN = "AW74"  !CDS_PN = "AW74";
"VSS<688>":   PN = "AW72"  !CDS_PN = "AW72";
"VSS<689>":   PN = "AW70"  !CDS_PN = "AW70";
"VSS<690>":   PN = "AW68"  !CDS_PN = "AW68";
"VSS<691>":   PN = "AW66"  !CDS_PN = "AW66";
"VSS<692>":   PN = "AW62"  !CDS_PN = "AW62";
"VSS<693>":   PN = "AW10"  !CDS_PN = "AW10";
"VSS<694>":   PN = "AW2"  !CDS_PN = "AW2";
"VSS<695>":   PN = "AV83"  !CDS_PN = "AV83";
"VSS<696>":   PN = "AV75"  !CDS_PN = "AV75";
"VSS<697>":   PN = "AV67"  !CDS_PN = "AV67";
"VSS<698>":   PN = "AV65"  !CDS_PN = "AV65";
"VSS<699>":   PN = "AV63"  !CDS_PN = "AV63";
"VSS<700>":   PN = "AV25"  !CDS_PN = "AV25";
"VSS<701>":   PN = "AV23"  !CDS_PN = "AV23";
"VSS<702>":   PN = "AV19"  !CDS_PN = "AV19";
"VSS<703>":   PN = "AV13"  !CDS_PN = "AV13";
"VSS<704>":   PN = "AV11"  !CDS_PN = "AV11";
"VSS<705>":   PN = "AV7"  !CDS_PN = "AV7";
"VSS<706>":   PN = "AV3"  !CDS_PN = "AV3";
"VSS<707>":   PN = "AV1"  !CDS_PN = "AV1";
"VSS<708>":   PN = "AU86"  !CDS_PN = "AU86";
"VSS<709>":   PN = "AU84"  !CDS_PN = "AU84";
"VSS<710>":   PN = "AU80"  !CDS_PN = "AU80";
"VSS<711>":   PN = "AU78"  !CDS_PN = "AU78";
"VSS<712>":   PN = "AU76"  !CDS_PN = "AU76";
"VSS<713>":   PN = "AU74"  !CDS_PN = "AU74";
"VSS<714>":   PN = "AU68"  !CDS_PN = "AU68";
"VSS<715>":   PN = "AU64"  !CDS_PN = "AU64";
"VSS<716>":   PN = "AU62"  !CDS_PN = "AU62";
"VSS<717>":   PN = "AU28"  !CDS_PN = "AU28";
"VSS<718>":   PN = "AU26"  !CDS_PN = "AU26";
"VSS<719>":   PN = "AU6"  !CDS_PN = "AU6";
"VSS<720>":   PN = "AU2"  !CDS_PN = "AU2";
"VSS<721>":   PN = "AT85"  !CDS_PN = "AT85";
"VSS<722>":   PN = "AT83"  !CDS_PN = "AT83";
"VSS<723>":   PN = "AT77"  !CDS_PN = "AT77";
"VSS<724>":   PN = "AT73"  !CDS_PN = "AT73";
"VSS<725>":   PN = "AT69"  !CDS_PN = "AT69";
"VSS<726>":   PN = "AT63"  !CDS_PN = "AT63";
"VSS<727>":   PN = "AT61"  !CDS_PN = "AT61";
"VSS<728>":   PN = "AT27"  !CDS_PN = "AT27";
"VSS<729>":   PN = "AT21"  !CDS_PN = "AT21";
"VSS<730>":   PN = "AT17"  !CDS_PN = "AT17";
"VSS<731>":   PN = "AT15"  !CDS_PN = "AT15";
"VSS<732>":   PN = "P63"  !CDS_PN = "P63";
"VSS<733>":   PN = "AC48"  !CDS_PN = "AC48";
"VSS<734>":   PN = "AR78"  !CDS_PN = "AR78";
"VSS<735>":   PN = "AR72"  !CDS_PN = "AR72";
"VSS<736>":   PN = "AR60"  !CDS_PN = "AR60";
"VSS<737>":   PN = "AR30"  !CDS_PN = "AR30";
"VSS<738>":   PN = "AR24"  !CDS_PN = "AR24";
"VSS<739>":   PN = "AR10"  !CDS_PN = "AR10";
"VSS<740>":   PN = "AP85"  !CDS_PN = "AP85";
"VSS<741>":   PN = "AP83"  !CDS_PN = "AP83";
"VSS<742>":   PN = "AP81"  !CDS_PN = "AP81";
"VSS<743>":   PN = "AP75"  !CDS_PN = "AP75";
"VSS<744>":   PN = "AP73"  !CDS_PN = "AP73";
"VSS<745>":   PN = "AP69"  !CDS_PN = "AP69";
"VSS<746>":   PN = "AP67"  !CDS_PN = "AP67";
"VSS<747>":   PN = "AP65"  !CDS_PN = "AP65";
"VSS<748>":   PN = "AP63"  !CDS_PN = "AP63";
"VSS<749>":   PN = "AP59"  !CDS_PN = "AP59";
"VSS<750>":   PN = "AP31"  !CDS_PN = "AP31";
"VSS<751>":   PN = "AP19"  !CDS_PN = "AP19";
"VSS<752>":   PN = "AP13"  !CDS_PN = "AP13";
"VSS<753>":   PN = "AP9"  !CDS_PN = "AP9";
"VSS<754>":   PN = "AP5"  !CDS_PN = "AP5";
"VSS<755>":   PN = "AN78"  !CDS_PN = "AN78";
"VSS<756>":   PN = "AN58"  !CDS_PN = "AN58";
"VSS<757>":   PN = "AN28"  !CDS_PN = "AN28";
"VSS<758>":   PN = "AN6"  !CDS_PN = "AN6";
"VSS<759>":   PN = "AN2"  !CDS_PN = "AN2";
"VSS<760>":   PN = "AM83"  !CDS_PN = "AM83";
"VSS<761>":   PN = "AM79"  !CDS_PN = "AM79";
"VSS<762>":   PN = "AM73"  !CDS_PN = "AM73";
"VSS<763>":   PN = "AM69"  !CDS_PN = "AM69";
"VSS<764>":   PN = "AM63"  !CDS_PN = "AM63";
"VSS<765>":   PN = "AM57"  !CDS_PN = "AM57";
"VSS<766>":   PN = "AM31"  !CDS_PN = "AM31";
"VSS<767>":   PN = "AC50"  !CDS_PN = "AC50";
"VSS<768>":   PN = "AM1"  !CDS_PN = "AM1";
"VSS<769>":   PN = "AL86"  !CDS_PN = "AL86";
"VSS<770>":   PN = "AL82"  !CDS_PN = "AL82";
"VSS<771>":   PN = "AL80"  !CDS_PN = "AL80";
"VSS<772>":   PN = "AL78"  !CDS_PN = "AL78";
"VSS<773>":   PN = "AL76"  !CDS_PN = "AL76";
DRAWING = "@baseboard_fab2_lib.baseboard_fab2(sch_1):page41";
BODY = "SKX_EXT_B","I283": #LOCATION = "U5D1" !CDS_LOCATION = "U5D1" #SEC = "27" !CDS_SEC = "27";
"VSS<454>":   PN = "P49"  !CDS_PN = "P49";
"VSS<455>":   PN = "CJ12"  !CDS_PN = "CJ12";
"VSS<456>":   PN = "CJ10"  !CDS_PN = "CJ10";
"VSS<457>":   PN = "CJ8"  !CDS_PN = "CJ8";
"VSS<458>":   PN = "CJ6"  !CDS_PN = "CJ6";
"VSS<459>":   PN = "CJ2"  !CDS_PN = "CJ2";
"VSS<460>":   PN = "CH83"  !CDS_PN = "CH83";
"VSS<461>":   PN = "CH81"  !CDS_PN = "CH81";
"VSS<462>":   PN = "CH79"  !CDS_PN = "CH79";
"VSS<463>":   PN = "CH73"  !CDS_PN = "CH73";
"VSS<464>":   PN = "CH67"  !CDS_PN = "CH67";
"VSS<465>":   PN = "CH63"  !CDS_PN = "CH63";
"VSS<466>":   PN = "CH19"  !CDS_PN = "CH19";
"VSS<467>":   PN = "CH15"  !CDS_PN = "CH15";
"VSS<468>":   PN = "CH3"  !CDS_PN = "CH3";
"VSS<469>":   PN = "CH1"  !CDS_PN = "CH1";
"VSS<470>":   PN = "CG80"  !CDS_PN = "CG80";
"VSS<471>":   PN = "CG72"  !CDS_PN = "CG72";
"VSS<472>":   PN = "CG68"  !CDS_PN = "CG68";
"VSS<473>":   PN = "CG62"  !CDS_PN = "CG62";
"VSS<474>":   PN = "CG22"  !CDS_PN = "CG22";
"VSS<475>":   PN = "CG18"  !CDS_PN = "CG18";
"VSS<476>":   PN = "P51"  !CDS_PN = "P51";
"VSS<477>":   PN = "CF83"  !CDS_PN = "CF83";
"VSS<478>":   PN = "CF77"  !CDS_PN = "CF77";
"VSS<479>":   PN = "CF71"  !CDS_PN = "CF71";
"VSS<480>":   PN = "CF69"  !CDS_PN = "CF69";
"VSS<481>":   PN = "CF63"  !CDS_PN = "CF63";
"VSS<482>":   PN = "CF9"  !CDS_PN = "CF9";
"VSS<483>":   PN = "P53"  !CDS_PN = "P53";
"VSS<484>":   PN = "CE82"  !CDS_PN = "CE82";
"VSS<485>":   PN = "CE70"  !CDS_PN = "CE70";
"VSS<486>":   PN = "CE62"  !CDS_PN = "CE62";
"VSS<487>":   PN = "CE26"  !CDS_PN = "CE26";
"VSS<488>":   PN = "CE20"  !CDS_PN = "CE20";
"VSS<489>":   PN = "CE14"  !CDS_PN = "CE14";
"VSS<490>":   PN = "CE10"  !CDS_PN = "CE10";
"VSS<491>":   PN = "CD81"  !CDS_PN = "CD81";
"VSS<492>":   PN = "CD79"  !CDS_PN = "CD79";
"VSS<493>":   PN = "CD77"  !CDS_PN = "CD77";
"VSS<494>":   PN = "CD75"  !CDS_PN = "CD75";
"VSS<495>":   PN = "CD73"  !CDS_PN = "CD73";
"VSS<496>":   PN = "CD63"  !CDS_PN = "CD63";
"VSS<497>":   PN = "CD13"  !CDS_PN = "CD13";
"VSS<498>":   PN = "CD5"  !CDS_PN = "CD5";
"VSS<499>":   PN = "CC82"  !CDS_PN = "CC82";
"VSS<500>":   PN = "CC80"  !CDS_PN = "CC80";
"VSS<501>":   PN = "CC78"  !CDS_PN = "CC78";
"VSS<502>":   PN = "CC76"  !CDS_PN = "CC76";
"VSS<503>":   PN = "CC74"  !CDS_PN = "CC74";
"VSS<504>":   PN = "CC72"  !CDS_PN = "CC72";
"VSS<505>":   PN = "CC64"  !CDS_PN = "CC64";
"VSS<506>":   PN = "CC24"  !CDS_PN = "CC24";
"VSS<507>":   PN = "CC18"  !CDS_PN = "CC18";
"VSS<508>":   PN = "CC16"  !CDS_PN = "CC16";
"VSS<509>":   PN = "CC4"  !CDS_PN = "CC4";
"VSS<510>":   PN = "CB71"  !CDS_PN = "CB71";
"VSS<511>":   PN = "CB63"  !CDS_PN = "CB63";
"VSS<512>":   PN = "CB27"  !CDS_PN = "CB27";
"VSS<513>":   PN = "CB9"  !CDS_PN = "CB9";
"VSS<514>":   PN = "CB7"  !CDS_PN = "CB7";
"VSS<515>":   PN = "CA70"  !CDS_PN = "CA70";
"VSS<516>":   PN = "CA68"  !CDS_PN = "CA68";
"VSS<517>":   PN = "CA66"  !CDS_PN = "CA66";
"VSS<518>":   PN = "CA64"  !CDS_PN = "CA64";
"VSS<519>":   PN = "CA26"  !CDS_PN = "CA26";
"VSS<520>":   PN = "CA18"  !CDS_PN = "CA18";
"VSS<521>":   PN = "CA14"  !CDS_PN = "CA14";
"VSS<522>":   PN = "CA10"  !CDS_PN = "CA10";
"VSS<523>":   PN = "CA8"  !CDS_PN = "CA8";
"VSS<524>":   PN = "CA6"  !CDS_PN = "CA6";
"VSS<525>":   PN = "CA2"  !CDS_PN = "CA2";
"VSS<526>":   PN = "BY71"  !CDS_PN = "BY71";
"VSS<527>":   PN = "BY69"  !CDS_PN = "BY69";
"VSS<528>":   PN = "BY67"  !CDS_PN = "BY67";
"VSS<529>":   PN = "BY65"  !CDS_PN = "BY65";
"VSS<530>":   PN = "BY63"  !CDS_PN = "BY63";
"VSS<531>":   PN = "BY23"  !CDS_PN = "BY23";
"VSS<532>":   PN = "BY13"  !CDS_PN = "BY13";
"VSS<533>":   PN = "BY11"  !CDS_PN = "BY11";
"VSS<534>":   PN = "BW82"  !CDS_PN = "BW82";
"VSS<535>":   PN = "BW80"  !CDS_PN = "BW80";
"VSS<536>":   PN = "BW78"  !CDS_PN = "BW78";
"VSS<537>":   PN = "BW76"  !CDS_PN = "BW76";
"VSS<538>":   PN = "BW74"  !CDS_PN = "BW74";
"VSS<539>":   PN = "BW72"  !CDS_PN = "BW72";
"VSS<540>":   PN = "BW26"  !CDS_PN = "BW26";
"VSS<541>":   PN = "BW18"  !CDS_PN = "BW18";
"VSS<542>":   PN = "BW16"  !CDS_PN = "BW16";
"VSS<543>":   PN = "BW14"  !CDS_PN = "BW14";
"VSS<544>":   PN = "BW12"  !CDS_PN = "BW12";
"VSS<545>":   PN = "P55"  !CDS_PN = "P55";
"VSS<546>":   PN = "BW6"  !CDS_PN = "BW6";
"VSS<547>":   PN = "BV25"  !CDS_PN = "BV25";
"VSS<548>":   PN = "BV17"  !CDS_PN = "BV17";
"VSS<549>":   PN = "BU10"  !CDS_PN = "BU10";
"VSS<550>":   PN = "BV5"  !CDS_PN = "BV5";
"VSS<551>":   PN = "BU8"  !CDS_PN = "BU8";
"VSS<552>":   PN = "BT25"  !CDS_PN = "BT25";
"VSS<553>":   PN = "BT23"  !CDS_PN = "BT23";
"VSS<554>":   PN = "BT21"  !CDS_PN = "BT21";
"VSS<555>":   PN = "BT5"  !CDS_PN = "BT5";
"VSS<556>":   PN = "BT3"  !CDS_PN = "BT3";
"VSS<557>":   PN = "BR82"  !CDS_PN = "BR82";
"VSS<558>":   PN = "BR80"  !CDS_PN = "BR80";
"VSS<559>":   PN = "BR78"  !CDS_PN = "BR78";
"VSS<560>":   PN = "BR76"  !CDS_PN = "BR76";
"VSS<561>":   PN = "BR74"  !CDS_PN = "BR74";
"VSS<562>":   PN = "BR72"  !CDS_PN = "BR72";
"VSS<563>":   PN = "BR70"  !CDS_PN = "BR70";
"VSS<564>":   PN = "BR68"  !CDS_PN = "BR68";
"VSS<565>":   PN = "BR66"  !CDS_PN = "BR66";
"VSS<566>":   PN = "BR64"  !CDS_PN = "BR64";
"VSS<567>":   PN = "P57"  !CDS_PN = "P57";
"VSS<568>":   PN = "BR16"  !CDS_PN = "BR16";
"VSS<569>":   PN = "BR10"  !CDS_PN = "BR10";
"VSS<570>":   PN = "BR6"  !CDS_PN = "BR6";
"VSS<571>":   PN = "BP27"  !CDS_PN = "BP27";
"VSS<572>":   PN = "BP3"  !CDS_PN = "BP3";
"VSS<573>":   PN = "BN26"  !CDS_PN = "BN26";
"VSS<574>":   PN = "BN20"  !CDS_PN = "BN20";
"VSS<575>":   PN = "BN10"  !CDS_PN = "BN10";
"VSS<576>":   PN = "BN6"  !CDS_PN = "BN6";
"VSS<577>":   PN = "BM25"  !CDS_PN = "BM25";
"VSS<578>":   PN = "P59"  !CDS_PN = "P59";
"VSS<579>":   PN = "BM15"  !CDS_PN = "BM15";
"VSS<580>":   PN = "BM13"  !CDS_PN = "BM13";
"VSS<581>":   PN = "BM9"  !CDS_PN = "BM9";
"VSS<582>":   PN = "BL82"  !CDS_PN = "BL82";
"VSS<583>":   PN = "BL80"  !CDS_PN = "BL80";
"VSS<584>":   PN = "BL78"  !CDS_PN = "BL78";
"VSS<585>":   PN = "BL76"  !CDS_PN = "BL76";
"VSS<586>":   PN = "BL74"  !CDS_PN = "BL74";
"VSS<587>":   PN = "BL72"  !CDS_PN = "BL72";
"VSS<588>":   PN = "BL70"  !CDS_PN = "BL70";
"VSS<589>":   PN = "BL68"  !CDS_PN = "BL68";
"VSS<590>":   PN = "BL66"  !CDS_PN = "BL66";
"VSS<591>":   PN = "BL64"  !CDS_PN = "BL64";
"VSS<592>":   PN = "BL24"  !CDS_PN = "BL24";
"VSS<593>":   PN = "BL22"  !CDS_PN = "BL22";
"VSS<594>":   PN = "P61"  !CDS_PN = "P61";
"VSS<595>":   PN = "BL12"  !CDS_PN = "BL12";
"VSS<596>":   PN = "BL10"  !CDS_PN = "BL10";
"VSS<597>":   PN = "BL6"  !CDS_PN = "BL6";
"VSS<598>":   PN = "BK19"  !CDS_PN = "BK19";
"VSS<599>":   PN = "BK11"  !CDS_PN = "BK11";
"VSS<600>":   PN = "BK7"  !CDS_PN = "BK7";
"VSS<601>":   PN = "BK3"  !CDS_PN = "BK3";
"VSS<602>":   PN = "BJ6"  !CDS_PN = "BJ6";
"VSS<603>":   PN = "BJ4"  !CDS_PN = "BJ4";
"VSS<604>":   PN = "BH21"  !CDS_PN = "BH21";
"VSS<605>":   PN = "BH15"  !CDS_PN = "BH15";
"VSS<606>":   PN = "BH11"  !CDS_PN = "BH11";
"VSS<607>":   PN = "BH9"  !CDS_PN = "BH9";
"VSS<608>":   PN = "BH7"  !CDS_PN = "BH7";
"VSS<609>":   PN = "BG82"  !CDS_PN = "BG82";
"VSS<610>":   PN = "BG80"  !CDS_PN = "BG80";
"VSS<611>":   PN = "BG78"  !CDS_PN = "BG78";
"VSS<612>":   PN = "BG76"  !CDS_PN = "BG76";
"VSS<613>":   PN = "BG74"  !CDS_PN = "BG74";
BODY = "SKX_EXT_B","I284": #LOCATION = "U5D1" !CDS_LOCATION = "U5D1" #SEC = "28" !CDS_SEC = "28";
"VSS<294>":   PN = "DA46"  !CDS_PN = "DA46";
"VSS<295>":   PN = "DA44"  !CDS_PN = "DA44";
"VSS<296>":   PN = "DA38"  !CDS_PN = "DA38";
"VSS<297>":   PN = "DA36"  !CDS_PN = "DA36";
"VSS<298>":   PN = "DA34"  !CDS_PN = "DA34";
"VSS<299>":   PN = "DA32"  !CDS_PN = "DA32";
"VSS<300>":   PN = "DA30"  !CDS_PN = "DA30";
"VSS<301>":   PN = "DA28"  !CDS_PN = "DA28";
"VSS<302>":   PN = "DA26"  !CDS_PN = "DA26";
"VSS<303>":   PN = "DA18"  !CDS_PN = "DA18";
"VSS<304>":   PN = "H53"  !CDS_PN = "H53";
"VSS<305>":   PN = "DA6"  !CDS_PN = "DA6";
"VSS<306>":   PN = "CY85"  !CDS_PN = "CY85";
"VSS<307>":   PN = "CY83"  !CDS_PN = "CY83";
"VSS<308>":   PN = "CY77"  !CDS_PN = "CY77";
"VSS<309>":   PN = "CY75"  !CDS_PN = "CY75";
"VSS<310>":   PN = "CY69"  !CDS_PN = "CY69";
"VSS<311>":   PN = "CY65"  !CDS_PN = "CY65";
"VSS<312>":   PN = "CY61"  !CDS_PN = "CY61";
"VSS<313>":   PN = "CY59"  !CDS_PN = "CY59";
"VSS<314>":   PN = "CY51"  !CDS_PN = "CY51";
"VSS<315>":   PN = "CY45"  !CDS_PN = "CY45";
"VSS<316>":   PN = "CY41"  !CDS_PN = "CY41";
"VSS<317>":   PN = "CY21"  !CDS_PN = "CY21";
"VSS<318>":   PN = "CY15"  !CDS_PN = "CY15";
"VSS<319>":   PN = "CY13"  !CDS_PN = "CY13";
"VSS<320>":   PN = "CY9"  !CDS_PN = "CY9";
"VSS<321>":   PN = "CY1"  !CDS_PN = "CY1";
"VSS<322>":   PN = "CW82"  !CDS_PN = "CW82";
"VSS<323>":   PN = "CW78"  !CDS_PN = "CW78";
"VSS<324>":   PN = "CW74"  !CDS_PN = "CW74";
"VSS<325>":   PN = "CW68"  !CDS_PN = "CW68";
"VSS<326>":   PN = "CW66"  !CDS_PN = "CW66";
"VSS<327>":   PN = "CW64"  !CDS_PN = "CW64";
"VSS<328>":   PN = "CW54"  !CDS_PN = "CW54";
"VSS<329>":   PN = "CW52"  !CDS_PN = "CW52";
"VSS<330>":   PN = "CW42"  !CDS_PN = "CW42";
"VSS<331>":   PN = "CW40"  !CDS_PN = "CW40";
"VSS<332>":   PN = "CW38"  !CDS_PN = "CW38";
"VSS<333>":   PN = "CW32"  !CDS_PN = "CW32";
"VSS<334>":   PN = "CW26"  !CDS_PN = "CW26";
"VSS<335>":   PN = "CW12"  !CDS_PN = "CW12";
"VSS<336>":   PN = "CV83"  !CDS_PN = "CV83";
"VSS<337>":   PN = "CV81"  !CDS_PN = "CV81";
"VSS<338>":   PN = "CV79"  !CDS_PN = "CV79";
"VSS<339>":   PN = "CV73"  !CDS_PN = "CV73";
"VSS<340>":   PN = "CV67"  !CDS_PN = "CV67";
"VSS<341>":   PN = "CV63"  !CDS_PN = "CV63";
"VSS<342>":   PN = "CV55"  !CDS_PN = "CV55";
"VSS<343>":   PN = "CV53"  !CDS_PN = "CV53";
"VSS<344>":   PN = "CV41"  !CDS_PN = "CV41";
"VSS<345>":   PN = "CV39"  !CDS_PN = "CV39";
"VSS<346>":   PN = "CV37"  !CDS_PN = "CV37";
"VSS<347>":   PN = "CV33"  !CDS_PN = "CV33";
"VSS<348>":   PN = "CV31"  !CDS_PN = "CV31";
"VSS<349>":   PN = "CV27"  !CDS_PN = "CV27";
"VSS<350>":   PN = "CV25"  !CDS_PN = "CV25";
"VSS<351>":   PN = "CV17"  !CDS_PN = "CV17";
"VSS<352>":   PN = "H55"  !CDS_PN = "H55";
"VSS<353>":   PN = "CV1"  !CDS_PN = "CV1";
"VSS<354>":   PN = "CU86"  !CDS_PN = "CU86";
"VSS<355>":   PN = "CU82"  !CDS_PN = "CU82";
"VSS<356>":   PN = "CU80"  !CDS_PN = "CU80";
"VSS<357>":   PN = "CU78"  !CDS_PN = "CU78";
"VSS<358>":   PN = "CU76"  !CDS_PN = "CU76";
"VSS<359>":   PN = "CU68"  !CDS_PN = "CU68";
"VSS<360>":   PN = "CU62"  !CDS_PN = "CU62";
"VSS<361>":   PN = "CU56"  !CDS_PN = "CU56";
"VSS<362>":   PN = "CU36"  !CDS_PN = "CU36";
"VSS<363>":   PN = "CU34"  !CDS_PN = "CU34";
"VSS<364>":   PN = "CU30"  !CDS_PN = "CU30";
"VSS<365>":   PN = "CU28"  !CDS_PN = "CU28";
"VSS<366>":   PN = "CU22"  !CDS_PN = "CU22";
"VSS<367>":   PN = "CU4"  !CDS_PN = "CU4";
"VSS<368>":   PN = "CT85"  !CDS_PN = "CT85";
"VSS<369>":   PN = "CT83"  !CDS_PN = "CT83";
"VSS<370>":   PN = "CT79"  !CDS_PN = "CT79";
"VSS<371>":   PN = "CT73"  !CDS_PN = "CT73";
"VSS<372>":   PN = "CT57"  !CDS_PN = "CT57";
"VSS<373>":   PN = "CT35"  !CDS_PN = "CT35";
"VSS<374>":   PN = "CT33"  !CDS_PN = "CT33";
"VSS<375>":   PN = "CT29"  !CDS_PN = "CT29";
"VSS<376>":   PN = "CT27"  !CDS_PN = "CT27";
"VSS<377>":   PN = "CT19"  !CDS_PN = "CT19";
"VSS<378>":   PN = "CT13"  !CDS_PN = "CT13";
"VSS<379>":   PN = "H57"  !CDS_PN = "H57";
"VSS<380>":   PN = "CR86"  !CDS_PN = "CR86";
"VSS<381>":   PN = "CR78"  !CDS_PN = "CR78";
"VSS<382>":   PN = "CR68"  !CDS_PN = "CR68";
"VSS<383>":   PN = "CR66"  !CDS_PN = "CR66";
"VSS<384>":   PN = "CR64"  !CDS_PN = "CR64";
"VSS<385>":   PN = "CR62"  !CDS_PN = "CR62";
"VSS<386>":   PN = "CR58"  !CDS_PN = "CR58";
"VSS<387>":   PN = "CR32"  !CDS_PN = "CR32";
"VSS<388>":   PN = "CR24"  !CDS_PN = "CR24";
"VSS<389>":   PN = "CR22"  !CDS_PN = "CR22";
"VSS<390>":   PN = "CR10"  !CDS_PN = "CR10";
"VSS<391>":   PN = "CR6"  !CDS_PN = "CR6";
"VSS<392>":   PN = "CP83"  !CDS_PN = "CP83";
"VSS<393>":   PN = "CP81"  !CDS_PN = "CP81";
"VSS<394>":   PN = "CP75"  !CDS_PN = "CP75";
"VSS<395>":   PN = "CP73"  !CDS_PN = "CP73";
"VSS<396>":   PN = "CP69"  !CDS_PN = "CP69";
"VSS<397>":   PN = "CP59"  !CDS_PN = "CP59";
"VSS<398>":   PN = "CP25"  !CDS_PN = "CP25";
"VSS<399>":   PN = "H59"  !CDS_PN = "H59";
"VSS<400>":   PN = "CP1"  !CDS_PN = "CP1";
"VSS<401>":   PN = "CN78"  !CDS_PN = "CN78";
"VSS<402>":   PN = "CN68"  !CDS_PN = "CN68";
"VSS<403>":   PN = "CN62"  !CDS_PN = "CN62";
"VSS<404>":   PN = "CN60"  !CDS_PN = "CN60";
"VSS<405>":   PN = "CN32"  !CDS_PN = "CN32";
"VSS<406>":   PN = "CN26"  !CDS_PN = "CN26";
"VSS<407>":   PN = "H61"  !CDS_PN = "H61";
"VSS<408>":   PN = "CN12"  !CDS_PN = "CN12";
"VSS<409>":   PN = "CN2"  !CDS_PN = "CN2";
"VSS<410>":   PN = "CM85"  !CDS_PN = "CM85";
"VSS<411>":   PN = "CM83"  !CDS_PN = "CM83";
"VSS<412>":   PN = "CM77"  !CDS_PN = "CM77";
"VSS<413>":   PN = "CM73"  !CDS_PN = "CM73";
"VSS<414>":   PN = "CM67"  !CDS_PN = "CM67";
"VSS<415>":   PN = "CM63"  !CDS_PN = "CM63";
"VSS<416>":   PN = "CM61"  !CDS_PN = "CM61";
"VSS<417>":   PN = "CM31"  !CDS_PN = "CM31";
"VSS<418>":   PN = "CM5"  !CDS_PN = "CM5";
"VSS<419>":   PN = "CM29"  !CDS_PN = "CM29";
"VSS<420>":   PN = "CM19"  !CDS_PN = "CM19";
"VSS<421>":   PN = "CL80"  !CDS_PN = "CL80";
"VSS<422>":   PN = "CL78"  !CDS_PN = "CL78";
"VSS<423>":   PN = "CL76"  !CDS_PN = "CL76";
"VSS<424>":   PN = "CL74"  !CDS_PN = "CL74";
"VSS<425>":   PN = "CL66"  !CDS_PN = "CL66";
"VSS<426>":   PN = "CL64"  !CDS_PN = "CL64";
"VSS<427>":   PN = "CL62"  !CDS_PN = "CL62";
"VSS<428>":   PN = "H63"  !CDS_PN = "H63";
"VSS<429>":   PN = "P45"  !CDS_PN = "P45";
"VSS<430>":   PN = "CL18"  !CDS_PN = "CL18";
"VSS<431>":   PN = "CL14"  !CDS_PN = "CL14";
"VSS<432>":   PN = "CL8"  !CDS_PN = "CL8";
"VSS<433>":   PN = "CK85"  !CDS_PN = "CK85";
"VSS<434>":   PN = "CK83"  !CDS_PN = "CK83";
"VSS<435>":   PN = "CK75"  !CDS_PN = "CK75";
"VSS<436>":   PN = "CK73"  !CDS_PN = "CK73";
"VSS<437>":   PN = "CK71"  !CDS_PN = "CK71";
"VSS<438>":   PN = "CK69"  !CDS_PN = "CK69";
"VSS<439>":   PN = "CK67"  !CDS_PN = "CK67";
"VSS<440>":   PN = "CK65"  !CDS_PN = "CK65";
"VSS<441>":   PN = "CK63"  !CDS_PN = "CK63";
"VSS<442>":   PN = "CK27"  !CDS_PN = "CK27";
"VSS<443>":   PN = "CK21"  !CDS_PN = "CK21";
"VSS<444>":   PN = "CK15"  !CDS_PN = "CK15";
"VSS<445>":   PN = "CK11"  !CDS_PN = "CK11";
"VSS<446>":   PN = "CJ86"  !CDS_PN = "CJ86";
"VSS<447>":   PN = "CJ84"  !CDS_PN = "CJ84";
"VSS<448>":   PN = "CJ82"  !CDS_PN = "CJ82";
"VSS<449>":   PN = "CJ78"  !CDS_PN = "CJ78";
"VSS<450>":   PN = "CJ76"  !CDS_PN = "CJ76";
"VSS<451>":   PN = "CJ74"  !CDS_PN = "CJ74";
"VSS<452>":   PN = "CJ62"  !CDS_PN = "CJ62";
"VSS<453>":   PN = "P47"  !CDS_PN = "P47";
BODY = "SKX_EXT_B","I285": #LOCATION = "U5D1" !CDS_LOCATION = "U5D1" #SEC = "29" !CDS_SEC = "29";
"VSS<134>":   PN = "DN72"  !CDS_PN = "DN72";
"VSS<135>":   PN = "DN68"  !CDS_PN = "DN68";
"VSS<136>":   PN = "DN38"  !CDS_PN = "DN38";
"VSS<137>":   PN = "DN32"  !CDS_PN = "DN32";
"VSS<138>":   PN = "DN26"  !CDS_PN = "DN26";
"VSS<139>":   PN = "DN22"  !CDS_PN = "DN22";
"VSS<140>":   PN = "DN12"  !CDS_PN = "DN12";
"VSS<141>":   PN = "BH17"  !CDS_PN = "BH17";
"VSS<142>":   PN = "DN2"  !CDS_PN = "DN2";
"VSS<143>":   PN = "DM83"  !CDS_PN = "DM83";
"VSS<144>":   PN = "DM77"  !CDS_PN = "DM77";
"VSS<145>":   PN = "DM73"  !CDS_PN = "DM73";
"VSS<146>":   PN = "DM65"  !CDS_PN = "DM65";
"VSS<147>":   PN = "DM39"  !CDS_PN = "DM39";
"VSS<148>":   PN = "DM37"  !CDS_PN = "DM37";
"VSS<149>":   PN = "DM33"  !CDS_PN = "DM33";
"VSS<150>":   PN = "DM31"  !CDS_PN = "DM31";
"VSS<151>":   PN = "DM27"  !CDS_PN = "DM27";
"VSS<152>":   PN = "DM25"  !CDS_PN = "DM25";
"VSS<153>":   PN = "H45"  !CDS_PN = "H45";
"VSS<154>":   PN = "DM15"  !CDS_PN = "DM15";
"VSS<155>":   PN = "DL80"  !CDS_PN = "DL80";
"VSS<156>":   PN = "DL78"  !CDS_PN = "DL78";
"VSS<157>":   PN = "DL76"  !CDS_PN = "DL76";
"VSS<158>":   PN = "DL74"  !CDS_PN = "DL74";
"VSS<159>":   PN = "DL70"  !CDS_PN = "DL70";
"VSS<160>":   PN = "DL68"  !CDS_PN = "DL68";
"VSS<161>":   PN = "DL40"  !CDS_PN = "DL40";
"VSS<162>":   PN = "DL36"  !CDS_PN = "DL36";
"VSS<163>":   PN = "DL34"  !CDS_PN = "DL34";
"VSS<164>":   PN = "DL30"  !CDS_PN = "DL30";
"VSS<165>":   PN = "DL28"  !CDS_PN = "DL28";
"VSS<166>":   PN = "DL24"  !CDS_PN = "DL24";
"VSS<167>":   PN = "DL22"  !CDS_PN = "DL22";
"VSS<168>":   PN = "DL4"  !CDS_PN = "DL4";
"VSS<169>":   PN = "DL18"  !CDS_PN = "DL18";
"VSS<170>":   PN = "DL16"  !CDS_PN = "DL16";
"VSS<171>":   PN = "DK85"  !CDS_PN = "DK85";
"VSS<172>":   PN = "DK83"  !CDS_PN = "DK83";
"VSS<173>":   PN = "DK77"  !CDS_PN = "DK77";
"VSS<174>":   PN = "DK75"  !CDS_PN = "DK75";
"VSS<175>":   PN = "DK73"  !CDS_PN = "DK73";
"VSS<176>":   PN = "DK41"  !CDS_PN = "DK41";
"VSS<177>":   PN = "DK39"  !CDS_PN = "DK39";
"VSS<178>":   PN = "DK35"  !CDS_PN = "DK35";
"VSS<179>":   PN = "DK29"  !CDS_PN = "DK29";
"VSS<180>":   PN = "DK23"  !CDS_PN = "DK23";
"VSS<181>":   PN = "DK7"  !CDS_PN = "DK7";
"VSS<182>":   PN = "DJ84"  !CDS_PN = "DJ84";
"VSS<183>":   PN = "DJ82"  !CDS_PN = "DJ82";
"VSS<184>":   PN = "DJ78"  !CDS_PN = "DJ78";
"VSS<185>":   PN = "DJ74"  !CDS_PN = "DJ74";
"VSS<186>":   PN = "DJ68"  !CDS_PN = "DJ68";
"VSS<187>":   PN = "DJ42"  !CDS_PN = "DJ42";
"VSS<188>":   PN = "DJ38"  !CDS_PN = "DJ38";
"VSS<189>":   PN = "DJ22"  !CDS_PN = "DJ22";
"VSS<190>":   PN = "H47"  !CDS_PN = "H47";
"VSS<191>":   PN = "DJ10"  !CDS_PN = "DJ10";
"VSS<192>":   PN = "DJ2"  !CDS_PN = "DJ2";
"VSS<193>":   PN = "DH83"  !CDS_PN = "DH83";
"VSS<194>":   PN = "DH81"  !CDS_PN = "DH81";
"VSS<195>":   PN = "DH79"  !CDS_PN = "DH79";
"VSS<196>":   PN = "DH73"  !CDS_PN = "DH73";
"VSS<197>":   PN = "DH71"  !CDS_PN = "DH71";
"VSS<198>":   PN = "DH67"  !CDS_PN = "DH67";
"VSS<199>":   PN = "DH41"  !CDS_PN = "DH41";
"VSS<200>":   PN = "DH37"  !CDS_PN = "DH37";
"VSS<201>":   PN = "DH35"  !CDS_PN = "DH35";
"VSS<202>":   PN = "DH33"  !CDS_PN = "DH33";
"VSS<203>":   PN = "DH31"  !CDS_PN = "DH31";
"VSS<204>":   PN = "DH29"  !CDS_PN = "DH29";
"VSS<205>":   PN = "DH27"  !CDS_PN = "DH27";
"VSS<206>":   PN = "DH25"  !CDS_PN = "DH25";
"VSS<207>":   PN = "DH23"  !CDS_PN = "DH23";
"VSS<208>":   PN = "DH15"  !CDS_PN = "DH15";
"VSS<209>":   PN = "DH13"  !CDS_PN = "DH13";
"VSS<210>":   PN = "DG82"  !CDS_PN = "DG82";
"VSS<211>":   PN = "DG80"  !CDS_PN = "DG80";
"VSS<212>":   PN = "DG78"  !CDS_PN = "DG78";
"VSS<213>":   PN = "DG76"  !CDS_PN = "DG76";
"VSS<214>":   PN = "DG68"  !CDS_PN = "DG68";
"VSS<215>":   PN = "DG66"  !CDS_PN = "DG66";
"VSS<216>":   PN = "DG24"  !CDS_PN = "DG24";
"VSS<217>":   PN = "DG16"  !CDS_PN = "DG16";
"VSS<218>":   PN = "DG14"  !CDS_PN = "DG14";
"VSS<219>":   PN = "H49"  !CDS_PN = "H49";
"VSS<220>":   PN = "DG2"  !CDS_PN = "DG2";
"VSS<221>":   PN = "DF85"  !CDS_PN = "DF85";
"VSS<222>":   PN = "DF83"  !CDS_PN = "DF83";
"VSS<223>":   PN = "DF79"  !CDS_PN = "DF79";
"VSS<224>":   PN = "DF73"  !CDS_PN = "DF73";
"VSS<225>":   PN = "DF69"  !CDS_PN = "DF69";
"VSS<226>":   PN = "DF65"  !CDS_PN = "DF65";
"VSS<227>":   PN = "DF41"  !CDS_PN = "DF41";
"VSS<228>":   PN = "DF39"  !CDS_PN = "DF39";
"VSS<229>":   PN = "DF37"  !CDS_PN = "DF37";
"VSS<230>":   PN = "DF35"  !CDS_PN = "DF35";
"VSS<231>":   PN = "DF29"  !CDS_PN = "DF29";
"VSS<232>":   PN = "DF19"  !CDS_PN = "DF19";
"VSS<233>":   PN = "H51"  !CDS_PN = "H51";
"VSS<234>":   PN = "DF7"  !CDS_PN = "DF7";
"VSS<235>":   PN = "DF5"  !CDS_PN = "DF5";
"VSS<236>":   PN = "DE78"  !CDS_PN = "DE78";
"VSS<237>":   PN = "DE72"  !CDS_PN = "DE72";
"VSS<238>":   PN = "DE70"  !CDS_PN = "DE70";
"VSS<239>":   PN = "DE64"  !CDS_PN = "DE64";
"VSS<240>":   PN = "DE36"  !CDS_PN = "DE36";
"VSS<241>":   PN = "DE34"  !CDS_PN = "DE34";
"VSS<242>":   PN = "DE30"  !CDS_PN = "DE30";
"VSS<243>":   PN = "DE28"  !CDS_PN = "DE28";
"VSS<244>":   PN = "DE24"  !CDS_PN = "DE24";
"VSS<245>":   PN = "DE20"  !CDS_PN = "DE20";
"VSS<246>":   PN = "DE18"  !CDS_PN = "DE18";
"VSS<247>":   PN = "DE8"  !CDS_PN = "DE8";
"VSS<248>":   PN = "DE6"  !CDS_PN = "DE6";
"VSS<249>":   PN = "DD83"  !CDS_PN = "DD83";
"VSS<250>":   PN = "DD81"  !CDS_PN = "DD81";
"VSS<251>":   PN = "DD75"  !CDS_PN = "DD75";
"VSS<252>":   PN = "DD73"  !CDS_PN = "DD73";
"VSS<253>":   PN = "DD71"  !CDS_PN = "DD71";
"VSS<254>":   PN = "DD37"  !CDS_PN = "DD37";
"VSS<255>":   PN = "DD33"  !CDS_PN = "DD33";
"VSS<256>":   PN = "DD31"  !CDS_PN = "DD31";
"VSS<257>":   PN = "DD27"  !CDS_PN = "DD27";
"VSS<258>":   PN = "DD23"  !CDS_PN = "DD23";
"VSS<259>":   PN = "DD11"  !CDS_PN = "DD11";
"VSS<260>":   PN = "DC86"  !CDS_PN = "DC86";
"VSS<261>":   PN = "DC84"  !CDS_PN = "DC84";
"VSS<262>":   PN = "DC78"  !CDS_PN = "DC78";
"VSS<263>":   PN = "DC70"  !CDS_PN = "DC70";
"VSS<264>":   PN = "DC68"  !CDS_PN = "DC68";
"VSS<265>":   PN = "DC66"  !CDS_PN = "DC66";
"VSS<266>":   PN = "DC64"  !CDS_PN = "DC64";
"VSS<267>":   PN = "DC42"  !CDS_PN = "DC42";
"VSS<268>":   PN = "DC38"  !CDS_PN = "DC38";
"VSS<269>":   PN = "DC32"  !CDS_PN = "DC32";
"VSS<270>":   PN = "DC26"  !CDS_PN = "DC26";
"VSS<271>":   PN = "DC24"  !CDS_PN = "DC24";
"VSS<272>":   PN = "DC14"  !CDS_PN = "DC14";
"VSS<273>":   PN = "DB85"  !CDS_PN = "DB85";
"VSS<274>":   PN = "DB83"  !CDS_PN = "DB83";
"VSS<275>":   PN = "DB77"  !CDS_PN = "DB77";
"VSS<276>":   PN = "DB73"  !CDS_PN = "DB73";
"VSS<277>":   PN = "DB49"  !CDS_PN = "DB49";
"VSS<278>":   PN = "DB47"  !CDS_PN = "DB47";
"VSS<279>":   PN = "DB41"  !CDS_PN = "DB41";
"VSS<280>":   PN = "DB39"  !CDS_PN = "DB39";
"VSS<281>":   PN = "DB25"  !CDS_PN = "DB25";
"VSS<282>":   PN = "DB23"  !CDS_PN = "DB23";
"VSS<283>":   PN = "DB17"  !CDS_PN = "DB17";
"VSS<284>":   PN = "DB13"  !CDS_PN = "DB13";
"VSS<285>":   PN = "DB3"  !CDS_PN = "DB3";
"VSS<286>":   PN = "DA80"  !CDS_PN = "DA80";
"VSS<287>":   PN = "DA78"  !CDS_PN = "DA78";
"VSS<288>":   PN = "DA76"  !CDS_PN = "DA76";
"VSS<289>":   PN = "DA74"  !CDS_PN = "DA74";
"VSS<290>":   PN = "DA70"  !CDS_PN = "DA70";
"VSS<291>":   PN = "DA64"  !CDS_PN = "DA64";
"VSS<292>":   PN = "DA50"  !CDS_PN = "DA50";
"VSS<293>":   PN = "DA48"  !CDS_PN = "DA48";
BODY = "SKX_EXT_B","I286": #LOCATION = "U5D1" !CDS_LOCATION = "U5D1" #SEC = "30" !CDS_SEC = "30";
"VSS<0>":   PN = "EF79"  !CDS_PN = "EF79";
"VSS<1>":   PN = "EF75"  !CDS_PN = "EF75";
"VSS<2>":   PN = "EF71"  !CDS_PN = "EF71";
"VSS<3>":   PN = "EE78"  !CDS_PN = "EE78";
"VSS<4>":   PN = "EE76"  !CDS_PN = "EE76";
"VSS<5>":   PN = "EE70"  !CDS_PN = "EE70";
"VSS<6>":   PN = "EE36"  !CDS_PN = "EE36";
"VSS<7>":   PN = "EE34"  !CDS_PN = "EE34";
"VSS<8>":   PN = "EE30"  !CDS_PN = "EE30";
"VSS<9>":   PN = "EE28"  !CDS_PN = "EE28";
"VSS<10>":   PN = "EE24"  !CDS_PN = "EE24";
"VSS<11>":   PN = "ED77"  !CDS_PN = "ED77";
"VSS<12>":   PN = "ED35"  !CDS_PN = "ED35";
"VSS<13>":   PN = "ED29"  !CDS_PN = "ED29";
"VSS<14>":   PN = "ED23"  !CDS_PN = "ED23";
"VSS<15>":   PN = "ED15"  !CDS_PN = "ED15";
"VSS<16>":   PN = "ED11"  !CDS_PN = "ED11";
"VSS<17>":   PN = "EC76"  !CDS_PN = "EC76";
"VSS<18>":   PN = "EC74"  !CDS_PN = "EC74";
"VSS<19>":   PN = "EC72"  !CDS_PN = "EC72";
"VSS<20>":   PN = "EC70"  !CDS_PN = "EC70";
"VSS<21>":   PN = "EC10"  !CDS_PN = "EC10";
"VSS<22>":   PN = "EB69"  !CDS_PN = "EB69";
"VSS<23>":   PN = "EB65"  !CDS_PN = "EB65";
"VSS<24>":   PN = "EB41"  !CDS_PN = "EB41";
"VSS<25>":   PN = "EB39"  !CDS_PN = "EB39";
"VSS<26>":   PN = "EB37"  !CDS_PN = "EB37";
"VSS<27>":   PN = "EB35"  !CDS_PN = "EB35";
"VSS<28>":   PN = "EB33"  !CDS_PN = "EB33";
"VSS<29>":   PN = "EB31"  !CDS_PN = "EB31";
"VSS<30>":   PN = "EB29"  !CDS_PN = "EB29";
"VSS<31>":   PN = "EB27"  !CDS_PN = "EB27";
"VSS<32>":   PN = "EB25"  !CDS_PN = "EB25";
"VSS<33>":   PN = "EB23"  !CDS_PN = "EB23";
"VSS<34>":   PN = "BR18"  !CDS_PN = "BR18";
"VSS<35>":   PN = "EB13"  !CDS_PN = "EB13";
"VSS<36>":   PN = "EA82"  !CDS_PN = "EA82";
"VSS<37>":   PN = "EA80"  !CDS_PN = "EA80";
"VSS<38>":   PN = "EA78"  !CDS_PN = "EA78";
"VSS<39>":   PN = "EA76"  !CDS_PN = "EA76";
"VSS<40>":   PN = "EA70"  !CDS_PN = "EA70";
"VSS<41>":   PN = "EA64"  !CDS_PN = "EA64";
"VSS<42>":   PN = "EA42"  !CDS_PN = "EA42";
"VSS<43>":   PN = "EA22"  !CDS_PN = "EA22";
"VSS<44>":   PN = "EA20"  !CDS_PN = "EA20";
"VSS<45>":   PN = "EA16"  !CDS_PN = "EA16";
"VSS<46>":   PN = "J16"  !CDS_PN = "J16";
"VSS<47>":   PN = "EA6"  !CDS_PN = "EA6";
"VSS<48>":   PN = "DY75"  !CDS_PN = "DY75";
"VSS<49>":   PN = "DY71"  !CDS_PN = "DY71";
"VSS<50>":   PN = "DY41"  !CDS_PN = "DY41";
"VSS<51>":   PN = "DY35"  !CDS_PN = "DY35";
"VSS<52>":   PN = "DY29"  !CDS_PN = "DY29";
"VSS<53>":   PN = "DY23"  !CDS_PN = "DY23";
"VSS<54>":   PN = "DY19"  !CDS_PN = "DY19";
"VSS<55>":   PN = "DY5"  !CDS_PN = "DY5";
"VSS<56>":   PN = "DW84"  !CDS_PN = "DW84";
"VSS<57>":   PN = "DW82"  !CDS_PN = "DW82";
"VSS<58>":   PN = "DW8"  !CDS_PN = "DW8";
"VSS<59>":   PN = "DW76"  !CDS_PN = "DW76";
"VSS<60>":   PN = "DW74"  !CDS_PN = "DW74";
"VSS<61>":   PN = "DW72"  !CDS_PN = "DW72";
"VSS<62>":   PN = "DW70"  !CDS_PN = "DW70";
"VSS<63>":   PN = "DW68"  !CDS_PN = "DW68";
"VSS<64>":   PN = "DW66"  !CDS_PN = "DW66";
"VSS<65>":   PN = "DW64"  !CDS_PN = "DW64";
"VSS<66>":   PN = "DW40"  !CDS_PN = "DW40";
"VSS<67>":   PN = "DW36"  !CDS_PN = "DW36";
"VSS<68>":   PN = "DW34"  !CDS_PN = "DW34";
"VSS<69>":   PN = "DW30"  !CDS_PN = "DW30";
"VSS<70>":   PN = "DW28"  !CDS_PN = "DW28";
"VSS<71>":   PN = "DW24"  !CDS_PN = "DW24";
"VSS<72>":   PN = "DW20"  !CDS_PN = "DW20";
"VSS<73>":   PN = "DW12"  !CDS_PN = "DW12";
"VSS<74>":   PN = "DV81"  !CDS_PN = "DV81";
"VSS<75>":   PN = "DV77"  !CDS_PN = "DV77";
"VSS<76>":   PN = "DV73"  !CDS_PN = "DV73";
"VSS<77>":   PN = "DV39"  !CDS_PN = "DV39";
"VSS<78>":   PN = "DV37"  !CDS_PN = "DV37";
"VSS<79>":   PN = "DV33"  !CDS_PN = "DV33";
"VSS<80>":   PN = "DV31"  !CDS_PN = "DV31";
"VSS<81>":   PN = "DV27"  !CDS_PN = "DV27";
"VSS<82>":   PN = "DV25"  !CDS_PN = "DV25";
"VSS<83>":   PN = "DV21"  !CDS_PN = "DV21";
"VSS<84>":   PN = "DU84"  !CDS_PN = "DU84";
"VSS<85>":   PN = "DU82"  !CDS_PN = "DU82";
"VSS<86>":   PN = "DU80"  !CDS_PN = "DU80";
"VSS<87>":   PN = "DU78"  !CDS_PN = "DU78";
"VSS<88>":   PN = "DU72"  !CDS_PN = "DU72";
"VSS<89>":   PN = "DU70"  !CDS_PN = "DU70";
"VSS<90>":   PN = "DU38"  !CDS_PN = "DU38";
"VSS<91>":   PN = "DU32"  !CDS_PN = "DU32";
"VSS<92>":   PN = "DU26"  !CDS_PN = "DU26";
"VSS<93>":   PN = "DU22"  !CDS_PN = "DU22";
"VSS<94>":   PN = "CN14"  !CDS_PN = "CN14";
"VSS<95>":   PN = "DU14"  !CDS_PN = "DU14";
"VSS<96>":   PN = "DU10"  !CDS_PN = "DU10";
"VSS<97>":   PN = "DT85"  !CDS_PN = "DT85";
"VSS<98>":   PN = "DT83"  !CDS_PN = "DT83";
"VSS<99>":   PN = "DT79"  !CDS_PN = "DT79";
"VSS<100>":   PN = "DT69"  !CDS_PN = "DT69";
"VSS<101>":   PN = "DT65"  !CDS_PN = "DT65";
"VSS<102>":   PN = "DH21"  !CDS_PN = "DH21";
"VSS<103>":   PN = "DT17"  !CDS_PN = "DT17";
"VSS<104>":   PN = "DT3"  !CDS_PN = "DT3";
"VSS<105>":   PN = "DR78"  !CDS_PN = "DR78";
"VSS<106>":   PN = "DR76"  !CDS_PN = "DR76";
"VSS<107>":   PN = "DR74"  !CDS_PN = "DR74";
"VSS<108>":   PN = "DR72"  !CDS_PN = "DR72";
"VSS<109>":   PN = "DR70"  !CDS_PN = "DR70";
"VSS<110>":   PN = "DR68"  !CDS_PN = "DR68";
"VSS<111>":   PN = "DR66"  !CDS_PN = "DR66";
"VSS<112>":   PN = "DR42"  !CDS_PN = "DR42";
"VSS<113>":   PN = "DR40"  !CDS_PN = "DR40";
"VSS<114>":   PN = "DR38"  !CDS_PN = "DR38";
"VSS<115>":   PN = "DR36"  !CDS_PN = "DR36";
"VSS<116>":   PN = "DR34"  !CDS_PN = "DR34";
"VSS<117>":   PN = "DR32"  !CDS_PN = "DR32";
"VSS<118>":   PN = "DR30"  !CDS_PN = "DR30";
"VSS<119>":   PN = "DR28"  !CDS_PN = "DR28";
"VSS<120>":   PN = "DR26"  !CDS_PN = "DR26";
"VSS<121>":   PN = "DR24"  !CDS_PN = "DR24";
"VSS<122>":   PN = "DR22"  !CDS_PN = "DR22";
"VSS<123>":   PN = "DR20"  !CDS_PN = "DR20";
"VSS<124>":   PN = "CL22"  !CDS_PN = "CL22";
"VSS<125>":   PN = "CA20"  !CDS_PN = "CA20";
"VSS<126>":   PN = "DR6"  !CDS_PN = "DR6";
"VSS<127>":   PN = "BR26"  !CDS_PN = "BR26";
"VSS<128>":   PN = "DP83"  !CDS_PN = "DP83";
"VSS<129>":   PN = "DP81"  !CDS_PN = "DP81";
"VSS<130>":   PN = "DP71"  !CDS_PN = "DP71";
"VSS<131>":   PN = "DP69"  !CDS_PN = "DP69";
"VSS<132>":   PN = "DP67"  !CDS_PN = "DP67";
"VSS<133>":   PN = "DN78"  !CDS_PN = "DN78";
DRAWING = "@baseboard_fab2_lib.baseboard_fab2(sch_1):page42";
BODY = "CAP","I10": #LOCATION = "C4P1" !CDS_LOCATION = "C4P1" &SEC = "1" #&CDS_SEC = "1";
"A":   PN = "1"  !CDS_PN = "1";
"B":   PN = "2"  !CDS_PN = "2";
BODY = "CAP","I12": #LOCATION = "C4P9" !CDS_LOCATION = "C4P9" &SEC = "1" #&CDS_SEC = "1";
"A":   PN = "1"  !CDS_PN = "1";
"B":   PN = "2"  !CDS_PN = "2";
BODY = "CAP","I17": #LOCATION = "C4P10" !CDS_LOCATION = "C4P10" &SEC = "1" #&CDS_SEC = "1";
"A":   PN = "1"  !CDS_PN = "1";
"B":   PN = "2"  !CDS_PN = "2";
BODY = "CAP","I25": #LOCATION = "C5P7" !CDS_LOCATION = "C5P7" &SEC = "1" #&CDS_SEC = "1";
"A":   PN = "1"  !CDS_PN = "1";
"B":   PN = "2"  !CDS_PN = "2";
BODY = "CAP","I28": #LOCATION = "C5P23" !CDS_LOCATION = "C5P23" &SEC = "1" #&CDS_SEC = "1";
"A":   PN = "1"  !CDS_PN = "1";
"B":   PN = "2"  !CDS_PN = "2";
BODY = "CAP","I33": #LOCATION = "C5P24" !CDS_LOCATION = "C5P24" &SEC = "1" #&CDS_SEC = "1";
"A":   PN = "1"  !CDS_PN = "1";
"B":   PN = "2"  !CDS_PN = "2";
BODY = "CAP","I37": #LOCATION = "C5P25" !CDS_LOCATION = "C5P25" &SEC = "1" #&CDS_SEC = "1";
"A":   PN = "1"  !CDS_PN = "1";
"B":   PN = "2"  !CDS_PN = "2";
BODY = "CAP","I41": #LOCATION = "C5P14" !CDS_LOCATION = "C5P14" &SEC = "1" #&CDS_SEC = "1";
"A":   PN = "1"  !CDS_PN = "1";
"B":   PN = "2"  !CDS_PN = "2";
BODY = "CAP","I44": #LOCATION = "C5P27" !CDS_LOCATION = "C5P27" &SEC = "1" #&CDS_SEC = "1";
"A":   PN = "1"  !CDS_PN = "1";
"B":   PN = "2"  !CDS_PN = "2";
BODY = "CAP","I50": #LOCATION = "C5P33" !CDS_LOCATION = "C5P33" &SEC = "1" #&CDS_SEC = "1";
"A":   PN = "1"  !CDS_PN = "1";
"B":   PN = "2"  !CDS_PN = "2";
BODY = "CAP","I51": #LOCATION = "C5P35" !CDS_LOCATION = "C5P35" &SEC = "1" #&CDS_SEC = "1";
"A":   PN = "1"  !CDS_PN = "1";
"B":   PN = "2"  !CDS_PN = "2";
BODY = "CAP","I53": #LOCATION = "C5P32" !CDS_LOCATION = "C5P32" &SEC = "1" #&CDS_SEC = "1";
"A":   PN = "1"  !CDS_PN = "1";
"B":   PN = "2"  !CDS_PN = "2";
BODY = "CAP","I54": #LOCATION = "C5P34" !CDS_LOCATION = "C5P34" &SEC = "1" #&CDS_SEC = "1";
"A":   PN = "1"  !CDS_PN = "1";
"B":   PN = "2"  !CDS_PN = "2";
BODY = "CAP","I55": #LOCATION = "C5P22" !CDS_LOCATION = "C5P22" &SEC = "1" #&CDS_SEC = "1";
"A":   PN = "1"  !CDS_PN = "1";
"B":   PN = "2"  !CDS_PN = "2";
BODY = "CAP","I56": #LOCATION = "C5P26" !CDS_LOCATION = "C5P26" &SEC = "1" #&CDS_SEC = "1";
"A":   PN = "1"  !CDS_PN = "1";
"B":   PN = "2"  !CDS_PN = "2";
BODY = "CAP","I57": #LOCATION = "C5P40" !CDS_LOCATION = "C5P40" &SEC = "1" #&CDS_SEC = "1";
"A":   PN = "1"  !CDS_PN = "1";
"B":   PN = "2"  !CDS_PN = "2";
BODY = "CAP","I63": #LOCATION = "C5P37" !CDS_LOCATION = "C5P37" &SEC = "1" #&CDS_SEC = "1";
"A":   PN = "1"  !CDS_PN = "1";
"B":   PN = "2"  !CDS_PN = "2";
BODY = "CAP","I65": #LOCATION = "C5P36" !CDS_LOCATION = "C5P36" &SEC = "1" #&CDS_SEC = "1";
"A":   PN = "1"  !CDS_PN = "1";
"B":   PN = "2"  !CDS_PN = "2";
BODY = "CAP_A","I68": #LOCATION = "C6D8" !CDS_LOCATION = "C6D8" &SEC = "1" #&CDS_SEC = "1";
"A":   PN = "1"  !CDS_PN = "1";
"B":   PN = "2"  !CDS_PN = "2";
BODY = "CAP_A","I69": #LOCATION = "C5D38" !CDS_LOCATION = "C5D38" &SEC = "1" #&CDS_SEC = "1";
"A":   PN = "1"  !CDS_PN = "1";
"B":   PN = "2"  !CDS_PN = "2";
BODY = "CAP_A","I70": #LOCATION = "C5D37" !CDS_LOCATION = "C5D37" &SEC = "1" #&CDS_SEC = "1";
"A":   PN = "1"  !CDS_PN = "1";
"B":   PN = "2"  !CDS_PN = "2";
BODY = "CAP_A","I72": #LOCATION = "C6D7" !CDS_LOCATION = "C6D7" &SEC = "1" #&CDS_SEC = "1";
"A":   PN = "1"  !CDS_PN = "1";
"B":   PN = "2"  !CDS_PN = "2";
BODY = "CAP_A","I74": #LOCATION = "C6D4" !CDS_LOCATION = "C6D4" &SEC = "1" #&CDS_SEC = "1";
"A":   PN = "1"  !CDS_PN = "1";
"B":   PN = "2"  !CDS_PN = "2";
BODY = "CAP_A","I75": #LOCATION = "C6D5" !CDS_LOCATION = "C6D5" &SEC = "1" #&CDS_SEC = "1";
"A":   PN = "1"  !CDS_PN = "1";
"B":   PN = "2"  !CDS_PN = "2";
BODY = "CAP_A","I77": #LOCATION = "C6D2" !CDS_LOCATION = "C6D2" &SEC = "1" #&CDS_SEC = "1";
"A":   PN = "1"  !CDS_PN = "1";
"B":   PN = "2"  !CDS_PN = "2";
BODY = "CAP_A","I80": #LOCATION = "C6D3" !CDS_LOCATION = "C6D3" &SEC = "1" #&CDS_SEC = "1";
"A":   PN = "1"  !CDS_PN = "1";
"B":   PN = "2"  !CDS_PN = "2";
BODY = "CAP_A","I81": #LOCATION = "C6D6" !CDS_LOCATION = "C6D6" &SEC = "1" #&CDS_SEC = "1";
"A":   PN = "1"  !CDS_PN = "1";
"B":   PN = "2"  !CDS_PN = "2";
BODY = "CAP_A","I83": #LOCATION = "C5D51" !CDS_LOCATION = "C5D51" &SEC = "1" #&CDS_SEC = "1";
"A":   PN = "1"  !CDS_PN = "1";
"B":   PN = "2"  !CDS_PN = "2";
BODY = "CAP_A","I88": #LOCATION = "C5D21" !CDS_LOCATION = "C5D21" &SEC = "1" #&CDS_SEC = "1";
"A":   PN = "1"  !CDS_PN = "1";
"B":   PN = "2"  !CDS_PN = "2";
BODY = "CAP_A","I89": #LOCATION = "C5D50" !CDS_LOCATION = "C5D50" &SEC = "1" #&CDS_SEC = "1";
"A":   PN = "1"  !CDS_PN = "1";
"B":   PN = "2"  !CDS_PN = "2";
BODY = "CAP_A","I90": #LOCATION = "C5D48" !CDS_LOCATION = "C5D48" &SEC = "1" #&CDS_SEC = "1";
"A":   PN = "1"  !CDS_PN = "1";
"B":   PN = "2"  !CDS_PN = "2";
BODY = "CAP","I91": #LOCATION = "C5D13" !CDS_LOCATION = "C5D13" &SEC = "1" #&CDS_SEC = "1";
"A":   PN = "1"  !CDS_PN = "1";
"B":   PN = "2"  !CDS_PN = "2";
BODY = "CAP","I93": #LOCATION = "C5D11" !CDS_LOCATION = "C5D11" &SEC = "1" #&CDS_SEC = "1";
"A":   PN = "1"  !CDS_PN = "1";
"B":   PN = "2"  !CDS_PN = "2";
BODY = "CAP","I94": #LOCATION = "C5D12" !CDS_LOCATION = "C5D12" &SEC = "1" #&CDS_SEC = "1";
"A":   PN = "1"  !CDS_PN = "1";
"B":   PN = "2"  !CDS_PN = "2";
BODY = "CAP_A","I98": #LOCATION = "C5D23" !CDS_LOCATION = "C5D23" &SEC = "1" #&CDS_SEC = "1";
"A":   PN = "1"  !CDS_PN = "1";
"B":   PN = "2"  !CDS_PN = "2";
BODY = "CAP_A","I100": #LOCATION = "C5D28" !CDS_LOCATION = "C5D28" &SEC = "1" #&CDS_SEC = "1";
"A":   PN = "1"  !CDS_PN = "1";
"B":   PN = "2"  !CDS_PN = "2";
BODY = "CAP_A","I102": #LOCATION = "C5D29" !CDS_LOCATION = "C5D29" &SEC = "1" #&CDS_SEC = "1";
"A":   PN = "1"  !CDS_PN = "1";
"B":   PN = "2"  !CDS_PN = "2";
BODY = "CAP_A","I103": #LOCATION = "C5D32" !CDS_LOCATION = "C5D32" &SEC = "1" #&CDS_SEC = "1";
"A":   PN = "1"  !CDS_PN = "1";
"B":   PN = "2"  !CDS_PN = "2";
BODY = "CAP_A","I104": #LOCATION = "C5D47" !CDS_LOCATION = "C5D47" &SEC = "1" #&CDS_SEC = "1";
"A":   PN = "1"  !CDS_PN = "1";
"B":   PN = "2"  !CDS_PN = "2";
BODY = "CAP_A","I106": #LOCATION = "C5D31" !CDS_LOCATION = "C5D31" &SEC = "1" #&CDS_SEC = "1";
"A":   PN = "1"  !CDS_PN = "1";
"B":   PN = "2"  !CDS_PN = "2";
BODY = "CAP_A","I107": #LOCATION = "C5D46" !CDS_LOCATION = "C5D46" &SEC = "1" #&CDS_SEC = "1";
"A":   PN = "1"  !CDS_PN = "1";
"B":   PN = "2"  !CDS_PN = "2";
BODY = "CAP","I108": #LOCATION = "C5D10" !CDS_LOCATION = "C5D10" &SEC = "1" #&CDS_SEC = "1";
"A":   PN = "1"  !CDS_PN = "1";
"B":   PN = "2"  !CDS_PN = "2";
BODY = "CAP_A","I109": #LOCATION = "C5D27" !CDS_LOCATION = "C5D27" &SEC = "1" #&CDS_SEC = "1";
"A":   PN = "1"  !CDS_PN = "1";
"B":   PN = "2"  !CDS_PN = "2";
BODY = "CAP_A","I111": #LOCATION = "C5D30" !CDS_LOCATION = "C5D30" &SEC = "1" #&CDS_SEC = "1";
"A":   PN = "1"  !CDS_PN = "1";
"B":   PN = "2"  !CDS_PN = "2";
BODY = "CAP_A","I114": #LOCATION = "C5D41" !CDS_LOCATION = "C5D41" &SEC = "1" #&CDS_SEC = "1";
"A":   PN = "1"  !CDS_PN = "1";
"B":   PN = "2"  !CDS_PN = "2";
BODY = "CAP_A","I115": #LOCATION = "C5D40" !CDS_LOCATION = "C5D40" &SEC = "1" #&CDS_SEC = "1";
"A":   PN = "1"  !CDS_PN = "1";
"B":   PN = "2"  !CDS_PN = "2";
BODY = "CAP_A","I117": #LOCATION = "C5D14" !CDS_LOCATION = "C5D14" &SEC = "1" #&CDS_SEC = "1";
"A":   PN = "1"  !CDS_PN = "1";
"B":   PN = "2"  !CDS_PN = "2";
BODY = "CAP_A","I118": #LOCATION = "C5D17" !CDS_LOCATION = "C5D17" &SEC = "1" #&CDS_SEC = "1";
"A":   PN = "1"  !CDS_PN = "1";
"B":   PN = "2"  !CDS_PN = "2";
BODY = "CAP_A","I123": #LOCATION = "C5D16" !CDS_LOCATION = "C5D16" &SEC = "1" #&CDS_SEC = "1";
"A":   PN = "1"  !CDS_PN = "1";
"B":   PN = "2"  !CDS_PN = "2";
BODY = "CAP_A","I125": #LOCATION = "C5D5" !CDS_LOCATION = "C5D5" &SEC = "1" #&CDS_SEC = "1";
"A":   PN = "1"  !CDS_PN = "1";
"B":   PN = "2"  !CDS_PN = "2";
BODY = "CAP_A","I128": #LOCATION = "C5D19" !CDS_LOCATION = "C5D19" &SEC = "1" #&CDS_SEC = "1";
"A":   PN = "1"  !CDS_PN = "1";
"B":   PN = "2"  !CDS_PN = "2";
BODY = "CAP_A","I131": #LOCATION = "C5D43" !CDS_LOCATION = "C5D43" &SEC = "1" #&CDS_SEC = "1";
"A":   PN = "1"  !CDS_PN = "1";
"B":   PN = "2"  !CDS_PN = "2";
BODY = "CAP_A","I132": #LOCATION = "C5D15" !CDS_LOCATION = "C5D15" &SEC = "1" #&CDS_SEC = "1";
"A":   PN = "1"  !CDS_PN = "1";
"B":   PN = "2"  !CDS_PN = "2";
BODY = "CAP_A","I134": #LOCATION = "C5D18" !CDS_LOCATION = "C5D18" &SEC = "1" #&CDS_SEC = "1";
"A":   PN = "1"  !CDS_PN = "1";
"B":   PN = "2"  !CDS_PN = "2";
BODY = "CAP_A","I135": #LOCATION = "C5D42" !CDS_LOCATION = "C5D42" &SEC = "1" #&CDS_SEC = "1";
"A":   PN = "1"  !CDS_PN = "1";
"B":   PN = "2"  !CDS_PN = "2";
BODY = "CAP_A","I138": #LOCATION = "C5D24" !CDS_LOCATION = "C5D24" &SEC = "1" #&CDS_SEC = "1";
"A":   PN = "1"  !CDS_PN = "1";
"B":   PN = "2"  !CDS_PN = "2";
BODY = "CAP_A","I140": #LOCATION = "C5D39" !CDS_LOCATION = "C5D39" &SEC = "1" #&CDS_SEC = "1";
"A":   PN = "1"  !CDS_PN = "1";
"B":   PN = "2"  !CDS_PN = "2";
BODY = "CAP_A","I142": #LOCATION = "C5D44" !CDS_LOCATION = "C5D44" &SEC = "1" #&CDS_SEC = "1";
"A":   PN = "1"  !CDS_PN = "1";
"B":   PN = "2"  !CDS_PN = "2";
BODY = "CAP_A","I145": #LOCATION = "C6D9" !CDS_LOCATION = "C6D9" &SEC = "1" #&CDS_SEC = "1";
"A":   PN = "1"  !CDS_PN = "1";
"B":   PN = "2"  !CDS_PN = "2";
BODY = "CAP_A","I147": #LOCATION = "C6D10" !CDS_LOCATION = "C6D10" &SEC = "1" #&CDS_SEC = "1";
"A":   PN = "1"  !CDS_PN = "1";
"B":   PN = "2"  !CDS_PN = "2";
BODY = "CAP_A","I151": #LOCATION = "C5D36" !CDS_LOCATION = "C5D36" &SEC = "1" #&CDS_SEC = "1";
"A":   PN = "1"  !CDS_PN = "1";
"B":   PN = "2"  !CDS_PN = "2";
BODY = "CAP_A","I152": #LOCATION = "C5D49" !CDS_LOCATION = "C5D49" &SEC = "1" #&CDS_SEC = "1";
"A":   PN = "1"  !CDS_PN = "1";
"B":   PN = "2"  !CDS_PN = "2";
BODY = "CAP_A","I153": #LOCATION = "C5D22" !CDS_LOCATION = "C5D22" &SEC = "1" #&CDS_SEC = "1";
"A":   PN = "1"  !CDS_PN = "1";
"B":   PN = "2"  !CDS_PN = "2";
BODY = "CAP_A","I154": #LOCATION = "C5D26" !CDS_LOCATION = "C5D26" &SEC = "1" #&CDS_SEC = "1";
"A":   PN = "1"  !CDS_PN = "1";
"B":   PN = "2"  !CDS_PN = "2";
BODY = "CAP_A","I155": #LOCATION = "C5D25" !CDS_LOCATION = "C5D25" &SEC = "1" #&CDS_SEC = "1";
"A":   PN = "1"  !CDS_PN = "1";
"B":   PN = "2"  !CDS_PN = "2";
BODY = "CAP_A","I156": #LOCATION = "C5D45" !CDS_LOCATION = "C5D45" &SEC = "1" #&CDS_SEC = "1";
"A":   PN = "1"  !CDS_PN = "1";
"B":   PN = "2"  !CDS_PN = "2";
BODY = "CAP_A","I164": #LOCATION = "C4P6" !CDS_LOCATION = "C4P6" &SEC = "1" #&CDS_SEC = "1";
"A":   PN = "1"  !CDS_PN = "1";
"B":   PN = "2"  !CDS_PN = "2";
BODY = "CAP_A","I173": #LOCATION = "C5D20" !CDS_LOCATION = "C5D20" &SEC = "1" #&CDS_SEC = "1";
"A":   PN = "1"  !CDS_PN = "1";
"B":   PN = "2"  !CDS_PN = "2";
BODY = "CAP_A","I174": #LOCATION = "C5D33" !CDS_LOCATION = "C5D33" &SEC = "1" #&CDS_SEC = "1";
"A":   PN = "1"  !CDS_PN = "1";
"B":   PN = "2"  !CDS_PN = "2";
BODY = "CAP_A","I175": #LOCATION = "C5D34" !CDS_LOCATION = "C5D34" &SEC = "1" #&CDS_SEC = "1";
"A":   PN = "1"  !CDS_PN = "1";
"B":   PN = "2"  !CDS_PN = "2";
BODY = "CAP_A","I176": #LOCATION = "C5D35" !CDS_LOCATION = "C5D35" &SEC = "1" #&CDS_SEC = "1";
"A":   PN = "1"  !CDS_PN = "1";
"B":   PN = "2"  !CDS_PN = "2";
BODY = "CAP_A","I178": #LOCATION = "C4P8" !CDS_LOCATION = "C4P8" &SEC = "1" #&CDS_SEC = "1";
"A":   PN = "1"  !CDS_PN = "1";
"B":   PN = "2"  !CDS_PN = "2";
BODY = "CAP_A","I179": #LOCATION = "C5D53" !CDS_LOCATION = "C5D53" &SEC = "1" #&CDS_SEC = "1";
"A":   PN = "1"  !CDS_PN = "1";
"B":   PN = "2"  !CDS_PN = "2";
BODY = "CAP_A","I180": #LOCATION = "C5D52" !CDS_LOCATION = "C5D52" &SEC = "1" #&CDS_SEC = "1";
"A":   PN = "1"  !CDS_PN = "1";
"B":   PN = "2"  !CDS_PN = "2";
BODY = "CAP","I187": #LOCATION = "C5P15" !CDS_LOCATION = "C5P15" #SEC = "1" !CDS_SEC = "1";
"A":   PN = "1"  !CDS_PN = "1";
"B":   PN = "2"  !CDS_PN = "2";
BODY = "CAP","I188": #LOCATION = "C5P16" !CDS_LOCATION = "C5P16" #SEC = "1" !CDS_SEC = "1";
"A":   PN = "1"  !CDS_PN = "1";
"B":   PN = "2"  !CDS_PN = "2";
BODY = "CAP","I190": #LOCATION = "C5P17" !CDS_LOCATION = "C5P17" #SEC = "1" !CDS_SEC = "1";
"A":   PN = "1"  !CDS_PN = "1";
"B":   PN = "2"  !CDS_PN = "2";
BODY = "CAP","I211": #LOCATION = "C8W3" !CDS_LOCATION = "C8W3" #SEC = "1" !CDS_SEC = "1";
"A":   PN = "1"  !CDS_PN = "1";
"B":   PN = "2"  !CDS_PN = "2";
BODY = "CAP","I214": #LOCATION = "C5P8" !CDS_LOCATION = "C5P8" &SEC = "1" #&CDS_SEC = "1";
"A":   PN = "1"  !CDS_PN = "1";
"B":   PN = "2"  !CDS_PN = "2";
BODY = "CAP","I215": #LOCATION = "C5P9" !CDS_LOCATION = "C5P9" &SEC = "1" #&CDS_SEC = "1";
"A":   PN = "1"  !CDS_PN = "1";
"B":   PN = "2"  !CDS_PN = "2";
BODY = "CAP_A","I217": #LOCATION = "C5W1" !CDS_LOCATION = "C5W1" #SEC = "1" !CDS_SEC = "1";
"A":   PN = "1"  !CDS_PN = "1";
"B":   PN = "2"  !CDS_PN = "2";
BODY = "CAP_A","I218": #LOCATION = "C5W2" !CDS_LOCATION = "C5W2" #SEC = "1" !CDS_SEC = "1";
"A":   PN = "1"  !CDS_PN = "1";
"B":   PN = "2"  !CDS_PN = "2";
BODY = "CAP","I220": #LOCATION = "C5P29" !CDS_LOCATION = "C5P29" #SEC = "1" !CDS_SEC = "1";
"A":   PN = "1"  !CDS_PN = "1";
"B":   PN = "2"  !CDS_PN = "2";
BODY = "CAP","I221": #LOCATION = "C5P30" !CDS_LOCATION = "C5P30" #SEC = "1" !CDS_SEC = "1";
"A":   PN = "1"  !CDS_PN = "1";
"B":   PN = "2"  !CDS_PN = "2";
BODY = "CAP","I222": #LOCATION = "C5P19" !CDS_LOCATION = "C5P19" #SEC = "1" !CDS_SEC = "1";
"A":   PN = "1"  !CDS_PN = "1";
"B":   PN = "2"  !CDS_PN = "2";
BODY = "CAP","I223": #LOCATION = "C4P4" !CDS_LOCATION = "C4P4" #SEC = "1" !CDS_SEC = "1";
"A":   PN = "1"  !CDS_PN = "1";
"B":   PN = "2"  !CDS_PN = "2";
BODY = "CAP","I224": #LOCATION = "C4P7" !CDS_LOCATION = "C4P7" #SEC = "1" !CDS_SEC = "1";
"A":   PN = "1"  !CDS_PN = "1";
"B":   PN = "2"  !CDS_PN = "2";
BODY = "CAP","I225": #LOCATION = "C4P3" !CDS_LOCATION = "C4P3" #SEC = "1" !CDS_SEC = "1";
"A":   PN = "1"  !CDS_PN = "1";
"B":   PN = "2"  !CDS_PN = "2";
BODY = "CAP","I226": #LOCATION = "C5P10" !CDS_LOCATION = "C5P10" #SEC = "1" !CDS_SEC = "1";
"A":   PN = "1"  !CDS_PN = "1";
"B":   PN = "2"  !CDS_PN = "2";
BODY = "CAP","I227": #LOCATION = "C5P11" !CDS_LOCATION = "C5P11" #SEC = "1" !CDS_SEC = "1";
"A":   PN = "1"  !CDS_PN = "1";
"B":   PN = "2"  !CDS_PN = "2";
BODY = "CAP","I228": #LOCATION = "C5P18" !CDS_LOCATION = "C5P18" #SEC = "1" !CDS_SEC = "1";
"A":   PN = "1"  !CDS_PN = "1";
"B":   PN = "2"  !CDS_PN = "2";
BODY = "CAP","I229": #LOCATION = "C5P28" !CDS_LOCATION = "C5P28" #SEC = "1" !CDS_SEC = "1";
"A":   PN = "1"  !CDS_PN = "1";
"B":   PN = "2"  !CDS_PN = "2";
BODY = "CAP","I230": #LOCATION = "C4P2" !CDS_LOCATION = "C4P2" #SEC = "1" !CDS_SEC = "1";
"A":   PN = "1"  !CDS_PN = "1";
"B":   PN = "2"  !CDS_PN = "2";
BODY = "CAP","I231": #LOCATION = "C5P31" !CDS_LOCATION = "C5P31" #SEC = "1" !CDS_SEC = "1";
"A":   PN = "1"  !CDS_PN = "1";
"B":   PN = "2"  !CDS_PN = "2";
BODY = "CAP","I232": #LOCATION = "C5P13" !CDS_LOCATION = "C5P13" #SEC = "1" !CDS_SEC = "1";
"A":   PN = "1"  !CDS_PN = "1";
"B":   PN = "2"  !CDS_PN = "2";
BODY = "CAP","I233": #LOCATION = "C4P5" !CDS_LOCATION = "C4P5" #SEC = "1" !CDS_SEC = "1";
"A":   PN = "1"  !CDS_PN = "1";
"B":   PN = "2"  !CDS_PN = "2";
BODY = "CAP","I234": #LOCATION = "C5P20" !CDS_LOCATION = "C5P20" #SEC = "1" !CDS_SEC = "1";
"A":   PN = "1"  !CDS_PN = "1";
"B":   PN = "2"  !CDS_PN = "2";
BODY = "CAP","I235": #LOCATION = "C5P21" !CDS_LOCATION = "C5P21" #SEC = "1" !CDS_SEC = "1";
"A":   PN = "1"  !CDS_PN = "1";
"B":   PN = "2"  !CDS_PN = "2";
BODY = "CAP","I236": #LOCATION = "C5P12" !CDS_LOCATION = "C5P12" #SEC = "1" !CDS_SEC = "1";
"A":   PN = "1"  !CDS_PN = "1";
"B":   PN = "2"  !CDS_PN = "2";
DRAWING = "@baseboard_fab2_lib.baseboard_fab2(sch_1):page43";
BODY = "SCONN288_H44441004","I1": #LOCATION = "J4G1" !CDS_LOCATION = "J4G1" #SEC = "1" !CDS_SEC = "1";
"A0":   PN = "79"  !CDS_PN = "79";
"A1":   PN = "72"  !CDS_PN = "72";
"A2":   PN = "216"  !CDS_PN = "216";
"A3":   PN = "71"  !CDS_PN = "71";
"A4":   PN = "214"  !CDS_PN = "214";
"A5":   PN = "213"  !CDS_PN = "213";
"A6":   PN = "69"  !CDS_PN = "69";
"A7":   PN = "211"  !CDS_PN = "211";
"A8":   PN = "68"  !CDS_PN = "68";
"A9":   PN = "66"  !CDS_PN = "66";
"A10":   PN = "225"  !CDS_PN = "225";
"A11":   PN = "210"  !CDS_PN = "210";
"A12":   PN = "65"  !CDS_PN = "65";
"A13":   PN = "232"  !CDS_PN = "232";
"A14_WE_N":   PN = "228"  !CDS_PN = "228";
"A15_CAS_N":   PN = "86"  !CDS_PN = "86";
"A16_RAS_N":   PN = "82"  !CDS_PN = "82";
"A17":   PN = "234"  !CDS_PN = "234";
"ACT_N":   PN = "62"  !CDS_PN = "62";
"ALERT_N":   PN = "208"  !CDS_PN = "208";
"BA<0>":   PN = "81"  !CDS_PN = "81";
"BA<1>":   PN = "224"  !CDS_PN = "224";
"BG<0>":   PN = "63"  !CDS_PN = "63";
"BG<1>":   PN = "207"  !CDS_PN = "207";
"C<2>":   PN = "235"  !CDS_PN = "235";
"CB<0>":   PN = "49"  !CDS_PN = "49";
"CB<1>":   PN = "194"  !CDS_PN = "194";
"CB<2>":   PN = "56"  !CDS_PN = "56";
"CB<3>":   PN = "201"  !CDS_PN = "201";
"CB<4>":   PN = "47"  !CDS_PN = "47";
"CB<5>":   PN = "192"  !CDS_PN = "192";
"CB<6>":   PN = "54"  !CDS_PN = "54";
"CB<7>":   PN = "199"  !CDS_PN = "199";
"CK0N":   PN = "75"  !CDS_PN = "75";
"CK0P":   PN = "74"  !CDS_PN = "74";
"CK1N":   PN = "219"  !CDS_PN = "219";
"CK1P":   PN = "218"  !CDS_PN = "218";
"CKE<0>":   PN = "60"  !CDS_PN = "60";
"CKE<1>":   PN = "203"  !CDS_PN = "203";
"DQ<0>":   PN = "5"  !CDS_PN = "5";
"DQ<1>":   PN = "150"  !CDS_PN = "150";
"DQ<2>":   PN = "12"  !CDS_PN = "12";
"DQ<3>":   PN = "157"  !CDS_PN = "157";
"DQ<4>":   PN = "3"  !CDS_PN = "3";
"DQ<5>":   PN = "148"  !CDS_PN = "148";
"DQ<6>":   PN = "10"  !CDS_PN = "10";
"DQ<7>":   PN = "155"  !CDS_PN = "155";
"DQ<8>":   PN = "16"  !CDS_PN = "16";
"DQ<9>":   PN = "161"  !CDS_PN = "161";
"DQ<10>":   PN = "23"  !CDS_PN = "23";
"DQ<11>":   PN = "168"  !CDS_PN = "168";
"DQ<12>":   PN = "14"  !CDS_PN = "14";
"DQ<13>":   PN = "159"  !CDS_PN = "159";
"DQ<14>":   PN = "21"  !CDS_PN = "21";
"DQ<15>":   PN = "166"  !CDS_PN = "166";
"DQ<16>":   PN = "27"  !CDS_PN = "27";
"DQ<17>":   PN = "172"  !CDS_PN = "172";
"DQ<18>":   PN = "34"  !CDS_PN = "34";
"DQ<19>":   PN = "179"  !CDS_PN = "179";
"DQ<20>":   PN = "25"  !CDS_PN = "25";
"DQ<21>":   PN = "170"  !CDS_PN = "170";
"DQ<22>":   PN = "32"  !CDS_PN = "32";
"DQ<23>":   PN = "177"  !CDS_PN = "177";
"DQ<24>":   PN = "38"  !CDS_PN = "38";
"DQ<25>":   PN = "183"  !CDS_PN = "183";
"DQ<26>":   PN = "45"  !CDS_PN = "45";
"DQ<27>":   PN = "190"  !CDS_PN = "190";
"DQ<28>":   PN = "36"  !CDS_PN = "36";
"DQ<29>":   PN = "181"  !CDS_PN = "181";
"DQ<30>":   PN = "43"  !CDS_PN = "43";
"DQ<31>":   PN = "188"  !CDS_PN = "188";
"DQ<32>":   PN = "97"  !CDS_PN = "97";
"DQ<33>":   PN = "242"  !CDS_PN = "242";
"DQ<34>":   PN = "104"  !CDS_PN = "104";
"DQ<35>":   PN = "249"  !CDS_PN = "249";
"DQ<36>":   PN = "95"  !CDS_PN = "95";
"DQ<37>":   PN = "240"  !CDS_PN = "240";
"DQ<38>":   PN = "102"  !CDS_PN = "102";
"DQ<39>":   PN = "247"  !CDS_PN = "247";
"DQ<40>":   PN = "108"  !CDS_PN = "108";
"DQ<41>":   PN = "253"  !CDS_PN = "253";
"DQ<42>":   PN = "115"  !CDS_PN = "115";
"DQ<43>":   PN = "260"  !CDS_PN = "260";
"DQ<44>":   PN = "106"  !CDS_PN = "106";
"DQ<45>":   PN = "251"  !CDS_PN = "251";
"DQ<46>":   PN = "113"  !CDS_PN = "113";
"DQ<47>":   PN = "258"  !CDS_PN = "258";
"DQ<48>":   PN = "119"  !CDS_PN = "119";
"DQ<49>":   PN = "264"  !CDS_PN = "264";
"DQ<50>":   PN = "126"  !CDS_PN = "126";
"DQ<51>":   PN = "271"  !CDS_PN = "271";
"DQ<52>":   PN = "117"  !CDS_PN = "117";
"DQ<53>":   PN = "262"  !CDS_PN = "262";
"DQ<54>":   PN = "124"  !CDS_PN = "124";
"DQ<55>":   PN = "269"  !CDS_PN = "269";
"DQ<56>":   PN = "130"  !CDS_PN = "130";
"DQ<57>":   PN = "275"  !CDS_PN = "275";
"DQ<58>":   PN = "137"  !CDS_PN = "137";
"DQ<59>":   PN = "282"  !CDS_PN = "282";
"DQ<60>":   PN = "128"  !CDS_PN = "128";
"DQ<61>":   PN = "273"  !CDS_PN = "273";
"DQ<62>":   PN = "135"  !CDS_PN = "135";
"DQ<63>":   PN = "280"  !CDS_PN = "280";
"EVENT_N":   PN = "78"  !CDS_PN = "78";
"ODT<0>":   PN = "87"  !CDS_PN = "87";
"ODT<1>":   PN = "91"  !CDS_PN = "91";
"PAR":   PN = "222"  !CDS_PN = "222";
"RESET_N":   PN = "58"  !CDS_PN = "58";
"RFU<0>":   PN = "205"  !CDS_PN = "205";
"RFU<1>":   PN = "227"  !CDS_PN = "227";
"RFU<2>":   PN = "144"  !CDS_PN = "144";
"S0_N":   PN = "84"  !CDS_PN = "84";
"S1_N":   PN = "89"  !CDS_PN = "89";
"S2_N_C<0>":   PN = "93"  !CDS_PN = "93";
"S3_N_C<1>":   PN = "237"  !CDS_PN = "237";
"SA<0>":   PN = "139"  !CDS_PN = "139";
"SA<1>":   PN = "140"  !CDS_PN = "140";
"SA<2>":   PN = "238"  !CDS_PN = "238";
"SAVE_N_NC":   PN = "230"  !CDS_PN = "230";
"SCL":   PN = "141"  !CDS_PN = "141";
"SDA":   PN = "285"  !CDS_PN = "285";
"VDDSPD":   PN = "284"  !CDS_PN = "284";
"VREFCA":   PN = "146"  !CDS_PN = "146";
BODY = "SCONN288_H44441004","I2": #LOCATION = "J4G1" !CDS_LOCATION = "J4G1" #SEC = "2" !CDS_SEC = "2";
"DQS0N":   PN = "152"  !CDS_PN = "152";
"DQS0P":   PN = "153"  !CDS_PN = "153";
"DQS1N":   PN = "163"  !CDS_PN = "163";
"DQS1P":   PN = "164"  !CDS_PN = "164";
"DQS2N":   PN = "174"  !CDS_PN = "174";
"DQS2P":   PN = "175"  !CDS_PN = "175";
"DQS3N":   PN = "185"  !CDS_PN = "185";
"DQS3P":   PN = "186"  !CDS_PN = "186";
"DQS4N":   PN = "244"  !CDS_PN = "244";
"DQS4P":   PN = "245"  !CDS_PN = "245";
"DQS5N":   PN = "255"  !CDS_PN = "255";
"DQS5P":   PN = "256"  !CDS_PN = "256";
"DQS6N":   PN = "266"  !CDS_PN = "266";
"DQS6P":   PN = "267"  !CDS_PN = "267";
"DQS7N":   PN = "277"  !CDS_PN = "277";
"DQS7P":   PN = "278"  !CDS_PN = "278";
"DQS8N":   PN = "196"  !CDS_PN = "196";
"DQS8P":   PN = "197"  !CDS_PN = "197";
"DQS9N":   PN = "8"  !CDS_PN = "8";
"DQS9P":   PN = "7"  !CDS_PN = "7";
"DQS10N":   PN = "19"  !CDS_PN = "19";
"DQS10P":   PN = "18"  !CDS_PN = "18";
"DQS11N":   PN = "30"  !CDS_PN = "30";
"DQS11P":   PN = "29"  !CDS_PN = "29";
"DQS12N":   PN = "41"  !CDS_PN = "41";
"DQS12P":   PN = "40"  !CDS_PN = "40";
"DQS13N":   PN = "100"  !CDS_PN = "100";
"DQS13P":   PN = "99"  !CDS_PN = "99";
"DQS14N":   PN = "111"  !CDS_PN = "111";
"DQS14P":   PN = "110"  !CDS_PN = "110";
"DQS15N":   PN = "122"  !CDS_PN = "122";
"DQS15P":   PN = "121"  !CDS_PN = "121";
"DQS16N":   PN = "133"  !CDS_PN = "133";
"DQS16P":   PN = "132"  !CDS_PN = "132";
"DQS17N":   PN = "52"  !CDS_PN = "52";
"DQS17P":   PN = "51"  !CDS_PN = "51";
BODY = "SCONN288_H44441004","I259": #LOCATION = "J4G1" !CDS_LOCATION = "J4G1" #SEC = "3" !CDS_SEC = "3";
"VSS<0>":   PN = "283"  !CDS_PN = "283";
"VSS<1>":   PN = "281"  !CDS_PN = "281";
"VSS<2>":   PN = "279"  !CDS_PN = "279";
"VSS<3>":   PN = "276"  !CDS_PN = "276";
"VSS<4>":   PN = "274"  !CDS_PN = "274";
"VSS<5>":   PN = "272"  !CDS_PN = "272";
"VSS<6>":   PN = "270"  !CDS_PN = "270";
"VSS<7>":   PN = "268"  !CDS_PN = "268";
"VSS<8>":   PN = "265"  !CDS_PN = "265";
"VSS<9>":   PN = "263"  !CDS_PN = "263";
"VSS<10>":   PN = "261"  !CDS_PN = "261";
"VSS<11>":   PN = "259"  !CDS_PN = "259";
"VSS<12>":   PN = "257"  !CDS_PN = "257";
"VSS<13>":   PN = "254"  !CDS_PN = "254";
"VSS<14>":   PN = "252"  !CDS_PN = "252";
"VSS<15>":   PN = "250"  !CDS_PN = "250";
"VSS<16>":   PN = "248"  !CDS_PN = "248";
"VSS<17>":   PN = "246"  !CDS_PN = "246";
"VSS<18>":   PN = "243"  !CDS_PN = "243";
"VSS<19>":   PN = "241"  !CDS_PN = "241";
"VSS<20>":   PN = "239"  !CDS_PN = "239";
"VSS<21>":   PN = "202"  !CDS_PN = "202";
"VSS<22>":   PN = "200"  !CDS_PN = "200";
"VSS<23>":   PN = "198"  !CDS_PN = "198";
"VSS<24>":   PN = "195"  !CDS_PN = "195";
"VSS<25>":   PN = "193"  !CDS_PN = "193";
"VSS<26>":   PN = "191"  !CDS_PN = "191";
"VSS<27>":   PN = "189"  !CDS_PN = "189";
"VSS<28>":   PN = "187"  !CDS_PN = "187";
"VSS<29>":   PN = "184"  !CDS_PN = "184";
"VSS<30>":   PN = "182"  !CDS_PN = "182";
"VSS<31>":   PN = "180"  !CDS_PN = "180";
"VSS<32>":   PN = "178"  !CDS_PN = "178";
"VSS<33>":   PN = "176"  !CDS_PN = "176";
"VSS<34>":   PN = "173"  !CDS_PN = "173";
"VSS<35>":   PN = "171"  !CDS_PN = "171";
"VSS<36>":   PN = "169"  !CDS_PN = "169";
"VSS<37>":   PN = "167"  !CDS_PN = "167";
"VSS<38>":   PN = "165"  !CDS_PN = "165";
"VSS<39>":   PN = "162"  !CDS_PN = "162";
"VSS<40>":   PN = "160"  !CDS_PN = "160";
"VSS<41>":   PN = "158"  !CDS_PN = "158";
"VSS<42>":   PN = "156"  !CDS_PN = "156";
"VSS<43>":   PN = "154"  !CDS_PN = "154";
"VSS<44>":   PN = "151"  !CDS_PN = "151";
"VSS<45>":   PN = "149"  !CDS_PN = "149";
"VSS<46>":   PN = "147"  !CDS_PN = "147";
"VSS<47>":   PN = "138"  !CDS_PN = "138";
"VSS<48>":   PN = "136"  !CDS_PN = "136";
"VSS<49>":   PN = "134"  !CDS_PN = "134";
"VSS<50>":   PN = "131"  !CDS_PN = "131";
"VSS<51>":   PN = "129"  !CDS_PN = "129";
"VSS<52>":   PN = "127"  !CDS_PN = "127";
"VSS<53>":   PN = "125"  !CDS_PN = "125";
"VSS<54>":   PN = "123"  !CDS_PN = "123";
"VSS<55>":   PN = "120"  !CDS_PN = "120";
"VSS<56>":   PN = "118"  !CDS_PN = "118";
"VSS<57>":   PN = "116"  !CDS_PN = "116";
"VSS<58>":   PN = "114"  !CDS_PN = "114";
"VSS<59>":   PN = "112"  !CDS_PN = "112";
"VSS<60>":   PN = "109"  !CDS_PN = "109";
"VSS<61>":   PN = "107"  !CDS_PN = "107";
"VSS<62>":   PN = "105"  !CDS_PN = "105";
"VSS<63>":   PN = "103"  !CDS_PN = "103";
"VSS<64>":   PN = "101"  !CDS_PN = "101";
"VSS<65>":   PN = "98"  !CDS_PN = "98";
"VSS<66>":   PN = "96"  !CDS_PN = "96";
"VSS<67>":   PN = "94"  !CDS_PN = "94";
"VSS<68>":   PN = "57"  !CDS_PN = "57";
"VSS<69>":   PN = "55"  !CDS_PN = "55";
"VSS<70>":   PN = "53"  !CDS_PN = "53";
"VSS<71>":   PN = "50"  !CDS_PN = "50";
"VSS<72>":   PN = "48"  !CDS_PN = "48";
"VSS<73>":   PN = "46"  !CDS_PN = "46";
"VSS<74>":   PN = "44"  !CDS_PN = "44";
"VSS<75>":   PN = "42"  !CDS_PN = "42";
"VSS<76>":   PN = "39"  !CDS_PN = "39";
"VSS<77>":   PN = "37"  !CDS_PN = "37";
"VSS<78>":   PN = "35"  !CDS_PN = "35";
"VSS<79>":   PN = "33"  !CDS_PN = "33";
"VSS<80>":   PN = "31"  !CDS_PN = "31";
"VSS<81>":   PN = "28"  !CDS_PN = "28";
"VSS<82>":   PN = "26"  !CDS_PN = "26";
"VSS<83>":   PN = "24"  !CDS_PN = "24";
"VSS<84>":   PN = "22"  !CDS_PN = "22";
"VSS<85>":   PN = "20"  !CDS_PN = "20";
"VSS<86>":   PN = "17"  !CDS_PN = "17";
"VSS<87>":   PN = "15"  !CDS_PN = "15";
"VSS<88>":   PN = "13"  !CDS_PN = "13";
"VSS<89>":   PN = "11"  !CDS_PN = "11";
"VSS<90>":   PN = "9"  !CDS_PN = "9";
"VSS<91>":   PN = "6"  !CDS_PN = "6";
"VSS<92>":   PN = "4"  !CDS_PN = "4";
"VSS<93>":   PN = "2"  !CDS_PN = "2";
BODY = "SCONN288_H44441004","I260": #LOCATION = "J4G1" !CDS_LOCATION = "J4G1" #SEC = "4" !CDS_SEC = "4";
"12V<0>":   PN = "145"  !CDS_PN = "145";
"12V<1>":   PN = "1"  !CDS_PN = "1";
"VDD<0>":   PN = "236"  !CDS_PN = "236";
"VDD<1>":   PN = "233"  !CDS_PN = "233";
"VDD<2>":   PN = "231"  !CDS_PN = "231";
"VDD<3>":   PN = "229"  !CDS_PN = "229";
"VDD<4>":   PN = "226"  !CDS_PN = "226";
"VDD<5>":   PN = "223"  !CDS_PN = "223";
"VDD<6>":   PN = "220"  !CDS_PN = "220";
"VDD<7>":   PN = "217"  !CDS_PN = "217";
"VDD<8>":   PN = "215"  !CDS_PN = "215";
"VDD<9>":   PN = "212"  !CDS_PN = "212";
"VDD<10>":   PN = "209"  !CDS_PN = "209";
"VDD<11>":   PN = "206"  !CDS_PN = "206";
"VDD<12>":   PN = "204"  !CDS_PN = "204";
"VDD<13>":   PN = "92"  !CDS_PN = "92";
"VDD<14>":   PN = "90"  !CDS_PN = "90";
"VDD<15>":   PN = "88"  !CDS_PN = "88";
"VDD<16>":   PN = "85"  !CDS_PN = "85";
"VDD<17>":   PN = "83"  !CDS_PN = "83";
"VDD<18>":   PN = "80"  !CDS_PN = "80";
"VDD<19>":   PN = "76"  !CDS_PN = "76";
"VDD<20>":   PN = "73"  !CDS_PN = "73";
"VDD<21>":   PN = "70"  !CDS_PN = "70";
"VDD<22>":   PN = "67"  !CDS_PN = "67";
"VDD<23>":   PN = "64"  !CDS_PN = "64";
"VDD<24>":   PN = "61"  !CDS_PN = "61";
"VDD<25>":   PN = "59"  !CDS_PN = "59";
"VPP<0>":   PN = "287"  !CDS_PN = "287";
"VPP<1>":   PN = "286"  !CDS_PN = "286";
"VPP<2>":   PN = "288"  !CDS_PN = "288";
"VPP<3>":   PN = "143"  !CDS_PN = "143";
"VPP<4>":   PN = "142"  !CDS_PN = "142";
"VTT<0>":   PN = "221"  !CDS_PN = "221";
"VTT<1>":   PN = "77"  !CDS_PN = "77";
BODY = "CAP_A","I272": #LOCATION = "C4F10" !CDS_LOCATION = "C4F10" #SEC = "1" !CDS_SEC = "1";
"A":   PN = "1"  !CDS_PN = "1";
"B":   PN = "2"  !CDS_PN = "2";
DRAWING = "@baseboard_fab2_lib.baseboard_fab2(sch_1):page44";
BODY = "CAP_A","I2": #LOCATION = "C6T1" !CDS_LOCATION = "C6T1" #SEC = "1" !CDS_SEC = "1";
"A":   PN = "1"  !CDS_PN = "1";
"B":   PN = "2"  !CDS_PN = "2";
BODY = "SCONN288_H44441003","I13": #LOCATION = "J6T1" !CDS_LOCATION = "J6T1" #SEC = "1" !CDS_SEC = "1";
"A0":   PN = "79"  !CDS_PN = "79";
"A1":   PN = "72"  !CDS_PN = "72";
"A2":   PN = "216"  !CDS_PN = "216";
"A3":   PN = "71"  !CDS_PN = "71";
"A4":   PN = "214"  !CDS_PN = "214";
"A5":   PN = "213"  !CDS_PN = "213";
"A6":   PN = "69"  !CDS_PN = "69";
"A7":   PN = "211"  !CDS_PN = "211";
"A8":   PN = "68"  !CDS_PN = "68";
"A9":   PN = "66"  !CDS_PN = "66";
"A10":   PN = "225"  !CDS_PN = "225";
"A11":   PN = "210"  !CDS_PN = "210";
"A12":   PN = "65"  !CDS_PN = "65";
"A13":   PN = "232"  !CDS_PN = "232";
"A14_WE_N":   PN = "228"  !CDS_PN = "228";
"A15_CAS_N":   PN = "86"  !CDS_PN = "86";
"A16_RAS_N":   PN = "82"  !CDS_PN = "82";
"A17":   PN = "234"  !CDS_PN = "234";
"ACT_N":   PN = "62"  !CDS_PN = "62";
"ALERT_N":   PN = "208"  !CDS_PN = "208";
"BA<0>":   PN = "81"  !CDS_PN = "81";
"BA<1>":   PN = "224"  !CDS_PN = "224";
"BG<0>":   PN = "63"  !CDS_PN = "63";
"BG<1>":   PN = "207"  !CDS_PN = "207";
"C<2>":   PN = "235"  !CDS_PN = "235";
"CB<0>":   PN = "49"  !CDS_PN = "49";
"CB<1>":   PN = "194"  !CDS_PN = "194";
"CB<2>":   PN = "56"  !CDS_PN = "56";
"CB<3>":   PN = "201"  !CDS_PN = "201";
"CB<4>":   PN = "47"  !CDS_PN = "47";
"CB<5>":   PN = "192"  !CDS_PN = "192";
"CB<6>":   PN = "54"  !CDS_PN = "54";
"CB<7>":   PN = "199"  !CDS_PN = "199";
"CK0N":   PN = "75"  !CDS_PN = "75";
"CK0P":   PN = "74"  !CDS_PN = "74";
"CK1N":   PN = "219"  !CDS_PN = "219";
"CK1P":   PN = "218"  !CDS_PN = "218";
"CKE<0>":   PN = "60"  !CDS_PN = "60";
"CKE<1>":   PN = "203"  !CDS_PN = "203";
"DQ<0>":   PN = "5"  !CDS_PN = "5";
"DQ<1>":   PN = "150"  !CDS_PN = "150";
"DQ<2>":   PN = "12"  !CDS_PN = "12";
"DQ<3>":   PN = "157"  !CDS_PN = "157";
"DQ<4>":   PN = "3"  !CDS_PN = "3";
"DQ<5>":   PN = "148"  !CDS_PN = "148";
"DQ<6>":   PN = "10"  !CDS_PN = "10";
"DQ<7>":   PN = "155"  !CDS_PN = "155";
"DQ<8>":   PN = "16"  !CDS_PN = "16";
"DQ<9>":   PN = "161"  !CDS_PN = "161";
"DQ<10>":   PN = "23"  !CDS_PN = "23";
"DQ<11>":   PN = "168"  !CDS_PN = "168";
"DQ<12>":   PN = "14"  !CDS_PN = "14";
"DQ<13>":   PN = "159"  !CDS_PN = "159";
"DQ<14>":   PN = "21"  !CDS_PN = "21";
"DQ<15>":   PN = "166"  !CDS_PN = "166";
"DQ<16>":   PN = "27"  !CDS_PN = "27";
"DQ<17>":   PN = "172"  !CDS_PN = "172";
"DQ<18>":   PN = "34"  !CDS_PN = "34";
"DQ<19>":   PN = "179"  !CDS_PN = "179";
"DQ<20>":   PN = "25"  !CDS_PN = "25";
"DQ<21>":   PN = "170"  !CDS_PN = "170";
"DQ<22>":   PN = "32"  !CDS_PN = "32";
"DQ<23>":   PN = "177"  !CDS_PN = "177";
"DQ<24>":   PN = "38"  !CDS_PN = "38";
"DQ<25>":   PN = "183"  !CDS_PN = "183";
"DQ<26>":   PN = "45"  !CDS_PN = "45";
"DQ<27>":   PN = "190"  !CDS_PN = "190";
"DQ<28>":   PN = "36"  !CDS_PN = "36";
"DQ<29>":   PN = "181"  !CDS_PN = "181";
"DQ<30>":   PN = "43"  !CDS_PN = "43";
"DQ<31>":   PN = "188"  !CDS_PN = "188";
"DQ<32>":   PN = "97"  !CDS_PN = "97";
"DQ<33>":   PN = "242"  !CDS_PN = "242";
"DQ<34>":   PN = "104"  !CDS_PN = "104";
"DQ<35>":   PN = "249"  !CDS_PN = "249";
"DQ<36>":   PN = "95"  !CDS_PN = "95";
"DQ<37>":   PN = "240"  !CDS_PN = "240";
"DQ<38>":   PN = "102"  !CDS_PN = "102";
"DQ<39>":   PN = "247"  !CDS_PN = "247";
"DQ<40>":   PN = "108"  !CDS_PN = "108";
"DQ<41>":   PN = "253"  !CDS_PN = "253";
"DQ<42>":   PN = "115"  !CDS_PN = "115";
"DQ<43>":   PN = "260"  !CDS_PN = "260";
"DQ<44>":   PN = "106"  !CDS_PN = "106";
"DQ<45>":   PN = "251"  !CDS_PN = "251";
"DQ<46>":   PN = "113"  !CDS_PN = "113";
"DQ<47>":   PN = "258"  !CDS_PN = "258";
"DQ<48>":   PN = "119"  !CDS_PN = "119";
"DQ<49>":   PN = "264"  !CDS_PN = "264";
"DQ<50>":   PN = "126"  !CDS_PN = "126";
"DQ<51>":   PN = "271"  !CDS_PN = "271";
"DQ<52>":   PN = "117"  !CDS_PN = "117";
"DQ<53>":   PN = "262"  !CDS_PN = "262";
"DQ<54>":   PN = "124"  !CDS_PN = "124";
"DQ<55>":   PN = "269"  !CDS_PN = "269";
"DQ<56>":   PN = "130"  !CDS_PN = "130";
"DQ<57>":   PN = "275"  !CDS_PN = "275";
"DQ<58>":   PN = "137"  !CDS_PN = "137";
"DQ<59>":   PN = "282"  !CDS_PN = "282";
"DQ<60>":   PN = "128"  !CDS_PN = "128";
"DQ<61>":   PN = "273"  !CDS_PN = "273";
"DQ<62>":   PN = "135"  !CDS_PN = "135";
"DQ<63>":   PN = "280"  !CDS_PN = "280";
"EVENT_N":   PN = "78"  !CDS_PN = "78";
"ODT<0>":   PN = "87"  !CDS_PN = "87";
"ODT<1>":   PN = "91"  !CDS_PN = "91";
"PAR":   PN = "222"  !CDS_PN = "222";
"RESET_N":   PN = "58"  !CDS_PN = "58";
"RFU<0>":   PN = "205"  !CDS_PN = "205";
"RFU<1>":   PN = "227"  !CDS_PN = "227";
"RFU<2>":   PN = "144"  !CDS_PN = "144";
"S0_N":   PN = "84"  !CDS_PN = "84";
"S1_N":   PN = "89"  !CDS_PN = "89";
"S2_N_C<0>":   PN = "93"  !CDS_PN = "93";
"S3_N_C<1>":   PN = "237"  !CDS_PN = "237";
"SA<0>":   PN = "139"  !CDS_PN = "139";
"SA<1>":   PN = "140"  !CDS_PN = "140";
"SA<2>":   PN = "238"  !CDS_PN = "238";
"SAVE_N_NC":   PN = "230"  !CDS_PN = "230";
"SCL":   PN = "141"  !CDS_PN = "141";
"SDA":   PN = "285"  !CDS_PN = "285";
"VDDSPD":   PN = "284"  !CDS_PN = "284";
"VREFCA":   PN = "146"  !CDS_PN = "146";
BODY = "SCONN288_H44441003","I75": #LOCATION = "J6T1" !CDS_LOCATION = "J6T1" #SEC = "4" !CDS_SEC = "4";
"12V<0>":   PN = "145"  !CDS_PN = "145";
"12V<1>":   PN = "1"  !CDS_PN = "1";
"VDD<0>":   PN = "236"  !CDS_PN = "236";
"VDD<1>":   PN = "233"  !CDS_PN = "233";
"VDD<2>":   PN = "231"  !CDS_PN = "231";
"VDD<3>":   PN = "229"  !CDS_PN = "229";
"VDD<4>":   PN = "226"  !CDS_PN = "226";
"VDD<5>":   PN = "223"  !CDS_PN = "223";
"VDD<6>":   PN = "220"  !CDS_PN = "220";
"VDD<7>":   PN = "217"  !CDS_PN = "217";
"VDD<8>":   PN = "215"  !CDS_PN = "215";
"VDD<9>":   PN = "212"  !CDS_PN = "212";
"VDD<10>":   PN = "209"  !CDS_PN = "209";
"VDD<11>":   PN = "206"  !CDS_PN = "206";
"VDD<12>":   PN = "204"  !CDS_PN = "204";
"VDD<13>":   PN = "92"  !CDS_PN = "92";
"VDD<14>":   PN = "90"  !CDS_PN = "90";
"VDD<15>":   PN = "88"  !CDS_PN = "88";
"VDD<16>":   PN = "85"  !CDS_PN = "85";
"VDD<17>":   PN = "83"  !CDS_PN = "83";
"VDD<18>":   PN = "80"  !CDS_PN = "80";
"VDD<19>":   PN = "76"  !CDS_PN = "76";
"VDD<20>":   PN = "73"  !CDS_PN = "73";
"VDD<21>":   PN = "70"  !CDS_PN = "70";
"VDD<22>":   PN = "67"  !CDS_PN = "67";
"VDD<23>":   PN = "64"  !CDS_PN = "64";
"VDD<24>":   PN = "61"  !CDS_PN = "61";
"VDD<25>":   PN = "59"  !CDS_PN = "59";
"VPP<0>":   PN = "287"  !CDS_PN = "287";
"VPP<1>":   PN = "286"  !CDS_PN = "286";
"VPP<2>":   PN = "288"  !CDS_PN = "288";
"VPP<3>":   PN = "143"  !CDS_PN = "143";
"VPP<4>":   PN = "142"  !CDS_PN = "142";
"VTT<0>":   PN = "221"  !CDS_PN = "221";
"VTT<1>":   PN = "77"  !CDS_PN = "77";
BODY = "SCONN288_H44441003","I120": #LOCATION = "J6T1" !CDS_LOCATION = "J6T1" #SEC = "2" !CDS_SEC = "2";
"DQS0N":   PN = "152"  !CDS_PN = "152";
"DQS0P":   PN = "153"  !CDS_PN = "153";
"DQS1N":   PN = "163"  !CDS_PN = "163";
"DQS1P":   PN = "164"  !CDS_PN = "164";
"DQS2N":   PN = "174"  !CDS_PN = "174";
"DQS2P":   PN = "175"  !CDS_PN = "175";
"DQS3N":   PN = "185"  !CDS_PN = "185";
"DQS3P":   PN = "186"  !CDS_PN = "186";
"DQS4N":   PN = "244"  !CDS_PN = "244";
"DQS4P":   PN = "245"  !CDS_PN = "245";
"DQS5N":   PN = "255"  !CDS_PN = "255";
"DQS5P":   PN = "256"  !CDS_PN = "256";
"DQS6N":   PN = "266"  !CDS_PN = "266";
"DQS6P":   PN = "267"  !CDS_PN = "267";
"DQS7N":   PN = "277"  !CDS_PN = "277";
"DQS7P":   PN = "278"  !CDS_PN = "278";
"DQS8N":   PN = "196"  !CDS_PN = "196";
"DQS8P":   PN = "197"  !CDS_PN = "197";
"DQS9N":   PN = "8"  !CDS_PN = "8";
"DQS9P":   PN = "7"  !CDS_PN = "7";
"DQS10N":   PN = "19"  !CDS_PN = "19";
"DQS10P":   PN = "18"  !CDS_PN = "18";
"DQS11N":   PN = "30"  !CDS_PN = "30";
"DQS11P":   PN = "29"  !CDS_PN = "29";
"DQS12N":   PN = "41"  !CDS_PN = "41";
"DQS12P":   PN = "40"  !CDS_PN = "40";
"DQS13N":   PN = "100"  !CDS_PN = "100";
"DQS13P":   PN = "99"  !CDS_PN = "99";
"DQS14N":   PN = "111"  !CDS_PN = "111";
"DQS14P":   PN = "110"  !CDS_PN = "110";
"DQS15N":   PN = "122"  !CDS_PN = "122";
"DQS15P":   PN = "121"  !CDS_PN = "121";
"DQS16N":   PN = "133"  !CDS_PN = "133";
"DQS16P":   PN = "132"  !CDS_PN = "132";
"DQS17N":   PN = "52"  !CDS_PN = "52";
"DQS17P":   PN = "51"  !CDS_PN = "51";
BODY = "SCONN288_H44441003","I139": #LOCATION = "J6T1" !CDS_LOCATION = "J6T1" #SEC = "3" !CDS_SEC = "3";
"VSS<0>":   PN = "283"  !CDS_PN = "283";
"VSS<1>":   PN = "281"  !CDS_PN = "281";
"VSS<2>":   PN = "279"  !CDS_PN = "279";
"VSS<3>":   PN = "276"  !CDS_PN = "276";
"VSS<4>":   PN = "274"  !CDS_PN = "274";
"VSS<5>":   PN = "272"  !CDS_PN = "272";
"VSS<6>":   PN = "270"  !CDS_PN = "270";
"VSS<7>":   PN = "268"  !CDS_PN = "268";
"VSS<8>":   PN = "265"  !CDS_PN = "265";
"VSS<9>":   PN = "263"  !CDS_PN = "263";
"VSS<10>":   PN = "261"  !CDS_PN = "261";
"VSS<11>":   PN = "259"  !CDS_PN = "259";
"VSS<12>":   PN = "257"  !CDS_PN = "257";
"VSS<13>":   PN = "254"  !CDS_PN = "254";
"VSS<14>":   PN = "252"  !CDS_PN = "252";
"VSS<15>":   PN = "250"  !CDS_PN = "250";
"VSS<16>":   PN = "248"  !CDS_PN = "248";
"VSS<17>":   PN = "246"  !CDS_PN = "246";
"VSS<18>":   PN = "243"  !CDS_PN = "243";
"VSS<19>":   PN = "241"  !CDS_PN = "241";
"VSS<20>":   PN = "239"  !CDS_PN = "239";
"VSS<21>":   PN = "202"  !CDS_PN = "202";
"VSS<22>":   PN = "200"  !CDS_PN = "200";
"VSS<23>":   PN = "198"  !CDS_PN = "198";
"VSS<24>":   PN = "195"  !CDS_PN = "195";
"VSS<25>":   PN = "193"  !CDS_PN = "193";
"VSS<26>":   PN = "191"  !CDS_PN = "191";
"VSS<27>":   PN = "189"  !CDS_PN = "189";
"VSS<28>":   PN = "187"  !CDS_PN = "187";
"VSS<29>":   PN = "184"  !CDS_PN = "184";
"VSS<30>":   PN = "182"  !CDS_PN = "182";
"VSS<31>":   PN = "180"  !CDS_PN = "180";
"VSS<32>":   PN = "178"  !CDS_PN = "178";
"VSS<33>":   PN = "176"  !CDS_PN = "176";
"VSS<34>":   PN = "173"  !CDS_PN = "173";
"VSS<35>":   PN = "171"  !CDS_PN = "171";
"VSS<36>":   PN = "169"  !CDS_PN = "169";
"VSS<37>":   PN = "167"  !CDS_PN = "167";
"VSS<38>":   PN = "165"  !CDS_PN = "165";
"VSS<39>":   PN = "162"  !CDS_PN = "162";
"VSS<40>":   PN = "160"  !CDS_PN = "160";
"VSS<41>":   PN = "158"  !CDS_PN = "158";
"VSS<42>":   PN = "156"  !CDS_PN = "156";
"VSS<43>":   PN = "154"  !CDS_PN = "154";
"VSS<44>":   PN = "151"  !CDS_PN = "151";
"VSS<45>":   PN = "149"  !CDS_PN = "149";
"VSS<46>":   PN = "147"  !CDS_PN = "147";
"VSS<47>":   PN = "138"  !CDS_PN = "138";
"VSS<48>":   PN = "136"  !CDS_PN = "136";
"VSS<49>":   PN = "134"  !CDS_PN = "134";
"VSS<50>":   PN = "131"  !CDS_PN = "131";
"VSS<51>":   PN = "129"  !CDS_PN = "129";
"VSS<52>":   PN = "127"  !CDS_PN = "127";
"VSS<53>":   PN = "125"  !CDS_PN = "125";
"VSS<54>":   PN = "123"  !CDS_PN = "123";
"VSS<55>":   PN = "120"  !CDS_PN = "120";
"VSS<56>":   PN = "118"  !CDS_PN = "118";
"VSS<57>":   PN = "116"  !CDS_PN = "116";
"VSS<58>":   PN = "114"  !CDS_PN = "114";
"VSS<59>":   PN = "112"  !CDS_PN = "112";
"VSS<60>":   PN = "109"  !CDS_PN = "109";
"VSS<61>":   PN = "107"  !CDS_PN = "107";
"VSS<62>":   PN = "105"  !CDS_PN = "105";
"VSS<63>":   PN = "103"  !CDS_PN = "103";
"VSS<64>":   PN = "101"  !CDS_PN = "101";
"VSS<65>":   PN = "98"  !CDS_PN = "98";
"VSS<66>":   PN = "96"  !CDS_PN = "96";
"VSS<67>":   PN = "94"  !CDS_PN = "94";
"VSS<68>":   PN = "57"  !CDS_PN = "57";
"VSS<69>":   PN = "55"  !CDS_PN = "55";
"VSS<70>":   PN = "53"  !CDS_PN = "53";
"VSS<71>":   PN = "50"  !CDS_PN = "50";
"VSS<72>":   PN = "48"  !CDS_PN = "48";
"VSS<73>":   PN = "46"  !CDS_PN = "46";
"VSS<74>":   PN = "44"  !CDS_PN = "44";
"VSS<75>":   PN = "42"  !CDS_PN = "42";
"VSS<76>":   PN = "39"  !CDS_PN = "39";
"VSS<77>":   PN = "37"  !CDS_PN = "37";
"VSS<78>":   PN = "35"  !CDS_PN = "35";
"VSS<79>":   PN = "33"  !CDS_PN = "33";
"VSS<80>":   PN = "31"  !CDS_PN = "31";
"VSS<81>":   PN = "28"  !CDS_PN = "28";
"VSS<82>":   PN = "26"  !CDS_PN = "26";
"VSS<83>":   PN = "24"  !CDS_PN = "24";
"VSS<84>":   PN = "22"  !CDS_PN = "22";
"VSS<85>":   PN = "20"  !CDS_PN = "20";
"VSS<86>":   PN = "17"  !CDS_PN = "17";
"VSS<87>":   PN = "15"  !CDS_PN = "15";
"VSS<88>":   PN = "13"  !CDS_PN = "13";
"VSS<89>":   PN = "11"  !CDS_PN = "11";
"VSS<90>":   PN = "9"  !CDS_PN = "9";
"VSS<91>":   PN = "6"  !CDS_PN = "6";
"VSS<92>":   PN = "4"  !CDS_PN = "4";
"VSS<93>":   PN = "2"  !CDS_PN = "2";
DRAWING = "@baseboard_fab2_lib.baseboard_fab2(sch_1):page45";
BODY = "SCONN288_H44441004","I43": #LOCATION = "J4G2" !CDS_LOCATION = "J4G2" #SEC = "3" !CDS_SEC = "3";
"VSS<0>":   PN = "283"  !CDS_PN = "283";
"VSS<1>":   PN = "281"  !CDS_PN = "281";
"VSS<2>":   PN = "279"  !CDS_PN = "279";
"VSS<3>":   PN = "276"  !CDS_PN = "276";
"VSS<4>":   PN = "274"  !CDS_PN = "274";
"VSS<5>":   PN = "272"  !CDS_PN = "272";
"VSS<6>":   PN = "270"  !CDS_PN = "270";
"VSS<7>":   PN = "268"  !CDS_PN = "268";
"VSS<8>":   PN = "265"  !CDS_PN = "265";
"VSS<9>":   PN = "263"  !CDS_PN = "263";
"VSS<10>":   PN = "261"  !CDS_PN = "261";
"VSS<11>":   PN = "259"  !CDS_PN = "259";
"VSS<12>":   PN = "257"  !CDS_PN = "257";
"VSS<13>":   PN = "254"  !CDS_PN = "254";
"VSS<14>":   PN = "252"  !CDS_PN = "252";
"VSS<15>":   PN = "250"  !CDS_PN = "250";
"VSS<16>":   PN = "248"  !CDS_PN = "248";
"VSS<17>":   PN = "246"  !CDS_PN = "246";
"VSS<18>":   PN = "243"  !CDS_PN = "243";
"VSS<19>":   PN = "241"  !CDS_PN = "241";
"VSS<20>":   PN = "239"  !CDS_PN = "239";
"VSS<21>":   PN = "202"  !CDS_PN = "202";
"VSS<22>":   PN = "200"  !CDS_PN = "200";
"VSS<23>":   PN = "198"  !CDS_PN = "198";
"VSS<24>":   PN = "195"  !CDS_PN = "195";
"VSS<25>":   PN = "193"  !CDS_PN = "193";
"VSS<26>":   PN = "191"  !CDS_PN = "191";
"VSS<27>":   PN = "189"  !CDS_PN = "189";
"VSS<28>":   PN = "187"  !CDS_PN = "187";
"VSS<29>":   PN = "184"  !CDS_PN = "184";
"VSS<30>":   PN = "182"  !CDS_PN = "182";
"VSS<31>":   PN = "180"  !CDS_PN = "180";
"VSS<32>":   PN = "178"  !CDS_PN = "178";
"VSS<33>":   PN = "176"  !CDS_PN = "176";
"VSS<34>":   PN = "173"  !CDS_PN = "173";
"VSS<35>":   PN = "171"  !CDS_PN = "171";
"VSS<36>":   PN = "169"  !CDS_PN = "169";
"VSS<37>":   PN = "167"  !CDS_PN = "167";
"VSS<38>":   PN = "165"  !CDS_PN = "165";
"VSS<39>":   PN = "162"  !CDS_PN = "162";
"VSS<40>":   PN = "160"  !CDS_PN = "160";
"VSS<41>":   PN = "158"  !CDS_PN = "158";
"VSS<42>":   PN = "156"  !CDS_PN = "156";
"VSS<43>":   PN = "154"  !CDS_PN = "154";
"VSS<44>":   PN = "151"  !CDS_PN = "151";
"VSS<45>":   PN = "149"  !CDS_PN = "149";
"VSS<46>":   PN = "147"  !CDS_PN = "147";
"VSS<47>":   PN = "138"  !CDS_PN = "138";
"VSS<48>":   PN = "136"  !CDS_PN = "136";
"VSS<49>":   PN = "134"  !CDS_PN = "134";
"VSS<50>":   PN = "131"  !CDS_PN = "131";
"VSS<51>":   PN = "129"  !CDS_PN = "129";
"VSS<52>":   PN = "127"  !CDS_PN = "127";
"VSS<53>":   PN = "125"  !CDS_PN = "125";
"VSS<54>":   PN = "123"  !CDS_PN = "123";
"VSS<55>":   PN = "120"  !CDS_PN = "120";
"VSS<56>":   PN = "118"  !CDS_PN = "118";
"VSS<57>":   PN = "116"  !CDS_PN = "116";
"VSS<58>":   PN = "114"  !CDS_PN = "114";
"VSS<59>":   PN = "112"  !CDS_PN = "112";
"VSS<60>":   PN = "109"  !CDS_PN = "109";
"VSS<61>":   PN = "107"  !CDS_PN = "107";
"VSS<62>":   PN = "105"  !CDS_PN = "105";
"VSS<63>":   PN = "103"  !CDS_PN = "103";
"VSS<64>":   PN = "101"  !CDS_PN = "101";
"VSS<65>":   PN = "98"  !CDS_PN = "98";
"VSS<66>":   PN = "96"  !CDS_PN = "96";
"VSS<67>":   PN = "94"  !CDS_PN = "94";
"VSS<68>":   PN = "57"  !CDS_PN = "57";
"VSS<69>":   PN = "55"  !CDS_PN = "55";
"VSS<70>":   PN = "53"  !CDS_PN = "53";
"VSS<71>":   PN = "50"  !CDS_PN = "50";
"VSS<72>":   PN = "48"  !CDS_PN = "48";
"VSS<73>":   PN = "46"  !CDS_PN = "46";
"VSS<74>":   PN = "44"  !CDS_PN = "44";
"VSS<75>":   PN = "42"  !CDS_PN = "42";
"VSS<76>":   PN = "39"  !CDS_PN = "39";
"VSS<77>":   PN = "37"  !CDS_PN = "37";
"VSS<78>":   PN = "35"  !CDS_PN = "35";
"VSS<79>":   PN = "33"  !CDS_PN = "33";
"VSS<80>":   PN = "31"  !CDS_PN = "31";
"VSS<81>":   PN = "28"  !CDS_PN = "28";
"VSS<82>":   PN = "26"  !CDS_PN = "26";
"VSS<83>":   PN = "24"  !CDS_PN = "24";
"VSS<84>":   PN = "22"  !CDS_PN = "22";
"VSS<85>":   PN = "20"  !CDS_PN = "20";
"VSS<86>":   PN = "17"  !CDS_PN = "17";
"VSS<87>":   PN = "15"  !CDS_PN = "15";
"VSS<88>":   PN = "13"  !CDS_PN = "13";
"VSS<89>":   PN = "11"  !CDS_PN = "11";
"VSS<90>":   PN = "9"  !CDS_PN = "9";
"VSS<91>":   PN = "6"  !CDS_PN = "6";
"VSS<92>":   PN = "4"  !CDS_PN = "4";
"VSS<93>":   PN = "2"  !CDS_PN = "2";
BODY = "SCONN288_H44441004","I61": #LOCATION = "J4G2" !CDS_LOCATION = "J4G2" #SEC = "2" !CDS_SEC = "2";
"DQS0N":   PN = "152"  !CDS_PN = "152";
"DQS0P":   PN = "153"  !CDS_PN = "153";
"DQS1N":   PN = "163"  !CDS_PN = "163";
"DQS1P":   PN = "164"  !CDS_PN = "164";
"DQS2N":   PN = "174"  !CDS_PN = "174";
"DQS2P":   PN = "175"  !CDS_PN = "175";
"DQS3N":   PN = "185"  !CDS_PN = "185";
"DQS3P":   PN = "186"  !CDS_PN = "186";
"DQS4N":   PN = "244"  !CDS_PN = "244";
"DQS4P":   PN = "245"  !CDS_PN = "245";
"DQS5N":   PN = "255"  !CDS_PN = "255";
"DQS5P":   PN = "256"  !CDS_PN = "256";
"DQS6N":   PN = "266"  !CDS_PN = "266";
"DQS6P":   PN = "267"  !CDS_PN = "267";
"DQS7N":   PN = "277"  !CDS_PN = "277";
"DQS7P":   PN = "278"  !CDS_PN = "278";
"DQS8N":   PN = "196"  !CDS_PN = "196";
"DQS8P":   PN = "197"  !CDS_PN = "197";
"DQS9N":   PN = "8"  !CDS_PN = "8";
"DQS9P":   PN = "7"  !CDS_PN = "7";
"DQS10N":   PN = "19"  !CDS_PN = "19";
"DQS10P":   PN = "18"  !CDS_PN = "18";
"DQS11N":   PN = "30"  !CDS_PN = "30";
"DQS11P":   PN = "29"  !CDS_PN = "29";
"DQS12N":   PN = "41"  !CDS_PN = "41";
"DQS12P":   PN = "40"  !CDS_PN = "40";
"DQS13N":   PN = "100"  !CDS_PN = "100";
"DQS13P":   PN = "99"  !CDS_PN = "99";
"DQS14N":   PN = "111"  !CDS_PN = "111";
"DQS14P":   PN = "110"  !CDS_PN = "110";
"DQS15N":   PN = "122"  !CDS_PN = "122";
"DQS15P":   PN = "121"  !CDS_PN = "121";
"DQS16N":   PN = "133"  !CDS_PN = "133";
"DQS16P":   PN = "132"  !CDS_PN = "132";
"DQS17N":   PN = "52"  !CDS_PN = "52";
"DQS17P":   PN = "51"  !CDS_PN = "51";
BODY = "SCONN288_H44441004","I111": #LOCATION = "J4G2" !CDS_LOCATION = "J4G2" #SEC = "1" !CDS_SEC = "1";
"A0":   PN = "79"  !CDS_PN = "79";
"A1":   PN = "72"  !CDS_PN = "72";
"A2":   PN = "216"  !CDS_PN = "216";
"A3":   PN = "71"  !CDS_PN = "71";
"A4":   PN = "214"  !CDS_PN = "214";
"A5":   PN = "213"  !CDS_PN = "213";
"A6":   PN = "69"  !CDS_PN = "69";
"A7":   PN = "211"  !CDS_PN = "211";
"A8":   PN = "68"  !CDS_PN = "68";
"A9":   PN = "66"  !CDS_PN = "66";
"A10":   PN = "225"  !CDS_PN = "225";
"A11":   PN = "210"  !CDS_PN = "210";
"A12":   PN = "65"  !CDS_PN = "65";
"A13":   PN = "232"  !CDS_PN = "232";
"A14_WE_N":   PN = "228"  !CDS_PN = "228";
"A15_CAS_N":   PN = "86"  !CDS_PN = "86";
"A16_RAS_N":   PN = "82"  !CDS_PN = "82";
"A17":   PN = "234"  !CDS_PN = "234";
"ACT_N":   PN = "62"  !CDS_PN = "62";
"ALERT_N":   PN = "208"  !CDS_PN = "208";
"BA<0>":   PN = "81"  !CDS_PN = "81";
"BA<1>":   PN = "224"  !CDS_PN = "224";
"BG<0>":   PN = "63"  !CDS_PN = "63";
"BG<1>":   PN = "207"  !CDS_PN = "207";
"C<2>":   PN = "235"  !CDS_PN = "235";
"CB<0>":   PN = "49"  !CDS_PN = "49";
"CB<1>":   PN = "194"  !CDS_PN = "194";
"CB<2>":   PN = "56"  !CDS_PN = "56";
"CB<3>":   PN = "201"  !CDS_PN = "201";
"CB<4>":   PN = "47"  !CDS_PN = "47";
"CB<5>":   PN = "192"  !CDS_PN = "192";
"CB<6>":   PN = "54"  !CDS_PN = "54";
"CB<7>":   PN = "199"  !CDS_PN = "199";
"CK0N":   PN = "75"  !CDS_PN = "75";
"CK0P":   PN = "74"  !CDS_PN = "74";
"CK1N":   PN = "219"  !CDS_PN = "219";
"CK1P":   PN = "218"  !CDS_PN = "218";
"CKE<0>":   PN = "60"  !CDS_PN = "60";
"CKE<1>":   PN = "203"  !CDS_PN = "203";
"DQ<0>":   PN = "5"  !CDS_PN = "5";
"DQ<1>":   PN = "150"  !CDS_PN = "150";
"DQ<2>":   PN = "12"  !CDS_PN = "12";
"DQ<3>":   PN = "157"  !CDS_PN = "157";
"DQ<4>":   PN = "3"  !CDS_PN = "3";
"DQ<5>":   PN = "148"  !CDS_PN = "148";
"DQ<6>":   PN = "10"  !CDS_PN = "10";
"DQ<7>":   PN = "155"  !CDS_PN = "155";
"DQ<8>":   PN = "16"  !CDS_PN = "16";
"DQ<9>":   PN = "161"  !CDS_PN = "161";
"DQ<10>":   PN = "23"  !CDS_PN = "23";
"DQ<11>":   PN = "168"  !CDS_PN = "168";
"DQ<12>":   PN = "14"  !CDS_PN = "14";
"DQ<13>":   PN = "159"  !CDS_PN = "159";
"DQ<14>":   PN = "21"  !CDS_PN = "21";
"DQ<15>":   PN = "166"  !CDS_PN = "166";
"DQ<16>":   PN = "27"  !CDS_PN = "27";
"DQ<17>":   PN = "172"  !CDS_PN = "172";
"DQ<18>":   PN = "34"  !CDS_PN = "34";
"DQ<19>":   PN = "179"  !CDS_PN = "179";
"DQ<20>":   PN = "25"  !CDS_PN = "25";
"DQ<21>":   PN = "170"  !CDS_PN = "170";
"DQ<22>":   PN = "32"  !CDS_PN = "32";
"DQ<23>":   PN = "177"  !CDS_PN = "177";
"DQ<24>":   PN = "38"  !CDS_PN = "38";
"DQ<25>":   PN = "183"  !CDS_PN = "183";
"DQ<26>":   PN = "45"  !CDS_PN = "45";
"DQ<27>":   PN = "190"  !CDS_PN = "190";
"DQ<28>":   PN = "36"  !CDS_PN = "36";
"DQ<29>":   PN = "181"  !CDS_PN = "181";
"DQ<30>":   PN = "43"  !CDS_PN = "43";
"DQ<31>":   PN = "188"  !CDS_PN = "188";
"DQ<32>":   PN = "97"  !CDS_PN = "97";
"DQ<33>":   PN = "242"  !CDS_PN = "242";
"DQ<34>":   PN = "104"  !CDS_PN = "104";
"DQ<35>":   PN = "249"  !CDS_PN = "249";
"DQ<36>":   PN = "95"  !CDS_PN = "95";
"DQ<37>":   PN = "240"  !CDS_PN = "240";
"DQ<38>":   PN = "102"  !CDS_PN = "102";
"DQ<39>":   PN = "247"  !CDS_PN = "247";
"DQ<40>":   PN = "108"  !CDS_PN = "108";
"DQ<41>":   PN = "253"  !CDS_PN = "253";
"DQ<42>":   PN = "115"  !CDS_PN = "115";
"DQ<43>":   PN = "260"  !CDS_PN = "260";
"DQ<44>":   PN = "106"  !CDS_PN = "106";
"DQ<45>":   PN = "251"  !CDS_PN = "251";
"DQ<46>":   PN = "113"  !CDS_PN = "113";
"DQ<47>":   PN = "258"  !CDS_PN = "258";
"DQ<48>":   PN = "119"  !CDS_PN = "119";
"DQ<49>":   PN = "264"  !CDS_PN = "264";
"DQ<50>":   PN = "126"  !CDS_PN = "126";
"DQ<51>":   PN = "271"  !CDS_PN = "271";
"DQ<52>":   PN = "117"  !CDS_PN = "117";
"DQ<53>":   PN = "262"  !CDS_PN = "262";
"DQ<54>":   PN = "124"  !CDS_PN = "124";
"DQ<55>":   PN = "269"  !CDS_PN = "269";
"DQ<56>":   PN = "130"  !CDS_PN = "130";
"DQ<57>":   PN = "275"  !CDS_PN = "275";
"DQ<58>":   PN = "137"  !CDS_PN = "137";
"DQ<59>":   PN = "282"  !CDS_PN = "282";
"DQ<60>":   PN = "128"  !CDS_PN = "128";
"DQ<61>":   PN = "273"  !CDS_PN = "273";
"DQ<62>":   PN = "135"  !CDS_PN = "135";
"DQ<63>":   PN = "280"  !CDS_PN = "280";
"EVENT_N":   PN = "78"  !CDS_PN = "78";
"ODT<0>":   PN = "87"  !CDS_PN = "87";
"ODT<1>":   PN = "91"  !CDS_PN = "91";
"PAR":   PN = "222"  !CDS_PN = "222";
"RESET_N":   PN = "58"  !CDS_PN = "58";
"RFU<0>":   PN = "205"  !CDS_PN = "205";
"RFU<1>":   PN = "227"  !CDS_PN = "227";
"RFU<2>":   PN = "144"  !CDS_PN = "144";
"S0_N":   PN = "84"  !CDS_PN = "84";
"S1_N":   PN = "89"  !CDS_PN = "89";
"S2_N_C<0>":   PN = "93"  !CDS_PN = "93";
"S3_N_C<1>":   PN = "237"  !CDS_PN = "237";
"SA<0>":   PN = "139"  !CDS_PN = "139";
"SA<1>":   PN = "140"  !CDS_PN = "140";
"SA<2>":   PN = "238"  !CDS_PN = "238";
"SAVE_N_NC":   PN = "230"  !CDS_PN = "230";
"SCL":   PN = "141"  !CDS_PN = "141";
"SDA":   PN = "285"  !CDS_PN = "285";
"VDDSPD":   PN = "284"  !CDS_PN = "284";
"VREFCA":   PN = "146"  !CDS_PN = "146";
BODY = "SCONN288_H44441004","I169": #LOCATION = "J4G2" !CDS_LOCATION = "J4G2" #SEC = "4" !CDS_SEC = "4";
"12V<0>":   PN = "145"  !CDS_PN = "145";
"12V<1>":   PN = "1"  !CDS_PN = "1";
"VDD<0>":   PN = "236"  !CDS_PN = "236";
"VDD<1>":   PN = "233"  !CDS_PN = "233";
"VDD<2>":   PN = "231"  !CDS_PN = "231";
"VDD<3>":   PN = "229"  !CDS_PN = "229";
"VDD<4>":   PN = "226"  !CDS_PN = "226";
"VDD<5>":   PN = "223"  !CDS_PN = "223";
"VDD<6>":   PN = "220"  !CDS_PN = "220";
"VDD<7>":   PN = "217"  !CDS_PN = "217";
"VDD<8>":   PN = "215"  !CDS_PN = "215";
"VDD<9>":   PN = "212"  !CDS_PN = "212";
"VDD<10>":   PN = "209"  !CDS_PN = "209";
"VDD<11>":   PN = "206"  !CDS_PN = "206";
"VDD<12>":   PN = "204"  !CDS_PN = "204";
"VDD<13>":   PN = "92"  !CDS_PN = "92";
"VDD<14>":   PN = "90"  !CDS_PN = "90";
"VDD<15>":   PN = "88"  !CDS_PN = "88";
"VDD<16>":   PN = "85"  !CDS_PN = "85";
"VDD<17>":   PN = "83"  !CDS_PN = "83";
"VDD<18>":   PN = "80"  !CDS_PN = "80";
"VDD<19>":   PN = "76"  !CDS_PN = "76";
"VDD<20>":   PN = "73"  !CDS_PN = "73";
"VDD<21>":   PN = "70"  !CDS_PN = "70";
"VDD<22>":   PN = "67"  !CDS_PN = "67";
"VDD<23>":   PN = "64"  !CDS_PN = "64";
"VDD<24>":   PN = "61"  !CDS_PN = "61";
"VDD<25>":   PN = "59"  !CDS_PN = "59";
"VPP<0>":   PN = "287"  !CDS_PN = "287";
"VPP<1>":   PN = "286"  !CDS_PN = "286";
"VPP<2>":   PN = "288"  !CDS_PN = "288";
"VPP<3>":   PN = "143"  !CDS_PN = "143";
"VPP<4>":   PN = "142"  !CDS_PN = "142";
"VTT<0>":   PN = "221"  !CDS_PN = "221";
"VTT<1>":   PN = "77"  !CDS_PN = "77";
BODY = "CAP_A","I179": #LOCATION = "C4G3" !CDS_LOCATION = "C4G3" #SEC = "1" !CDS_SEC = "1";
"A":   PN = "1"  !CDS_PN = "1";
"B":   PN = "2"  !CDS_PN = "2";
DRAWING = "@baseboard_fab2_lib.baseboard_fab2(sch_1):page46";
BODY = "CAP_A","I5": #LOCATION = "C6U9" !CDS_LOCATION = "C6U9" #SEC = "1" !CDS_SEC = "1";
"A":   PN = "1"  !CDS_PN = "1";
"B":   PN = "2"  !CDS_PN = "2";
BODY = "SCONN288_H44441003","I14": #LOCATION = "J6U1" !CDS_LOCATION = "J6U1" #SEC = "1" !CDS_SEC = "1";
"A0":   PN = "79"  !CDS_PN = "79";
"A1":   PN = "72"  !CDS_PN = "72";
"A2":   PN = "216"  !CDS_PN = "216";
"A3":   PN = "71"  !CDS_PN = "71";
"A4":   PN = "214"  !CDS_PN = "214";
"A5":   PN = "213"  !CDS_PN = "213";
"A6":   PN = "69"  !CDS_PN = "69";
"A7":   PN = "211"  !CDS_PN = "211";
"A8":   PN = "68"  !CDS_PN = "68";
"A9":   PN = "66"  !CDS_PN = "66";
"A10":   PN = "225"  !CDS_PN = "225";
"A11":   PN = "210"  !CDS_PN = "210";
"A12":   PN = "65"  !CDS_PN = "65";
"A13":   PN = "232"  !CDS_PN = "232";
"A14_WE_N":   PN = "228"  !CDS_PN = "228";
"A15_CAS_N":   PN = "86"  !CDS_PN = "86";
"A16_RAS_N":   PN = "82"  !CDS_PN = "82";
"A17":   PN = "234"  !CDS_PN = "234";
"ACT_N":   PN = "62"  !CDS_PN = "62";
"ALERT_N":   PN = "208"  !CDS_PN = "208";
"BA<0>":   PN = "81"  !CDS_PN = "81";
"BA<1>":   PN = "224"  !CDS_PN = "224";
"BG<0>":   PN = "63"  !CDS_PN = "63";
"BG<1>":   PN = "207"  !CDS_PN = "207";
"C<2>":   PN = "235"  !CDS_PN = "235";
"CB<0>":   PN = "49"  !CDS_PN = "49";
"CB<1>":   PN = "194"  !CDS_PN = "194";
"CB<2>":   PN = "56"  !CDS_PN = "56";
"CB<3>":   PN = "201"  !CDS_PN = "201";
"CB<4>":   PN = "47"  !CDS_PN = "47";
"CB<5>":   PN = "192"  !CDS_PN = "192";
"CB<6>":   PN = "54"  !CDS_PN = "54";
"CB<7>":   PN = "199"  !CDS_PN = "199";
"CK0N":   PN = "75"  !CDS_PN = "75";
"CK0P":   PN = "74"  !CDS_PN = "74";
"CK1N":   PN = "219"  !CDS_PN = "219";
"CK1P":   PN = "218"  !CDS_PN = "218";
"CKE<0>":   PN = "60"  !CDS_PN = "60";
"CKE<1>":   PN = "203"  !CDS_PN = "203";
"DQ<0>":   PN = "5"  !CDS_PN = "5";
"DQ<1>":   PN = "150"  !CDS_PN = "150";
"DQ<2>":   PN = "12"  !CDS_PN = "12";
"DQ<3>":   PN = "157"  !CDS_PN = "157";
"DQ<4>":   PN = "3"  !CDS_PN = "3";
"DQ<5>":   PN = "148"  !CDS_PN = "148";
"DQ<6>":   PN = "10"  !CDS_PN = "10";
"DQ<7>":   PN = "155"  !CDS_PN = "155";
"DQ<8>":   PN = "16"  !CDS_PN = "16";
"DQ<9>":   PN = "161"  !CDS_PN = "161";
"DQ<10>":   PN = "23"  !CDS_PN = "23";
"DQ<11>":   PN = "168"  !CDS_PN = "168";
"DQ<12>":   PN = "14"  !CDS_PN = "14";
"DQ<13>":   PN = "159"  !CDS_PN = "159";
"DQ<14>":   PN = "21"  !CDS_PN = "21";
"DQ<15>":   PN = "166"  !CDS_PN = "166";
"DQ<16>":   PN = "27"  !CDS_PN = "27";
"DQ<17>":   PN = "172"  !CDS_PN = "172";
"DQ<18>":   PN = "34"  !CDS_PN = "34";
"DQ<19>":   PN = "179"  !CDS_PN = "179";
"DQ<20>":   PN = "25"  !CDS_PN = "25";
"DQ<21>":   PN = "170"  !CDS_PN = "170";
"DQ<22>":   PN = "32"  !CDS_PN = "32";
"DQ<23>":   PN = "177"  !CDS_PN = "177";
"DQ<24>":   PN = "38"  !CDS_PN = "38";
"DQ<25>":   PN = "183"  !CDS_PN = "183";
"DQ<26>":   PN = "45"  !CDS_PN = "45";
"DQ<27>":   PN = "190"  !CDS_PN = "190";
"DQ<28>":   PN = "36"  !CDS_PN = "36";
"DQ<29>":   PN = "181"  !CDS_PN = "181";
"DQ<30>":   PN = "43"  !CDS_PN = "43";
"DQ<31>":   PN = "188"  !CDS_PN = "188";
"DQ<32>":   PN = "97"  !CDS_PN = "97";
"DQ<33>":   PN = "242"  !CDS_PN = "242";
"DQ<34>":   PN = "104"  !CDS_PN = "104";
"DQ<35>":   PN = "249"  !CDS_PN = "249";
"DQ<36>":   PN = "95"  !CDS_PN = "95";
"DQ<37>":   PN = "240"  !CDS_PN = "240";
"DQ<38>":   PN = "102"  !CDS_PN = "102";
"DQ<39>":   PN = "247"  !CDS_PN = "247";
"DQ<40>":   PN = "108"  !CDS_PN = "108";
"DQ<41>":   PN = "253"  !CDS_PN = "253";
"DQ<42>":   PN = "115"  !CDS_PN = "115";
"DQ<43>":   PN = "260"  !CDS_PN = "260";
"DQ<44>":   PN = "106"  !CDS_PN = "106";
"DQ<45>":   PN = "251"  !CDS_PN = "251";
"DQ<46>":   PN = "113"  !CDS_PN = "113";
"DQ<47>":   PN = "258"  !CDS_PN = "258";
"DQ<48>":   PN = "119"  !CDS_PN = "119";
"DQ<49>":   PN = "264"  !CDS_PN = "264";
"DQ<50>":   PN = "126"  !CDS_PN = "126";
"DQ<51>":   PN = "271"  !CDS_PN = "271";
"DQ<52>":   PN = "117"  !CDS_PN = "117";
"DQ<53>":   PN = "262"  !CDS_PN = "262";
"DQ<54>":   PN = "124"  !CDS_PN = "124";
"DQ<55>":   PN = "269"  !CDS_PN = "269";
"DQ<56>":   PN = "130"  !CDS_PN = "130";
"DQ<57>":   PN = "275"  !CDS_PN = "275";
"DQ<58>":   PN = "137"  !CDS_PN = "137";
"DQ<59>":   PN = "282"  !CDS_PN = "282";
"DQ<60>":   PN = "128"  !CDS_PN = "128";
"DQ<61>":   PN = "273"  !CDS_PN = "273";
"DQ<62>":   PN = "135"  !CDS_PN = "135";
"DQ<63>":   PN = "280"  !CDS_PN = "280";
"EVENT_N":   PN = "78"  !CDS_PN = "78";
"ODT<0>":   PN = "87"  !CDS_PN = "87";
"ODT<1>":   PN = "91"  !CDS_PN = "91";
"PAR":   PN = "222"  !CDS_PN = "222";
"RESET_N":   PN = "58"  !CDS_PN = "58";
"RFU<0>":   PN = "205"  !CDS_PN = "205";
"RFU<1>":   PN = "227"  !CDS_PN = "227";
"RFU<2>":   PN = "144"  !CDS_PN = "144";
"S0_N":   PN = "84"  !CDS_PN = "84";
"S1_N":   PN = "89"  !CDS_PN = "89";
"S2_N_C<0>":   PN = "93"  !CDS_PN = "93";
"S3_N_C<1>":   PN = "237"  !CDS_PN = "237";
"SA<0>":   PN = "139"  !CDS_PN = "139";
"SA<1>":   PN = "140"  !CDS_PN = "140";
"SA<2>":   PN = "238"  !CDS_PN = "238";
"SAVE_N_NC":   PN = "230"  !CDS_PN = "230";
"SCL":   PN = "141"  !CDS_PN = "141";
"SDA":   PN = "285"  !CDS_PN = "285";
"VDDSPD":   PN = "284"  !CDS_PN = "284";
"VREFCA":   PN = "146"  !CDS_PN = "146";
BODY = "SCONN288_H44441003","I67": #LOCATION = "J6U1" !CDS_LOCATION = "J6U1" #SEC = "4" !CDS_SEC = "4";
"12V<0>":   PN = "145"  !CDS_PN = "145";
"12V<1>":   PN = "1"  !CDS_PN = "1";
"VDD<0>":   PN = "236"  !CDS_PN = "236";
"VDD<1>":   PN = "233"  !CDS_PN = "233";
"VDD<2>":   PN = "231"  !CDS_PN = "231";
"VDD<3>":   PN = "229"  !CDS_PN = "229";
"VDD<4>":   PN = "226"  !CDS_PN = "226";
"VDD<5>":   PN = "223"  !CDS_PN = "223";
"VDD<6>":   PN = "220"  !CDS_PN = "220";
"VDD<7>":   PN = "217"  !CDS_PN = "217";
"VDD<8>":   PN = "215"  !CDS_PN = "215";
"VDD<9>":   PN = "212"  !CDS_PN = "212";
"VDD<10>":   PN = "209"  !CDS_PN = "209";
"VDD<11>":   PN = "206"  !CDS_PN = "206";
"VDD<12>":   PN = "204"  !CDS_PN = "204";
"VDD<13>":   PN = "92"  !CDS_PN = "92";
"VDD<14>":   PN = "90"  !CDS_PN = "90";
"VDD<15>":   PN = "88"  !CDS_PN = "88";
"VDD<16>":   PN = "85"  !CDS_PN = "85";
"VDD<17>":   PN = "83"  !CDS_PN = "83";
"VDD<18>":   PN = "80"  !CDS_PN = "80";
"VDD<19>":   PN = "76"  !CDS_PN = "76";
"VDD<20>":   PN = "73"  !CDS_PN = "73";
"VDD<21>":   PN = "70"  !CDS_PN = "70";
"VDD<22>":   PN = "67"  !CDS_PN = "67";
"VDD<23>":   PN = "64"  !CDS_PN = "64";
"VDD<24>":   PN = "61"  !CDS_PN = "61";
"VDD<25>":   PN = "59"  !CDS_PN = "59";
"VPP<0>":   PN = "287"  !CDS_PN = "287";
"VPP<1>":   PN = "286"  !CDS_PN = "286";
"VPP<2>":   PN = "288"  !CDS_PN = "288";
"VPP<3>":   PN = "143"  !CDS_PN = "143";
"VPP<4>":   PN = "142"  !CDS_PN = "142";
"VTT<0>":   PN = "221"  !CDS_PN = "221";
"VTT<1>":   PN = "77"  !CDS_PN = "77";
BODY = "SCONN288_H44441003","I112": #LOCATION = "J6U1" !CDS_LOCATION = "J6U1" #SEC = "2" !CDS_SEC = "2";
"DQS0N":   PN = "152"  !CDS_PN = "152";
"DQS0P":   PN = "153"  !CDS_PN = "153";
"DQS1N":   PN = "163"  !CDS_PN = "163";
"DQS1P":   PN = "164"  !CDS_PN = "164";
"DQS2N":   PN = "174"  !CDS_PN = "174";
"DQS2P":   PN = "175"  !CDS_PN = "175";
"DQS3N":   PN = "185"  !CDS_PN = "185";
"DQS3P":   PN = "186"  !CDS_PN = "186";
"DQS4N":   PN = "244"  !CDS_PN = "244";
"DQS4P":   PN = "245"  !CDS_PN = "245";
"DQS5N":   PN = "255"  !CDS_PN = "255";
"DQS5P":   PN = "256"  !CDS_PN = "256";
"DQS6N":   PN = "266"  !CDS_PN = "266";
"DQS6P":   PN = "267"  !CDS_PN = "267";
"DQS7N":   PN = "277"  !CDS_PN = "277";
"DQS7P":   PN = "278"  !CDS_PN = "278";
"DQS8N":   PN = "196"  !CDS_PN = "196";
"DQS8P":   PN = "197"  !CDS_PN = "197";
"DQS9N":   PN = "8"  !CDS_PN = "8";
"DQS9P":   PN = "7"  !CDS_PN = "7";
"DQS10N":   PN = "19"  !CDS_PN = "19";
"DQS10P":   PN = "18"  !CDS_PN = "18";
"DQS11N":   PN = "30"  !CDS_PN = "30";
"DQS11P":   PN = "29"  !CDS_PN = "29";
"DQS12N":   PN = "41"  !CDS_PN = "41";
"DQS12P":   PN = "40"  !CDS_PN = "40";
"DQS13N":   PN = "100"  !CDS_PN = "100";
"DQS13P":   PN = "99"  !CDS_PN = "99";
"DQS14N":   PN = "111"  !CDS_PN = "111";
"DQS14P":   PN = "110"  !CDS_PN = "110";
"DQS15N":   PN = "122"  !CDS_PN = "122";
"DQS15P":   PN = "121"  !CDS_PN = "121";
"DQS16N":   PN = "133"  !CDS_PN = "133";
"DQS16P":   PN = "132"  !CDS_PN = "132";
"DQS17N":   PN = "52"  !CDS_PN = "52";
"DQS17P":   PN = "51"  !CDS_PN = "51";
BODY = "SCONN288_H44441003","I138": #LOCATION = "J6U1" !CDS_LOCATION = "J6U1" #SEC = "3" !CDS_SEC = "3";
"VSS<0>":   PN = "283"  !CDS_PN = "283";
"VSS<1>":   PN = "281"  !CDS_PN = "281";
"VSS<2>":   PN = "279"  !CDS_PN = "279";
"VSS<3>":   PN = "276"  !CDS_PN = "276";
"VSS<4>":   PN = "274"  !CDS_PN = "274";
"VSS<5>":   PN = "272"  !CDS_PN = "272";
"VSS<6>":   PN = "270"  !CDS_PN = "270";
"VSS<7>":   PN = "268"  !CDS_PN = "268";
"VSS<8>":   PN = "265"  !CDS_PN = "265";
"VSS<9>":   PN = "263"  !CDS_PN = "263";
"VSS<10>":   PN = "261"  !CDS_PN = "261";
"VSS<11>":   PN = "259"  !CDS_PN = "259";
"VSS<12>":   PN = "257"  !CDS_PN = "257";
"VSS<13>":   PN = "254"  !CDS_PN = "254";
"VSS<14>":   PN = "252"  !CDS_PN = "252";
"VSS<15>":   PN = "250"  !CDS_PN = "250";
"VSS<16>":   PN = "248"  !CDS_PN = "248";
"VSS<17>":   PN = "246"  !CDS_PN = "246";
"VSS<18>":   PN = "243"  !CDS_PN = "243";
"VSS<19>":   PN = "241"  !CDS_PN = "241";
"VSS<20>":   PN = "239"  !CDS_PN = "239";
"VSS<21>":   PN = "202"  !CDS_PN = "202";
"VSS<22>":   PN = "200"  !CDS_PN = "200";
"VSS<23>":   PN = "198"  !CDS_PN = "198";
"VSS<24>":   PN = "195"  !CDS_PN = "195";
"VSS<25>":   PN = "193"  !CDS_PN = "193";
"VSS<26>":   PN = "191"  !CDS_PN = "191";
"VSS<27>":   PN = "189"  !CDS_PN = "189";
"VSS<28>":   PN = "187"  !CDS_PN = "187";
"VSS<29>":   PN = "184"  !CDS_PN = "184";
"VSS<30>":   PN = "182"  !CDS_PN = "182";
"VSS<31>":   PN = "180"  !CDS_PN = "180";
"VSS<32>":   PN = "178"  !CDS_PN = "178";
"VSS<33>":   PN = "176"  !CDS_PN = "176";
"VSS<34>":   PN = "173"  !CDS_PN = "173";
"VSS<35>":   PN = "171"  !CDS_PN = "171";
"VSS<36>":   PN = "169"  !CDS_PN = "169";
"VSS<37>":   PN = "167"  !CDS_PN = "167";
"VSS<38>":   PN = "165"  !CDS_PN = "165";
"VSS<39>":   PN = "162"  !CDS_PN = "162";
"VSS<40>":   PN = "160"  !CDS_PN = "160";
"VSS<41>":   PN = "158"  !CDS_PN = "158";
"VSS<42>":   PN = "156"  !CDS_PN = "156";
"VSS<43>":   PN = "154"  !CDS_PN = "154";
"VSS<44>":   PN = "151"  !CDS_PN = "151";
"VSS<45>":   PN = "149"  !CDS_PN = "149";
"VSS<46>":   PN = "147"  !CDS_PN = "147";
"VSS<47>":   PN = "138"  !CDS_PN = "138";
"VSS<48>":   PN = "136"  !CDS_PN = "136";
"VSS<49>":   PN = "134"  !CDS_PN = "134";
"VSS<50>":   PN = "131"  !CDS_PN = "131";
"VSS<51>":   PN = "129"  !CDS_PN = "129";
"VSS<52>":   PN = "127"  !CDS_PN = "127";
"VSS<53>":   PN = "125"  !CDS_PN = "125";
"VSS<54>":   PN = "123"  !CDS_PN = "123";
"VSS<55>":   PN = "120"  !CDS_PN = "120";
"VSS<56>":   PN = "118"  !CDS_PN = "118";
"VSS<57>":   PN = "116"  !CDS_PN = "116";
"VSS<58>":   PN = "114"  !CDS_PN = "114";
"VSS<59>":   PN = "112"  !CDS_PN = "112";
"VSS<60>":   PN = "109"  !CDS_PN = "109";
"VSS<61>":   PN = "107"  !CDS_PN = "107";
"VSS<62>":   PN = "105"  !CDS_PN = "105";
"VSS<63>":   PN = "103"  !CDS_PN = "103";
"VSS<64>":   PN = "101"  !CDS_PN = "101";
"VSS<65>":   PN = "98"  !CDS_PN = "98";
"VSS<66>":   PN = "96"  !CDS_PN = "96";
"VSS<67>":   PN = "94"  !CDS_PN = "94";
"VSS<68>":   PN = "57"  !CDS_PN = "57";
"VSS<69>":   PN = "55"  !CDS_PN = "55";
"VSS<70>":   PN = "53"  !CDS_PN = "53";
"VSS<71>":   PN = "50"  !CDS_PN = "50";
"VSS<72>":   PN = "48"  !CDS_PN = "48";
"VSS<73>":   PN = "46"  !CDS_PN = "46";
"VSS<74>":   PN = "44"  !CDS_PN = "44";
"VSS<75>":   PN = "42"  !CDS_PN = "42";
"VSS<76>":   PN = "39"  !CDS_PN = "39";
"VSS<77>":   PN = "37"  !CDS_PN = "37";
"VSS<78>":   PN = "35"  !CDS_PN = "35";
"VSS<79>":   PN = "33"  !CDS_PN = "33";
"VSS<80>":   PN = "31"  !CDS_PN = "31";
"VSS<81>":   PN = "28"  !CDS_PN = "28";
"VSS<82>":   PN = "26"  !CDS_PN = "26";
"VSS<83>":   PN = "24"  !CDS_PN = "24";
"VSS<84>":   PN = "22"  !CDS_PN = "22";
"VSS<85>":   PN = "20"  !CDS_PN = "20";
"VSS<86>":   PN = "17"  !CDS_PN = "17";
"VSS<87>":   PN = "15"  !CDS_PN = "15";
"VSS<88>":   PN = "13"  !CDS_PN = "13";
"VSS<89>":   PN = "11"  !CDS_PN = "11";
"VSS<90>":   PN = "9"  !CDS_PN = "9";
"VSS<91>":   PN = "6"  !CDS_PN = "6";
"VSS<92>":   PN = "4"  !CDS_PN = "4";
"VSS<93>":   PN = "2"  !CDS_PN = "2";
DRAWING = "@baseboard_fab2_lib.baseboard_fab2(sch_1):page47";
BODY = "SCONN288_H44441004","I43": #LOCATION = "J4G3" !CDS_LOCATION = "J4G3" #SEC = "3" !CDS_SEC = "3";
"VSS<0>":   PN = "283"  !CDS_PN = "283";
"VSS<1>":   PN = "281"  !CDS_PN = "281";
"VSS<2>":   PN = "279"  !CDS_PN = "279";
"VSS<3>":   PN = "276"  !CDS_PN = "276";
"VSS<4>":   PN = "274"  !CDS_PN = "274";
"VSS<5>":   PN = "272"  !CDS_PN = "272";
"VSS<6>":   PN = "270"  !CDS_PN = "270";
"VSS<7>":   PN = "268"  !CDS_PN = "268";
"VSS<8>":   PN = "265"  !CDS_PN = "265";
"VSS<9>":   PN = "263"  !CDS_PN = "263";
"VSS<10>":   PN = "261"  !CDS_PN = "261";
"VSS<11>":   PN = "259"  !CDS_PN = "259";
"VSS<12>":   PN = "257"  !CDS_PN = "257";
"VSS<13>":   PN = "254"  !CDS_PN = "254";
"VSS<14>":   PN = "252"  !CDS_PN = "252";
"VSS<15>":   PN = "250"  !CDS_PN = "250";
"VSS<16>":   PN = "248"  !CDS_PN = "248";
"VSS<17>":   PN = "246"  !CDS_PN = "246";
"VSS<18>":   PN = "243"  !CDS_PN = "243";
"VSS<19>":   PN = "241"  !CDS_PN = "241";
"VSS<20>":   PN = "239"  !CDS_PN = "239";
"VSS<21>":   PN = "202"  !CDS_PN = "202";
"VSS<22>":   PN = "200"  !CDS_PN = "200";
"VSS<23>":   PN = "198"  !CDS_PN = "198";
"VSS<24>":   PN = "195"  !CDS_PN = "195";
"VSS<25>":   PN = "193"  !CDS_PN = "193";
"VSS<26>":   PN = "191"  !CDS_PN = "191";
"VSS<27>":   PN = "189"  !CDS_PN = "189";
"VSS<28>":   PN = "187"  !CDS_PN = "187";
"VSS<29>":   PN = "184"  !CDS_PN = "184";
"VSS<30>":   PN = "182"  !CDS_PN = "182";
"VSS<31>":   PN = "180"  !CDS_PN = "180";
"VSS<32>":   PN = "178"  !CDS_PN = "178";
"VSS<33>":   PN = "176"  !CDS_PN = "176";
"VSS<34>":   PN = "173"  !CDS_PN = "173";
"VSS<35>":   PN = "171"  !CDS_PN = "171";
"VSS<36>":   PN = "169"  !CDS_PN = "169";
"VSS<37>":   PN = "167"  !CDS_PN = "167";
"VSS<38>":   PN = "165"  !CDS_PN = "165";
"VSS<39>":   PN = "162"  !CDS_PN = "162";
"VSS<40>":   PN = "160"  !CDS_PN = "160";
"VSS<41>":   PN = "158"  !CDS_PN = "158";
"VSS<42>":   PN = "156"  !CDS_PN = "156";
"VSS<43>":   PN = "154"  !CDS_PN = "154";
"VSS<44>":   PN = "151"  !CDS_PN = "151";
"VSS<45>":   PN = "149"  !CDS_PN = "149";
"VSS<46>":   PN = "147"  !CDS_PN = "147";
"VSS<47>":   PN = "138"  !CDS_PN = "138";
"VSS<48>":   PN = "136"  !CDS_PN = "136";
"VSS<49>":   PN = "134"  !CDS_PN = "134";
"VSS<50>":   PN = "131"  !CDS_PN = "131";
"VSS<51>":   PN = "129"  !CDS_PN = "129";
"VSS<52>":   PN = "127"  !CDS_PN = "127";
"VSS<53>":   PN = "125"  !CDS_PN = "125";
"VSS<54>":   PN = "123"  !CDS_PN = "123";
"VSS<55>":   PN = "120"  !CDS_PN = "120";
"VSS<56>":   PN = "118"  !CDS_PN = "118";
"VSS<57>":   PN = "116"  !CDS_PN = "116";
"VSS<58>":   PN = "114"  !CDS_PN = "114";
"VSS<59>":   PN = "112"  !CDS_PN = "112";
"VSS<60>":   PN = "109"  !CDS_PN = "109";
"VSS<61>":   PN = "107"  !CDS_PN = "107";
"VSS<62>":   PN = "105"  !CDS_PN = "105";
"VSS<63>":   PN = "103"  !CDS_PN = "103";
"VSS<64>":   PN = "101"  !CDS_PN = "101";
"VSS<65>":   PN = "98"  !CDS_PN = "98";
"VSS<66>":   PN = "96"  !CDS_PN = "96";
"VSS<67>":   PN = "94"  !CDS_PN = "94";
"VSS<68>":   PN = "57"  !CDS_PN = "57";
"VSS<69>":   PN = "55"  !CDS_PN = "55";
"VSS<70>":   PN = "53"  !CDS_PN = "53";
"VSS<71>":   PN = "50"  !CDS_PN = "50";
"VSS<72>":   PN = "48"  !CDS_PN = "48";
"VSS<73>":   PN = "46"  !CDS_PN = "46";
"VSS<74>":   PN = "44"  !CDS_PN = "44";
"VSS<75>":   PN = "42"  !CDS_PN = "42";
"VSS<76>":   PN = "39"  !CDS_PN = "39";
"VSS<77>":   PN = "37"  !CDS_PN = "37";
"VSS<78>":   PN = "35"  !CDS_PN = "35";
"VSS<79>":   PN = "33"  !CDS_PN = "33";
"VSS<80>":   PN = "31"  !CDS_PN = "31";
"VSS<81>":   PN = "28"  !CDS_PN = "28";
"VSS<82>":   PN = "26"  !CDS_PN = "26";
"VSS<83>":   PN = "24"  !CDS_PN = "24";
"VSS<84>":   PN = "22"  !CDS_PN = "22";
"VSS<85>":   PN = "20"  !CDS_PN = "20";
"VSS<86>":   PN = "17"  !CDS_PN = "17";
"VSS<87>":   PN = "15"  !CDS_PN = "15";
"VSS<88>":   PN = "13"  !CDS_PN = "13";
"VSS<89>":   PN = "11"  !CDS_PN = "11";
"VSS<90>":   PN = "9"  !CDS_PN = "9";
"VSS<91>":   PN = "6"  !CDS_PN = "6";
"VSS<92>":   PN = "4"  !CDS_PN = "4";
"VSS<93>":   PN = "2"  !CDS_PN = "2";
BODY = "SCONN288_H44441004","I61": #LOCATION = "J4G3" !CDS_LOCATION = "J4G3" #SEC = "2" !CDS_SEC = "2";
"DQS0N":   PN = "152"  !CDS_PN = "152";
"DQS0P":   PN = "153"  !CDS_PN = "153";
"DQS1N":   PN = "163"  !CDS_PN = "163";
"DQS1P":   PN = "164"  !CDS_PN = "164";
"DQS2N":   PN = "174"  !CDS_PN = "174";
"DQS2P":   PN = "175"  !CDS_PN = "175";
"DQS3N":   PN = "185"  !CDS_PN = "185";
"DQS3P":   PN = "186"  !CDS_PN = "186";
"DQS4N":   PN = "244"  !CDS_PN = "244";
"DQS4P":   PN = "245"  !CDS_PN = "245";
"DQS5N":   PN = "255"  !CDS_PN = "255";
"DQS5P":   PN = "256"  !CDS_PN = "256";
"DQS6N":   PN = "266"  !CDS_PN = "266";
"DQS6P":   PN = "267"  !CDS_PN = "267";
"DQS7N":   PN = "277"  !CDS_PN = "277";
"DQS7P":   PN = "278"  !CDS_PN = "278";
"DQS8N":   PN = "196"  !CDS_PN = "196";
"DQS8P":   PN = "197"  !CDS_PN = "197";
"DQS9N":   PN = "8"  !CDS_PN = "8";
"DQS9P":   PN = "7"  !CDS_PN = "7";
"DQS10N":   PN = "19"  !CDS_PN = "19";
"DQS10P":   PN = "18"  !CDS_PN = "18";
"DQS11N":   PN = "30"  !CDS_PN = "30";
"DQS11P":   PN = "29"  !CDS_PN = "29";
"DQS12N":   PN = "41"  !CDS_PN = "41";
"DQS12P":   PN = "40"  !CDS_PN = "40";
"DQS13N":   PN = "100"  !CDS_PN = "100";
"DQS13P":   PN = "99"  !CDS_PN = "99";
"DQS14N":   PN = "111"  !CDS_PN = "111";
"DQS14P":   PN = "110"  !CDS_PN = "110";
"DQS15N":   PN = "122"  !CDS_PN = "122";
"DQS15P":   PN = "121"  !CDS_PN = "121";
"DQS16N":   PN = "133"  !CDS_PN = "133";
"DQS16P":   PN = "132"  !CDS_PN = "132";
"DQS17N":   PN = "52"  !CDS_PN = "52";
"DQS17P":   PN = "51"  !CDS_PN = "51";
BODY = "SCONN288_H44441004","I111": #LOCATION = "J4G3" !CDS_LOCATION = "J4G3" #SEC = "1" !CDS_SEC = "1";
"A0":   PN = "79"  !CDS_PN = "79";
"A1":   PN = "72"  !CDS_PN = "72";
"A2":   PN = "216"  !CDS_PN = "216";
"A3":   PN = "71"  !CDS_PN = "71";
"A4":   PN = "214"  !CDS_PN = "214";
"A5":   PN = "213"  !CDS_PN = "213";
"A6":   PN = "69"  !CDS_PN = "69";
"A7":   PN = "211"  !CDS_PN = "211";
"A8":   PN = "68"  !CDS_PN = "68";
"A9":   PN = "66"  !CDS_PN = "66";
"A10":   PN = "225"  !CDS_PN = "225";
"A11":   PN = "210"  !CDS_PN = "210";
"A12":   PN = "65"  !CDS_PN = "65";
"A13":   PN = "232"  !CDS_PN = "232";
"A14_WE_N":   PN = "228"  !CDS_PN = "228";
"A15_CAS_N":   PN = "86"  !CDS_PN = "86";
"A16_RAS_N":   PN = "82"  !CDS_PN = "82";
"A17":   PN = "234"  !CDS_PN = "234";
"ACT_N":   PN = "62"  !CDS_PN = "62";
"ALERT_N":   PN = "208"  !CDS_PN = "208";
"BA<0>":   PN = "81"  !CDS_PN = "81";
"BA<1>":   PN = "224"  !CDS_PN = "224";
"BG<0>":   PN = "63"  !CDS_PN = "63";
"BG<1>":   PN = "207"  !CDS_PN = "207";
"C<2>":   PN = "235"  !CDS_PN = "235";
"CB<0>":   PN = "49"  !CDS_PN = "49";
"CB<1>":   PN = "194"  !CDS_PN = "194";
"CB<2>":   PN = "56"  !CDS_PN = "56";
"CB<3>":   PN = "201"  !CDS_PN = "201";
"CB<4>":   PN = "47"  !CDS_PN = "47";
"CB<5>":   PN = "192"  !CDS_PN = "192";
"CB<6>":   PN = "54"  !CDS_PN = "54";
"CB<7>":   PN = "199"  !CDS_PN = "199";
"CK0N":   PN = "75"  !CDS_PN = "75";
"CK0P":   PN = "74"  !CDS_PN = "74";
"CK1N":   PN = "219"  !CDS_PN = "219";
"CK1P":   PN = "218"  !CDS_PN = "218";
"CKE<0>":   PN = "60"  !CDS_PN = "60";
"CKE<1>":   PN = "203"  !CDS_PN = "203";
"DQ<0>":   PN = "5"  !CDS_PN = "5";
"DQ<1>":   PN = "150"  !CDS_PN = "150";
"DQ<2>":   PN = "12"  !CDS_PN = "12";
"DQ<3>":   PN = "157"  !CDS_PN = "157";
"DQ<4>":   PN = "3"  !CDS_PN = "3";
"DQ<5>":   PN = "148"  !CDS_PN = "148";
"DQ<6>":   PN = "10"  !CDS_PN = "10";
"DQ<7>":   PN = "155"  !CDS_PN = "155";
"DQ<8>":   PN = "16"  !CDS_PN = "16";
"DQ<9>":   PN = "161"  !CDS_PN = "161";
"DQ<10>":   PN = "23"  !CDS_PN = "23";
"DQ<11>":   PN = "168"  !CDS_PN = "168";
"DQ<12>":   PN = "14"  !CDS_PN = "14";
"DQ<13>":   PN = "159"  !CDS_PN = "159";
"DQ<14>":   PN = "21"  !CDS_PN = "21";
"DQ<15>":   PN = "166"  !CDS_PN = "166";
"DQ<16>":   PN = "27"  !CDS_PN = "27";
"DQ<17>":   PN = "172"  !CDS_PN = "172";
"DQ<18>":   PN = "34"  !CDS_PN = "34";
"DQ<19>":   PN = "179"  !CDS_PN = "179";
"DQ<20>":   PN = "25"  !CDS_PN = "25";
"DQ<21>":   PN = "170"  !CDS_PN = "170";
"DQ<22>":   PN = "32"  !CDS_PN = "32";
"DQ<23>":   PN = "177"  !CDS_PN = "177";
"DQ<24>":   PN = "38"  !CDS_PN = "38";
"DQ<25>":   PN = "183"  !CDS_PN = "183";
"DQ<26>":   PN = "45"  !CDS_PN = "45";
"DQ<27>":   PN = "190"  !CDS_PN = "190";
"DQ<28>":   PN = "36"  !CDS_PN = "36";
"DQ<29>":   PN = "181"  !CDS_PN = "181";
"DQ<30>":   PN = "43"  !CDS_PN = "43";
"DQ<31>":   PN = "188"  !CDS_PN = "188";
"DQ<32>":   PN = "97"  !CDS_PN = "97";
"DQ<33>":   PN = "242"  !CDS_PN = "242";
"DQ<34>":   PN = "104"  !CDS_PN = "104";
"DQ<35>":   PN = "249"  !CDS_PN = "249";
"DQ<36>":   PN = "95"  !CDS_PN = "95";
"DQ<37>":   PN = "240"  !CDS_PN = "240";
"DQ<38>":   PN = "102"  !CDS_PN = "102";
"DQ<39>":   PN = "247"  !CDS_PN = "247";
"DQ<40>":   PN = "108"  !CDS_PN = "108";
"DQ<41>":   PN = "253"  !CDS_PN = "253";
"DQ<42>":   PN = "115"  !CDS_PN = "115";
"DQ<43>":   PN = "260"  !CDS_PN = "260";
"DQ<44>":   PN = "106"  !CDS_PN = "106";
"DQ<45>":   PN = "251"  !CDS_PN = "251";
"DQ<46>":   PN = "113"  !CDS_PN = "113";
"DQ<47>":   PN = "258"  !CDS_PN = "258";
"DQ<48>":   PN = "119"  !CDS_PN = "119";
"DQ<49>":   PN = "264"  !CDS_PN = "264";
"DQ<50>":   PN = "126"  !CDS_PN = "126";
"DQ<51>":   PN = "271"  !CDS_PN = "271";
"DQ<52>":   PN = "117"  !CDS_PN = "117";
"DQ<53>":   PN = "262"  !CDS_PN = "262";
"DQ<54>":   PN = "124"  !CDS_PN = "124";
"DQ<55>":   PN = "269"  !CDS_PN = "269";
"DQ<56>":   PN = "130"  !CDS_PN = "130";
"DQ<57>":   PN = "275"  !CDS_PN = "275";
"DQ<58>":   PN = "137"  !CDS_PN = "137";
"DQ<59>":   PN = "282"  !CDS_PN = "282";
"DQ<60>":   PN = "128"  !CDS_PN = "128";
"DQ<61>":   PN = "273"  !CDS_PN = "273";
"DQ<62>":   PN = "135"  !CDS_PN = "135";
"DQ<63>":   PN = "280"  !CDS_PN = "280";
"EVENT_N":   PN = "78"  !CDS_PN = "78";
"ODT<0>":   PN = "87"  !CDS_PN = "87";
"ODT<1>":   PN = "91"  !CDS_PN = "91";
"PAR":   PN = "222"  !CDS_PN = "222";
"RESET_N":   PN = "58"  !CDS_PN = "58";
"RFU<0>":   PN = "205"  !CDS_PN = "205";
"RFU<1>":   PN = "227"  !CDS_PN = "227";
"RFU<2>":   PN = "144"  !CDS_PN = "144";
"S0_N":   PN = "84"  !CDS_PN = "84";
"S1_N":   PN = "89"  !CDS_PN = "89";
"S2_N_C<0>":   PN = "93"  !CDS_PN = "93";
"S3_N_C<1>":   PN = "237"  !CDS_PN = "237";
"SA<0>":   PN = "139"  !CDS_PN = "139";
"SA<1>":   PN = "140"  !CDS_PN = "140";
"SA<2>":   PN = "238"  !CDS_PN = "238";
"SAVE_N_NC":   PN = "230"  !CDS_PN = "230";
"SCL":   PN = "141"  !CDS_PN = "141";
"SDA":   PN = "285"  !CDS_PN = "285";
"VDDSPD":   PN = "284"  !CDS_PN = "284";
"VREFCA":   PN = "146"  !CDS_PN = "146";
BODY = "SCONN288_H44441004","I179": #LOCATION = "J4G3" !CDS_LOCATION = "J4G3" #SEC = "4" !CDS_SEC = "4";
"12V<0>":   PN = "145"  !CDS_PN = "145";
"12V<1>":   PN = "1"  !CDS_PN = "1";
"VDD<0>":   PN = "236"  !CDS_PN = "236";
"VDD<1>":   PN = "233"  !CDS_PN = "233";
"VDD<2>":   PN = "231"  !CDS_PN = "231";
"VDD<3>":   PN = "229"  !CDS_PN = "229";
"VDD<4>":   PN = "226"  !CDS_PN = "226";
"VDD<5>":   PN = "223"  !CDS_PN = "223";
"VDD<6>":   PN = "220"  !CDS_PN = "220";
"VDD<7>":   PN = "217"  !CDS_PN = "217";
"VDD<8>":   PN = "215"  !CDS_PN = "215";
"VDD<9>":   PN = "212"  !CDS_PN = "212";
"VDD<10>":   PN = "209"  !CDS_PN = "209";
"VDD<11>":   PN = "206"  !CDS_PN = "206";
"VDD<12>":   PN = "204"  !CDS_PN = "204";
"VDD<13>":   PN = "92"  !CDS_PN = "92";
"VDD<14>":   PN = "90"  !CDS_PN = "90";
"VDD<15>":   PN = "88"  !CDS_PN = "88";
"VDD<16>":   PN = "85"  !CDS_PN = "85";
"VDD<17>":   PN = "83"  !CDS_PN = "83";
"VDD<18>":   PN = "80"  !CDS_PN = "80";
"VDD<19>":   PN = "76"  !CDS_PN = "76";
"VDD<20>":   PN = "73"  !CDS_PN = "73";
"VDD<21>":   PN = "70"  !CDS_PN = "70";
"VDD<22>":   PN = "67"  !CDS_PN = "67";
"VDD<23>":   PN = "64"  !CDS_PN = "64";
"VDD<24>":   PN = "61"  !CDS_PN = "61";
"VDD<25>":   PN = "59"  !CDS_PN = "59";
"VPP<0>":   PN = "287"  !CDS_PN = "287";
"VPP<1>":   PN = "286"  !CDS_PN = "286";
"VPP<2>":   PN = "288"  !CDS_PN = "288";
"VPP<3>":   PN = "143"  !CDS_PN = "143";
"VPP<4>":   PN = "142"  !CDS_PN = "142";
"VTT<0>":   PN = "221"  !CDS_PN = "221";
"VTT<1>":   PN = "77"  !CDS_PN = "77";
BODY = "CAP_A","I188": #LOCATION = "C4G19" !CDS_LOCATION = "C4G19" #SEC = "1" !CDS_SEC = "1";
"A":   PN = "1"  !CDS_PN = "1";
"B":   PN = "2"  !CDS_PN = "2";
DRAWING = "@baseboard_fab2_lib.baseboard_fab2(sch_1):page48";
BODY = "SCONN288_H44441003","I43": #LOCATION = "J6U2" !CDS_LOCATION = "J6U2" #SEC = "3" !CDS_SEC = "3";
"VSS<0>":   PN = "283"  !CDS_PN = "283";
"VSS<1>":   PN = "281"  !CDS_PN = "281";
"VSS<2>":   PN = "279"  !CDS_PN = "279";
"VSS<3>":   PN = "276"  !CDS_PN = "276";
"VSS<4>":   PN = "274"  !CDS_PN = "274";
"VSS<5>":   PN = "272"  !CDS_PN = "272";
"VSS<6>":   PN = "270"  !CDS_PN = "270";
"VSS<7>":   PN = "268"  !CDS_PN = "268";
"VSS<8>":   PN = "265"  !CDS_PN = "265";
"VSS<9>":   PN = "263"  !CDS_PN = "263";
"VSS<10>":   PN = "261"  !CDS_PN = "261";
"VSS<11>":   PN = "259"  !CDS_PN = "259";
"VSS<12>":   PN = "257"  !CDS_PN = "257";
"VSS<13>":   PN = "254"  !CDS_PN = "254";
"VSS<14>":   PN = "252"  !CDS_PN = "252";
"VSS<15>":   PN = "250"  !CDS_PN = "250";
"VSS<16>":   PN = "248"  !CDS_PN = "248";
"VSS<17>":   PN = "246"  !CDS_PN = "246";
"VSS<18>":   PN = "243"  !CDS_PN = "243";
"VSS<19>":   PN = "241"  !CDS_PN = "241";
"VSS<20>":   PN = "239"  !CDS_PN = "239";
"VSS<21>":   PN = "202"  !CDS_PN = "202";
"VSS<22>":   PN = "200"  !CDS_PN = "200";
"VSS<23>":   PN = "198"  !CDS_PN = "198";
"VSS<24>":   PN = "195"  !CDS_PN = "195";
"VSS<25>":   PN = "193"  !CDS_PN = "193";
"VSS<26>":   PN = "191"  !CDS_PN = "191";
"VSS<27>":   PN = "189"  !CDS_PN = "189";
"VSS<28>":   PN = "187"  !CDS_PN = "187";
"VSS<29>":   PN = "184"  !CDS_PN = "184";
"VSS<30>":   PN = "182"  !CDS_PN = "182";
"VSS<31>":   PN = "180"  !CDS_PN = "180";
"VSS<32>":   PN = "178"  !CDS_PN = "178";
"VSS<33>":   PN = "176"  !CDS_PN = "176";
"VSS<34>":   PN = "173"  !CDS_PN = "173";
"VSS<35>":   PN = "171"  !CDS_PN = "171";
"VSS<36>":   PN = "169"  !CDS_PN = "169";
"VSS<37>":   PN = "167"  !CDS_PN = "167";
"VSS<38>":   PN = "165"  !CDS_PN = "165";
"VSS<39>":   PN = "162"  !CDS_PN = "162";
"VSS<40>":   PN = "160"  !CDS_PN = "160";
"VSS<41>":   PN = "158"  !CDS_PN = "158";
"VSS<42>":   PN = "156"  !CDS_PN = "156";
"VSS<43>":   PN = "154"  !CDS_PN = "154";
"VSS<44>":   PN = "151"  !CDS_PN = "151";
"VSS<45>":   PN = "149"  !CDS_PN = "149";
"VSS<46>":   PN = "147"  !CDS_PN = "147";
"VSS<47>":   PN = "138"  !CDS_PN = "138";
"VSS<48>":   PN = "136"  !CDS_PN = "136";
"VSS<49>":   PN = "134"  !CDS_PN = "134";
"VSS<50>":   PN = "131"  !CDS_PN = "131";
"VSS<51>":   PN = "129"  !CDS_PN = "129";
"VSS<52>":   PN = "127"  !CDS_PN = "127";
"VSS<53>":   PN = "125"  !CDS_PN = "125";
"VSS<54>":   PN = "123"  !CDS_PN = "123";
"VSS<55>":   PN = "120"  !CDS_PN = "120";
"VSS<56>":   PN = "118"  !CDS_PN = "118";
"VSS<57>":   PN = "116"  !CDS_PN = "116";
"VSS<58>":   PN = "114"  !CDS_PN = "114";
"VSS<59>":   PN = "112"  !CDS_PN = "112";
"VSS<60>":   PN = "109"  !CDS_PN = "109";
"VSS<61>":   PN = "107"  !CDS_PN = "107";
"VSS<62>":   PN = "105"  !CDS_PN = "105";
"VSS<63>":   PN = "103"  !CDS_PN = "103";
"VSS<64>":   PN = "101"  !CDS_PN = "101";
"VSS<65>":   PN = "98"  !CDS_PN = "98";
"VSS<66>":   PN = "96"  !CDS_PN = "96";
"VSS<67>":   PN = "94"  !CDS_PN = "94";
"VSS<68>":   PN = "57"  !CDS_PN = "57";
"VSS<69>":   PN = "55"  !CDS_PN = "55";
"VSS<70>":   PN = "53"  !CDS_PN = "53";
"VSS<71>":   PN = "50"  !CDS_PN = "50";
"VSS<72>":   PN = "48"  !CDS_PN = "48";
"VSS<73>":   PN = "46"  !CDS_PN = "46";
"VSS<74>":   PN = "44"  !CDS_PN = "44";
"VSS<75>":   PN = "42"  !CDS_PN = "42";
"VSS<76>":   PN = "39"  !CDS_PN = "39";
"VSS<77>":   PN = "37"  !CDS_PN = "37";
"VSS<78>":   PN = "35"  !CDS_PN = "35";
"VSS<79>":   PN = "33"  !CDS_PN = "33";
"VSS<80>":   PN = "31"  !CDS_PN = "31";
"VSS<81>":   PN = "28"  !CDS_PN = "28";
"VSS<82>":   PN = "26"  !CDS_PN = "26";
"VSS<83>":   PN = "24"  !CDS_PN = "24";
"VSS<84>":   PN = "22"  !CDS_PN = "22";
"VSS<85>":   PN = "20"  !CDS_PN = "20";
"VSS<86>":   PN = "17"  !CDS_PN = "17";
"VSS<87>":   PN = "15"  !CDS_PN = "15";
"VSS<88>":   PN = "13"  !CDS_PN = "13";
"VSS<89>":   PN = "11"  !CDS_PN = "11";
"VSS<90>":   PN = "9"  !CDS_PN = "9";
"VSS<91>":   PN = "6"  !CDS_PN = "6";
"VSS<92>":   PN = "4"  !CDS_PN = "4";
"VSS<93>":   PN = "2"  !CDS_PN = "2";
BODY = "SCONN288_H44441003","I61": #LOCATION = "J6U2" !CDS_LOCATION = "J6U2" #SEC = "2" !CDS_SEC = "2";
"DQS0N":   PN = "152"  !CDS_PN = "152";
"DQS0P":   PN = "153"  !CDS_PN = "153";
"DQS1N":   PN = "163"  !CDS_PN = "163";
"DQS1P":   PN = "164"  !CDS_PN = "164";
"DQS2N":   PN = "174"  !CDS_PN = "174";
"DQS2P":   PN = "175"  !CDS_PN = "175";
"DQS3N":   PN = "185"  !CDS_PN = "185";
"DQS3P":   PN = "186"  !CDS_PN = "186";
"DQS4N":   PN = "244"  !CDS_PN = "244";
"DQS4P":   PN = "245"  !CDS_PN = "245";
"DQS5N":   PN = "255"  !CDS_PN = "255";
"DQS5P":   PN = "256"  !CDS_PN = "256";
"DQS6N":   PN = "266"  !CDS_PN = "266";
"DQS6P":   PN = "267"  !CDS_PN = "267";
"DQS7N":   PN = "277"  !CDS_PN = "277";
"DQS7P":   PN = "278"  !CDS_PN = "278";
"DQS8N":   PN = "196"  !CDS_PN = "196";
"DQS8P":   PN = "197"  !CDS_PN = "197";
"DQS9N":   PN = "8"  !CDS_PN = "8";
"DQS9P":   PN = "7"  !CDS_PN = "7";
"DQS10N":   PN = "19"  !CDS_PN = "19";
"DQS10P":   PN = "18"  !CDS_PN = "18";
"DQS11N":   PN = "30"  !CDS_PN = "30";
"DQS11P":   PN = "29"  !CDS_PN = "29";
"DQS12N":   PN = "41"  !CDS_PN = "41";
"DQS12P":   PN = "40"  !CDS_PN = "40";
"DQS13N":   PN = "100"  !CDS_PN = "100";
"DQS13P":   PN = "99"  !CDS_PN = "99";
"DQS14N":   PN = "111"  !CDS_PN = "111";
"DQS14P":   PN = "110"  !CDS_PN = "110";
"DQS15N":   PN = "122"  !CDS_PN = "122";
"DQS15P":   PN = "121"  !CDS_PN = "121";
"DQS16N":   PN = "133"  !CDS_PN = "133";
"DQS16P":   PN = "132"  !CDS_PN = "132";
"DQS17N":   PN = "52"  !CDS_PN = "52";
"DQS17P":   PN = "51"  !CDS_PN = "51";
BODY = "SCONN288_H44441003","I111": #LOCATION = "J6U2" !CDS_LOCATION = "J6U2" #SEC = "1" !CDS_SEC = "1";
"A0":   PN = "79"  !CDS_PN = "79";
"A1":   PN = "72"  !CDS_PN = "72";
"A2":   PN = "216"  !CDS_PN = "216";
"A3":   PN = "71"  !CDS_PN = "71";
"A4":   PN = "214"  !CDS_PN = "214";
"A5":   PN = "213"  !CDS_PN = "213";
"A6":   PN = "69"  !CDS_PN = "69";
"A7":   PN = "211"  !CDS_PN = "211";
"A8":   PN = "68"  !CDS_PN = "68";
"A9":   PN = "66"  !CDS_PN = "66";
"A10":   PN = "225"  !CDS_PN = "225";
"A11":   PN = "210"  !CDS_PN = "210";
"A12":   PN = "65"  !CDS_PN = "65";
"A13":   PN = "232"  !CDS_PN = "232";
"A14_WE_N":   PN = "228"  !CDS_PN = "228";
"A15_CAS_N":   PN = "86"  !CDS_PN = "86";
"A16_RAS_N":   PN = "82"  !CDS_PN = "82";
"A17":   PN = "234"  !CDS_PN = "234";
"ACT_N":   PN = "62"  !CDS_PN = "62";
"ALERT_N":   PN = "208"  !CDS_PN = "208";
"BA<0>":   PN = "81"  !CDS_PN = "81";
"BA<1>":   PN = "224"  !CDS_PN = "224";
"BG<0>":   PN = "63"  !CDS_PN = "63";
"BG<1>":   PN = "207"  !CDS_PN = "207";
"C<2>":   PN = "235"  !CDS_PN = "235";
"CB<0>":   PN = "49"  !CDS_PN = "49";
"CB<1>":   PN = "194"  !CDS_PN = "194";
"CB<2>":   PN = "56"  !CDS_PN = "56";
"CB<3>":   PN = "201"  !CDS_PN = "201";
"CB<4>":   PN = "47"  !CDS_PN = "47";
"CB<5>":   PN = "192"  !CDS_PN = "192";
"CB<6>":   PN = "54"  !CDS_PN = "54";
"CB<7>":   PN = "199"  !CDS_PN = "199";
"CK0N":   PN = "75"  !CDS_PN = "75";
"CK0P":   PN = "74"  !CDS_PN = "74";
"CK1N":   PN = "219"  !CDS_PN = "219";
"CK1P":   PN = "218"  !CDS_PN = "218";
"CKE<0>":   PN = "60"  !CDS_PN = "60";
"CKE<1>":   PN = "203"  !CDS_PN = "203";
"DQ<0>":   PN = "5"  !CDS_PN = "5";
"DQ<1>":   PN = "150"  !CDS_PN = "150";
"DQ<2>":   PN = "12"  !CDS_PN = "12";
"DQ<3>":   PN = "157"  !CDS_PN = "157";
"DQ<4>":   PN = "3"  !CDS_PN = "3";
"DQ<5>":   PN = "148"  !CDS_PN = "148";
"DQ<6>":   PN = "10"  !CDS_PN = "10";
"DQ<7>":   PN = "155"  !CDS_PN = "155";
"DQ<8>":   PN = "16"  !CDS_PN = "16";
"DQ<9>":   PN = "161"  !CDS_PN = "161";
"DQ<10>":   PN = "23"  !CDS_PN = "23";
"DQ<11>":   PN = "168"  !CDS_PN = "168";
"DQ<12>":   PN = "14"  !CDS_PN = "14";
"DQ<13>":   PN = "159"  !CDS_PN = "159";
"DQ<14>":   PN = "21"  !CDS_PN = "21";
"DQ<15>":   PN = "166"  !CDS_PN = "166";
"DQ<16>":   PN = "27"  !CDS_PN = "27";
"DQ<17>":   PN = "172"  !CDS_PN = "172";
"DQ<18>":   PN = "34"  !CDS_PN = "34";
"DQ<19>":   PN = "179"  !CDS_PN = "179";
"DQ<20>":   PN = "25"  !CDS_PN = "25";
"DQ<21>":   PN = "170"  !CDS_PN = "170";
"DQ<22>":   PN = "32"  !CDS_PN = "32";
"DQ<23>":   PN = "177"  !CDS_PN = "177";
"DQ<24>":   PN = "38"  !CDS_PN = "38";
"DQ<25>":   PN = "183"  !CDS_PN = "183";
"DQ<26>":   PN = "45"  !CDS_PN = "45";
"DQ<27>":   PN = "190"  !CDS_PN = "190";
"DQ<28>":   PN = "36"  !CDS_PN = "36";
"DQ<29>":   PN = "181"  !CDS_PN = "181";
"DQ<30>":   PN = "43"  !CDS_PN = "43";
"DQ<31>":   PN = "188"  !CDS_PN = "188";
"DQ<32>":   PN = "97"  !CDS_PN = "97";
"DQ<33>":   PN = "242"  !CDS_PN = "242";
"DQ<34>":   PN = "104"  !CDS_PN = "104";
"DQ<35>":   PN = "249"  !CDS_PN = "249";
"DQ<36>":   PN = "95"  !CDS_PN = "95";
"DQ<37>":   PN = "240"  !CDS_PN = "240";
"DQ<38>":   PN = "102"  !CDS_PN = "102";
"DQ<39>":   PN = "247"  !CDS_PN = "247";
"DQ<40>":   PN = "108"  !CDS_PN = "108";
"DQ<41>":   PN = "253"  !CDS_PN = "253";
"DQ<42>":   PN = "115"  !CDS_PN = "115";
"DQ<43>":   PN = "260"  !CDS_PN = "260";
"DQ<44>":   PN = "106"  !CDS_PN = "106";
"DQ<45>":   PN = "251"  !CDS_PN = "251";
"DQ<46>":   PN = "113"  !CDS_PN = "113";
"DQ<47>":   PN = "258"  !CDS_PN = "258";
"DQ<48>":   PN = "119"  !CDS_PN = "119";
"DQ<49>":   PN = "264"  !CDS_PN = "264";
"DQ<50>":   PN = "126"  !CDS_PN = "126";
"DQ<51>":   PN = "271"  !CDS_PN = "271";
"DQ<52>":   PN = "117"  !CDS_PN = "117";
"DQ<53>":   PN = "262"  !CDS_PN = "262";
"DQ<54>":   PN = "124"  !CDS_PN = "124";
"DQ<55>":   PN = "269"  !CDS_PN = "269";
"DQ<56>":   PN = "130"  !CDS_PN = "130";
"DQ<57>":   PN = "275"  !CDS_PN = "275";
"DQ<58>":   PN = "137"  !CDS_PN = "137";
"DQ<59>":   PN = "282"  !CDS_PN = "282";
"DQ<60>":   PN = "128"  !CDS_PN = "128";
"DQ<61>":   PN = "273"  !CDS_PN = "273";
"DQ<62>":   PN = "135"  !CDS_PN = "135";
"DQ<63>":   PN = "280"  !CDS_PN = "280";
"EVENT_N":   PN = "78"  !CDS_PN = "78";
"ODT<0>":   PN = "87"  !CDS_PN = "87";
"ODT<1>":   PN = "91"  !CDS_PN = "91";
"PAR":   PN = "222"  !CDS_PN = "222";
"RESET_N":   PN = "58"  !CDS_PN = "58";
"RFU<0>":   PN = "205"  !CDS_PN = "205";
"RFU<1>":   PN = "227"  !CDS_PN = "227";
"RFU<2>":   PN = "144"  !CDS_PN = "144";
"S0_N":   PN = "84"  !CDS_PN = "84";
"S1_N":   PN = "89"  !CDS_PN = "89";
"S2_N_C<0>":   PN = "93"  !CDS_PN = "93";
"S3_N_C<1>":   PN = "237"  !CDS_PN = "237";
"SA<0>":   PN = "139"  !CDS_PN = "139";
"SA<1>":   PN = "140"  !CDS_PN = "140";
"SA<2>":   PN = "238"  !CDS_PN = "238";
"SAVE_N_NC":   PN = "230"  !CDS_PN = "230";
"SCL":   PN = "141"  !CDS_PN = "141";
"SDA":   PN = "285"  !CDS_PN = "285";
"VDDSPD":   PN = "284"  !CDS_PN = "284";
"VREFCA":   PN = "146"  !CDS_PN = "146";
BODY = "SCONN288_H44441003","I171": #LOCATION = "J6U2" !CDS_LOCATION = "J6U2" #SEC = "4" !CDS_SEC = "4";
"12V<0>":   PN = "145"  !CDS_PN = "145";
"12V<1>":   PN = "1"  !CDS_PN = "1";
"VDD<0>":   PN = "236"  !CDS_PN = "236";
"VDD<1>":   PN = "233"  !CDS_PN = "233";
"VDD<2>":   PN = "231"  !CDS_PN = "231";
"VDD<3>":   PN = "229"  !CDS_PN = "229";
"VDD<4>":   PN = "226"  !CDS_PN = "226";
"VDD<5>":   PN = "223"  !CDS_PN = "223";
"VDD<6>":   PN = "220"  !CDS_PN = "220";
"VDD<7>":   PN = "217"  !CDS_PN = "217";
"VDD<8>":   PN = "215"  !CDS_PN = "215";
"VDD<9>":   PN = "212"  !CDS_PN = "212";
"VDD<10>":   PN = "209"  !CDS_PN = "209";
"VDD<11>":   PN = "206"  !CDS_PN = "206";
"VDD<12>":   PN = "204"  !CDS_PN = "204";
"VDD<13>":   PN = "92"  !CDS_PN = "92";
"VDD<14>":   PN = "90"  !CDS_PN = "90";
"VDD<15>":   PN = "88"  !CDS_PN = "88";
"VDD<16>":   PN = "85"  !CDS_PN = "85";
"VDD<17>":   PN = "83"  !CDS_PN = "83";
"VDD<18>":   PN = "80"  !CDS_PN = "80";
"VDD<19>":   PN = "76"  !CDS_PN = "76";
"VDD<20>":   PN = "73"  !CDS_PN = "73";
"VDD<21>":   PN = "70"  !CDS_PN = "70";
"VDD<22>":   PN = "67"  !CDS_PN = "67";
"VDD<23>":   PN = "64"  !CDS_PN = "64";
"VDD<24>":   PN = "61"  !CDS_PN = "61";
"VDD<25>":   PN = "59"  !CDS_PN = "59";
"VPP<0>":   PN = "287"  !CDS_PN = "287";
"VPP<1>":   PN = "286"  !CDS_PN = "286";
"VPP<2>":   PN = "288"  !CDS_PN = "288";
"VPP<3>":   PN = "143"  !CDS_PN = "143";
"VPP<4>":   PN = "142"  !CDS_PN = "142";
"VTT<0>":   PN = "221"  !CDS_PN = "221";
"VTT<1>":   PN = "77"  !CDS_PN = "77";
BODY = "CAP_A","I176": #LOCATION = "C6U17" !CDS_LOCATION = "C6U17" #SEC = "1" !CDS_SEC = "1";
"A":   PN = "1"  !CDS_PN = "1";
"B":   PN = "2"  !CDS_PN = "2";
DRAWING = "@baseboard_fab2_lib.baseboard_fab2(sch_1):page49";
BODY = "SCONN288_H44441004","I43": #LOCATION = "J4B1" !CDS_LOCATION = "J4B1" #SEC = "3" !CDS_SEC = "3";
"VSS<0>":   PN = "283"  !CDS_PN = "283";
"VSS<1>":   PN = "281"  !CDS_PN = "281";
"VSS<2>":   PN = "279"  !CDS_PN = "279";
"VSS<3>":   PN = "276"  !CDS_PN = "276";
"VSS<4>":   PN = "274"  !CDS_PN = "274";
"VSS<5>":   PN = "272"  !CDS_PN = "272";
"VSS<6>":   PN = "270"  !CDS_PN = "270";
"VSS<7>":   PN = "268"  !CDS_PN = "268";
"VSS<8>":   PN = "265"  !CDS_PN = "265";
"VSS<9>":   PN = "263"  !CDS_PN = "263";
"VSS<10>":   PN = "261"  !CDS_PN = "261";
"VSS<11>":   PN = "259"  !CDS_PN = "259";
"VSS<12>":   PN = "257"  !CDS_PN = "257";
"VSS<13>":   PN = "254"  !CDS_PN = "254";
"VSS<14>":   PN = "252"  !CDS_PN = "252";
"VSS<15>":   PN = "250"  !CDS_PN = "250";
"VSS<16>":   PN = "248"  !CDS_PN = "248";
"VSS<17>":   PN = "246"  !CDS_PN = "246";
"VSS<18>":   PN = "243"  !CDS_PN = "243";
"VSS<19>":   PN = "241"  !CDS_PN = "241";
"VSS<20>":   PN = "239"  !CDS_PN = "239";
"VSS<21>":   PN = "202"  !CDS_PN = "202";
"VSS<22>":   PN = "200"  !CDS_PN = "200";
"VSS<23>":   PN = "198"  !CDS_PN = "198";
"VSS<24>":   PN = "195"  !CDS_PN = "195";
"VSS<25>":   PN = "193"  !CDS_PN = "193";
"VSS<26>":   PN = "191"  !CDS_PN = "191";
"VSS<27>":   PN = "189"  !CDS_PN = "189";
"VSS<28>":   PN = "187"  !CDS_PN = "187";
"VSS<29>":   PN = "184"  !CDS_PN = "184";
"VSS<30>":   PN = "182"  !CDS_PN = "182";
"VSS<31>":   PN = "180"  !CDS_PN = "180";
"VSS<32>":   PN = "178"  !CDS_PN = "178";
"VSS<33>":   PN = "176"  !CDS_PN = "176";
"VSS<34>":   PN = "173"  !CDS_PN = "173";
"VSS<35>":   PN = "171"  !CDS_PN = "171";
"VSS<36>":   PN = "169"  !CDS_PN = "169";
"VSS<37>":   PN = "167"  !CDS_PN = "167";
"VSS<38>":   PN = "165"  !CDS_PN = "165";
"VSS<39>":   PN = "162"  !CDS_PN = "162";
"VSS<40>":   PN = "160"  !CDS_PN = "160";
"VSS<41>":   PN = "158"  !CDS_PN = "158";
"VSS<42>":   PN = "156"  !CDS_PN = "156";
"VSS<43>":   PN = "154"  !CDS_PN = "154";
"VSS<44>":   PN = "151"  !CDS_PN = "151";
"VSS<45>":   PN = "149"  !CDS_PN = "149";
"VSS<46>":   PN = "147"  !CDS_PN = "147";
"VSS<47>":   PN = "138"  !CDS_PN = "138";
"VSS<48>":   PN = "136"  !CDS_PN = "136";
"VSS<49>":   PN = "134"  !CDS_PN = "134";
"VSS<50>":   PN = "131"  !CDS_PN = "131";
"VSS<51>":   PN = "129"  !CDS_PN = "129";
"VSS<52>":   PN = "127"  !CDS_PN = "127";
"VSS<53>":   PN = "125"  !CDS_PN = "125";
"VSS<54>":   PN = "123"  !CDS_PN = "123";
"VSS<55>":   PN = "120"  !CDS_PN = "120";
"VSS<56>":   PN = "118"  !CDS_PN = "118";
"VSS<57>":   PN = "116"  !CDS_PN = "116";
"VSS<58>":   PN = "114"  !CDS_PN = "114";
"VSS<59>":   PN = "112"  !CDS_PN = "112";
"VSS<60>":   PN = "109"  !CDS_PN = "109";
"VSS<61>":   PN = "107"  !CDS_PN = "107";
"VSS<62>":   PN = "105"  !CDS_PN = "105";
"VSS<63>":   PN = "103"  !CDS_PN = "103";
"VSS<64>":   PN = "101"  !CDS_PN = "101";
"VSS<65>":   PN = "98"  !CDS_PN = "98";
"VSS<66>":   PN = "96"  !CDS_PN = "96";
"VSS<67>":   PN = "94"  !CDS_PN = "94";
"VSS<68>":   PN = "57"  !CDS_PN = "57";
"VSS<69>":   PN = "55"  !CDS_PN = "55";
"VSS<70>":   PN = "53"  !CDS_PN = "53";
"VSS<71>":   PN = "50"  !CDS_PN = "50";
"VSS<72>":   PN = "48"  !CDS_PN = "48";
"VSS<73>":   PN = "46"  !CDS_PN = "46";
"VSS<74>":   PN = "44"  !CDS_PN = "44";
"VSS<75>":   PN = "42"  !CDS_PN = "42";
"VSS<76>":   PN = "39"  !CDS_PN = "39";
"VSS<77>":   PN = "37"  !CDS_PN = "37";
"VSS<78>":   PN = "35"  !CDS_PN = "35";
"VSS<79>":   PN = "33"  !CDS_PN = "33";
"VSS<80>":   PN = "31"  !CDS_PN = "31";
"VSS<81>":   PN = "28"  !CDS_PN = "28";
"VSS<82>":   PN = "26"  !CDS_PN = "26";
"VSS<83>":   PN = "24"  !CDS_PN = "24";
"VSS<84>":   PN = "22"  !CDS_PN = "22";
"VSS<85>":   PN = "20"  !CDS_PN = "20";
"VSS<86>":   PN = "17"  !CDS_PN = "17";
"VSS<87>":   PN = "15"  !CDS_PN = "15";
"VSS<88>":   PN = "13"  !CDS_PN = "13";
"VSS<89>":   PN = "11"  !CDS_PN = "11";
"VSS<90>":   PN = "9"  !CDS_PN = "9";
"VSS<91>":   PN = "6"  !CDS_PN = "6";
"VSS<92>":   PN = "4"  !CDS_PN = "4";
"VSS<93>":   PN = "2"  !CDS_PN = "2";
BODY = "SCONN288_H44441004","I66": #LOCATION = "J4B1" !CDS_LOCATION = "J4B1" #SEC = "2" !CDS_SEC = "2";
"DQS0N":   PN = "152"  !CDS_PN = "152";
"DQS0P":   PN = "153"  !CDS_PN = "153";
"DQS1N":   PN = "163"  !CDS_PN = "163";
"DQS1P":   PN = "164"  !CDS_PN = "164";
"DQS2N":   PN = "174"  !CDS_PN = "174";
"DQS2P":   PN = "175"  !CDS_PN = "175";
"DQS3N":   PN = "185"  !CDS_PN = "185";
"DQS3P":   PN = "186"  !CDS_PN = "186";
"DQS4N":   PN = "244"  !CDS_PN = "244";
"DQS4P":   PN = "245"  !CDS_PN = "245";
"DQS5N":   PN = "255"  !CDS_PN = "255";
"DQS5P":   PN = "256"  !CDS_PN = "256";
"DQS6N":   PN = "266"  !CDS_PN = "266";
"DQS6P":   PN = "267"  !CDS_PN = "267";
"DQS7N":   PN = "277"  !CDS_PN = "277";
"DQS7P":   PN = "278"  !CDS_PN = "278";
"DQS8N":   PN = "196"  !CDS_PN = "196";
"DQS8P":   PN = "197"  !CDS_PN = "197";
"DQS9N":   PN = "8"  !CDS_PN = "8";
"DQS9P":   PN = "7"  !CDS_PN = "7";
"DQS10N":   PN = "19"  !CDS_PN = "19";
"DQS10P":   PN = "18"  !CDS_PN = "18";
"DQS11N":   PN = "30"  !CDS_PN = "30";
"DQS11P":   PN = "29"  !CDS_PN = "29";
"DQS12N":   PN = "41"  !CDS_PN = "41";
"DQS12P":   PN = "40"  !CDS_PN = "40";
"DQS13N":   PN = "100"  !CDS_PN = "100";
"DQS13P":   PN = "99"  !CDS_PN = "99";
"DQS14N":   PN = "111"  !CDS_PN = "111";
"DQS14P":   PN = "110"  !CDS_PN = "110";
"DQS15N":   PN = "122"  !CDS_PN = "122";
"DQS15P":   PN = "121"  !CDS_PN = "121";
"DQS16N":   PN = "133"  !CDS_PN = "133";
"DQS16P":   PN = "132"  !CDS_PN = "132";
"DQS17N":   PN = "52"  !CDS_PN = "52";
"DQS17P":   PN = "51"  !CDS_PN = "51";
BODY = "SCONN288_H44441004","I111": #LOCATION = "J4B1" !CDS_LOCATION = "J4B1" #SEC = "1" !CDS_SEC = "1";
"A0":   PN = "79"  !CDS_PN = "79";
"A1":   PN = "72"  !CDS_PN = "72";
"A2":   PN = "216"  !CDS_PN = "216";
"A3":   PN = "71"  !CDS_PN = "71";
"A4":   PN = "214"  !CDS_PN = "214";
"A5":   PN = "213"  !CDS_PN = "213";
"A6":   PN = "69"  !CDS_PN = "69";
"A7":   PN = "211"  !CDS_PN = "211";
"A8":   PN = "68"  !CDS_PN = "68";
"A9":   PN = "66"  !CDS_PN = "66";
"A10":   PN = "225"  !CDS_PN = "225";
"A11":   PN = "210"  !CDS_PN = "210";
"A12":   PN = "65"  !CDS_PN = "65";
"A13":   PN = "232"  !CDS_PN = "232";
"A14_WE_N":   PN = "228"  !CDS_PN = "228";
"A15_CAS_N":   PN = "86"  !CDS_PN = "86";
"A16_RAS_N":   PN = "82"  !CDS_PN = "82";
"A17":   PN = "234"  !CDS_PN = "234";
"ACT_N":   PN = "62"  !CDS_PN = "62";
"ALERT_N":   PN = "208"  !CDS_PN = "208";
"BA<0>":   PN = "81"  !CDS_PN = "81";
"BA<1>":   PN = "224"  !CDS_PN = "224";
"BG<0>":   PN = "63"  !CDS_PN = "63";
"BG<1>":   PN = "207"  !CDS_PN = "207";
"C<2>":   PN = "235"  !CDS_PN = "235";
"CB<0>":   PN = "49"  !CDS_PN = "49";
"CB<1>":   PN = "194"  !CDS_PN = "194";
"CB<2>":   PN = "56"  !CDS_PN = "56";
"CB<3>":   PN = "201"  !CDS_PN = "201";
"CB<4>":   PN = "47"  !CDS_PN = "47";
"CB<5>":   PN = "192"  !CDS_PN = "192";
"CB<6>":   PN = "54"  !CDS_PN = "54";
"CB<7>":   PN = "199"  !CDS_PN = "199";
"CK0N":   PN = "75"  !CDS_PN = "75";
"CK0P":   PN = "74"  !CDS_PN = "74";
"CK1N":   PN = "219"  !CDS_PN = "219";
"CK1P":   PN = "218"  !CDS_PN = "218";
"CKE<0>":   PN = "60"  !CDS_PN = "60";
"CKE<1>":   PN = "203"  !CDS_PN = "203";
"DQ<0>":   PN = "5"  !CDS_PN = "5";
"DQ<1>":   PN = "150"  !CDS_PN = "150";
"DQ<2>":   PN = "12"  !CDS_PN = "12";
"DQ<3>":   PN = "157"  !CDS_PN = "157";
"DQ<4>":   PN = "3"  !CDS_PN = "3";
"DQ<5>":   PN = "148"  !CDS_PN = "148";
"DQ<6>":   PN = "10"  !CDS_PN = "10";
"DQ<7>":   PN = "155"  !CDS_PN = "155";
"DQ<8>":   PN = "16"  !CDS_PN = "16";
"DQ<9>":   PN = "161"  !CDS_PN = "161";
"DQ<10>":   PN = "23"  !CDS_PN = "23";
"DQ<11>":   PN = "168"  !CDS_PN = "168";
"DQ<12>":   PN = "14"  !CDS_PN = "14";
"DQ<13>":   PN = "159"  !CDS_PN = "159";
"DQ<14>":   PN = "21"  !CDS_PN = "21";
"DQ<15>":   PN = "166"  !CDS_PN = "166";
"DQ<16>":   PN = "27"  !CDS_PN = "27";
"DQ<17>":   PN = "172"  !CDS_PN = "172";
"DQ<18>":   PN = "34"  !CDS_PN = "34";
"DQ<19>":   PN = "179"  !CDS_PN = "179";
"DQ<20>":   PN = "25"  !CDS_PN = "25";
"DQ<21>":   PN = "170"  !CDS_PN = "170";
"DQ<22>":   PN = "32"  !CDS_PN = "32";
"DQ<23>":   PN = "177"  !CDS_PN = "177";
"DQ<24>":   PN = "38"  !CDS_PN = "38";
"DQ<25>":   PN = "183"  !CDS_PN = "183";
"DQ<26>":   PN = "45"  !CDS_PN = "45";
"DQ<27>":   PN = "190"  !CDS_PN = "190";
"DQ<28>":   PN = "36"  !CDS_PN = "36";
"DQ<29>":   PN = "181"  !CDS_PN = "181";
"DQ<30>":   PN = "43"  !CDS_PN = "43";
"DQ<31>":   PN = "188"  !CDS_PN = "188";
"DQ<32>":   PN = "97"  !CDS_PN = "97";
"DQ<33>":   PN = "242"  !CDS_PN = "242";
"DQ<34>":   PN = "104"  !CDS_PN = "104";
"DQ<35>":   PN = "249"  !CDS_PN = "249";
"DQ<36>":   PN = "95"  !CDS_PN = "95";
"DQ<37>":   PN = "240"  !CDS_PN = "240";
"DQ<38>":   PN = "102"  !CDS_PN = "102";
"DQ<39>":   PN = "247"  !CDS_PN = "247";
"DQ<40>":   PN = "108"  !CDS_PN = "108";
"DQ<41>":   PN = "253"  !CDS_PN = "253";
"DQ<42>":   PN = "115"  !CDS_PN = "115";
"DQ<43>":   PN = "260"  !CDS_PN = "260";
"DQ<44>":   PN = "106"  !CDS_PN = "106";
"DQ<45>":   PN = "251"  !CDS_PN = "251";
"DQ<46>":   PN = "113"  !CDS_PN = "113";
"DQ<47>":   PN = "258"  !CDS_PN = "258";
"DQ<48>":   PN = "119"  !CDS_PN = "119";
"DQ<49>":   PN = "264"  !CDS_PN = "264";
"DQ<50>":   PN = "126"  !CDS_PN = "126";
"DQ<51>":   PN = "271"  !CDS_PN = "271";
"DQ<52>":   PN = "117"  !CDS_PN = "117";
"DQ<53>":   PN = "262"  !CDS_PN = "262";
"DQ<54>":   PN = "124"  !CDS_PN = "124";
"DQ<55>":   PN = "269"  !CDS_PN = "269";
"DQ<56>":   PN = "130"  !CDS_PN = "130";
"DQ<57>":   PN = "275"  !CDS_PN = "275";
"DQ<58>":   PN = "137"  !CDS_PN = "137";
"DQ<59>":   PN = "282"  !CDS_PN = "282";
"DQ<60>":   PN = "128"  !CDS_PN = "128";
"DQ<61>":   PN = "273"  !CDS_PN = "273";
"DQ<62>":   PN = "135"  !CDS_PN = "135";
"DQ<63>":   PN = "280"  !CDS_PN = "280";
"EVENT_N":   PN = "78"  !CDS_PN = "78";
"ODT<0>":   PN = "87"  !CDS_PN = "87";
"ODT<1>":   PN = "91"  !CDS_PN = "91";
"PAR":   PN = "222"  !CDS_PN = "222";
"RESET_N":   PN = "58"  !CDS_PN = "58";
"RFU<0>":   PN = "205"  !CDS_PN = "205";
"RFU<1>":   PN = "227"  !CDS_PN = "227";
"RFU<2>":   PN = "144"  !CDS_PN = "144";
"S0_N":   PN = "84"  !CDS_PN = "84";
"S1_N":   PN = "89"  !CDS_PN = "89";
"S2_N_C<0>":   PN = "93"  !CDS_PN = "93";
"S3_N_C<1>":   PN = "237"  !CDS_PN = "237";
"SA<0>":   PN = "139"  !CDS_PN = "139";
"SA<1>":   PN = "140"  !CDS_PN = "140";
"SA<2>":   PN = "238"  !CDS_PN = "238";
"SAVE_N_NC":   PN = "230"  !CDS_PN = "230";
"SCL":   PN = "141"  !CDS_PN = "141";
"SDA":   PN = "285"  !CDS_PN = "285";
"VDDSPD":   PN = "284"  !CDS_PN = "284";
"VREFCA":   PN = "146"  !CDS_PN = "146";
BODY = "SCONN288_H44441004","I169": #LOCATION = "J4B1" !CDS_LOCATION = "J4B1" #SEC = "4" !CDS_SEC = "4";
"12V<0>":   PN = "145"  !CDS_PN = "145";
"12V<1>":   PN = "1"  !CDS_PN = "1";
"VDD<0>":   PN = "236"  !CDS_PN = "236";
"VDD<1>":   PN = "233"  !CDS_PN = "233";
"VDD<2>":   PN = "231"  !CDS_PN = "231";
"VDD<3>":   PN = "229"  !CDS_PN = "229";
"VDD<4>":   PN = "226"  !CDS_PN = "226";
"VDD<5>":   PN = "223"  !CDS_PN = "223";
"VDD<6>":   PN = "220"  !CDS_PN = "220";
"VDD<7>":   PN = "217"  !CDS_PN = "217";
"VDD<8>":   PN = "215"  !CDS_PN = "215";
"VDD<9>":   PN = "212"  !CDS_PN = "212";
"VDD<10>":   PN = "209"  !CDS_PN = "209";
"VDD<11>":   PN = "206"  !CDS_PN = "206";
"VDD<12>":   PN = "204"  !CDS_PN = "204";
"VDD<13>":   PN = "92"  !CDS_PN = "92";
"VDD<14>":   PN = "90"  !CDS_PN = "90";
"VDD<15>":   PN = "88"  !CDS_PN = "88";
"VDD<16>":   PN = "85"  !CDS_PN = "85";
"VDD<17>":   PN = "83"  !CDS_PN = "83";
"VDD<18>":   PN = "80"  !CDS_PN = "80";
"VDD<19>":   PN = "76"  !CDS_PN = "76";
"VDD<20>":   PN = "73"  !CDS_PN = "73";
"VDD<21>":   PN = "70"  !CDS_PN = "70";
"VDD<22>":   PN = "67"  !CDS_PN = "67";
"VDD<23>":   PN = "64"  !CDS_PN = "64";
"VDD<24>":   PN = "61"  !CDS_PN = "61";
"VDD<25>":   PN = "59"  !CDS_PN = "59";
"VPP<0>":   PN = "287"  !CDS_PN = "287";
"VPP<1>":   PN = "286"  !CDS_PN = "286";
"VPP<2>":   PN = "288"  !CDS_PN = "288";
"VPP<3>":   PN = "143"  !CDS_PN = "143";
"VPP<4>":   PN = "142"  !CDS_PN = "142";
"VTT<0>":   PN = "221"  !CDS_PN = "221";
"VTT<1>":   PN = "77"  !CDS_PN = "77";
BODY = "CAP_A","I179": #LOCATION = "C4B12" !CDS_LOCATION = "C4B12" #SEC = "1" !CDS_SEC = "1";
"A":   PN = "1"  !CDS_PN = "1";
"B":   PN = "2"  !CDS_PN = "2";
DRAWING = "@baseboard_fab2_lib.baseboard_fab2(sch_1):page50";
BODY = "SCONN288_H44441003","I44": #LOCATION = "J6M1" !CDS_LOCATION = "J6M1" #SEC = "3" !CDS_SEC = "3";
"VSS<0>":   PN = "283"  !CDS_PN = "283";
"VSS<1>":   PN = "281"  !CDS_PN = "281";
"VSS<2>":   PN = "279"  !CDS_PN = "279";
"VSS<3>":   PN = "276"  !CDS_PN = "276";
"VSS<4>":   PN = "274"  !CDS_PN = "274";
"VSS<5>":   PN = "272"  !CDS_PN = "272";
"VSS<6>":   PN = "270"  !CDS_PN = "270";
"VSS<7>":   PN = "268"  !CDS_PN = "268";
"VSS<8>":   PN = "265"  !CDS_PN = "265";
"VSS<9>":   PN = "263"  !CDS_PN = "263";
"VSS<10>":   PN = "261"  !CDS_PN = "261";
"VSS<11>":   PN = "259"  !CDS_PN = "259";
"VSS<12>":   PN = "257"  !CDS_PN = "257";
"VSS<13>":   PN = "254"  !CDS_PN = "254";
"VSS<14>":   PN = "252"  !CDS_PN = "252";
"VSS<15>":   PN = "250"  !CDS_PN = "250";
"VSS<16>":   PN = "248"  !CDS_PN = "248";
"VSS<17>":   PN = "246"  !CDS_PN = "246";
"VSS<18>":   PN = "243"  !CDS_PN = "243";
"VSS<19>":   PN = "241"  !CDS_PN = "241";
"VSS<20>":   PN = "239"  !CDS_PN = "239";
"VSS<21>":   PN = "202"  !CDS_PN = "202";
"VSS<22>":   PN = "200"  !CDS_PN = "200";
"VSS<23>":   PN = "198"  !CDS_PN = "198";
"VSS<24>":   PN = "195"  !CDS_PN = "195";
"VSS<25>":   PN = "193"  !CDS_PN = "193";
"VSS<26>":   PN = "191"  !CDS_PN = "191";
"VSS<27>":   PN = "189"  !CDS_PN = "189";
"VSS<28>":   PN = "187"  !CDS_PN = "187";
"VSS<29>":   PN = "184"  !CDS_PN = "184";
"VSS<30>":   PN = "182"  !CDS_PN = "182";
"VSS<31>":   PN = "180"  !CDS_PN = "180";
"VSS<32>":   PN = "178"  !CDS_PN = "178";
"VSS<33>":   PN = "176"  !CDS_PN = "176";
"VSS<34>":   PN = "173"  !CDS_PN = "173";
"VSS<35>":   PN = "171"  !CDS_PN = "171";
"VSS<36>":   PN = "169"  !CDS_PN = "169";
"VSS<37>":   PN = "167"  !CDS_PN = "167";
"VSS<38>":   PN = "165"  !CDS_PN = "165";
"VSS<39>":   PN = "162"  !CDS_PN = "162";
"VSS<40>":   PN = "160"  !CDS_PN = "160";
"VSS<41>":   PN = "158"  !CDS_PN = "158";
"VSS<42>":   PN = "156"  !CDS_PN = "156";
"VSS<43>":   PN = "154"  !CDS_PN = "154";
"VSS<44>":   PN = "151"  !CDS_PN = "151";
"VSS<45>":   PN = "149"  !CDS_PN = "149";
"VSS<46>":   PN = "147"  !CDS_PN = "147";
"VSS<47>":   PN = "138"  !CDS_PN = "138";
"VSS<48>":   PN = "136"  !CDS_PN = "136";
"VSS<49>":   PN = "134"  !CDS_PN = "134";
"VSS<50>":   PN = "131"  !CDS_PN = "131";
"VSS<51>":   PN = "129"  !CDS_PN = "129";
"VSS<52>":   PN = "127"  !CDS_PN = "127";
"VSS<53>":   PN = "125"  !CDS_PN = "125";
"VSS<54>":   PN = "123"  !CDS_PN = "123";
"VSS<55>":   PN = "120"  !CDS_PN = "120";
"VSS<56>":   PN = "118"  !CDS_PN = "118";
"VSS<57>":   PN = "116"  !CDS_PN = "116";
"VSS<58>":   PN = "114"  !CDS_PN = "114";
"VSS<59>":   PN = "112"  !CDS_PN = "112";
"VSS<60>":   PN = "109"  !CDS_PN = "109";
"VSS<61>":   PN = "107"  !CDS_PN = "107";
"VSS<62>":   PN = "105"  !CDS_PN = "105";
"VSS<63>":   PN = "103"  !CDS_PN = "103";
"VSS<64>":   PN = "101"  !CDS_PN = "101";
"VSS<65>":   PN = "98"  !CDS_PN = "98";
"VSS<66>":   PN = "96"  !CDS_PN = "96";
"VSS<67>":   PN = "94"  !CDS_PN = "94";
"VSS<68>":   PN = "57"  !CDS_PN = "57";
"VSS<69>":   PN = "55"  !CDS_PN = "55";
"VSS<70>":   PN = "53"  !CDS_PN = "53";
"VSS<71>":   PN = "50"  !CDS_PN = "50";
"VSS<72>":   PN = "48"  !CDS_PN = "48";
"VSS<73>":   PN = "46"  !CDS_PN = "46";
"VSS<74>":   PN = "44"  !CDS_PN = "44";
"VSS<75>":   PN = "42"  !CDS_PN = "42";
"VSS<76>":   PN = "39"  !CDS_PN = "39";
"VSS<77>":   PN = "37"  !CDS_PN = "37";
"VSS<78>":   PN = "35"  !CDS_PN = "35";
"VSS<79>":   PN = "33"  !CDS_PN = "33";
"VSS<80>":   PN = "31"  !CDS_PN = "31";
"VSS<81>":   PN = "28"  !CDS_PN = "28";
"VSS<82>":   PN = "26"  !CDS_PN = "26";
"VSS<83>":   PN = "24"  !CDS_PN = "24";
"VSS<84>":   PN = "22"  !CDS_PN = "22";
"VSS<85>":   PN = "20"  !CDS_PN = "20";
"VSS<86>":   PN = "17"  !CDS_PN = "17";
"VSS<87>":   PN = "15"  !CDS_PN = "15";
"VSS<88>":   PN = "13"  !CDS_PN = "13";
"VSS<89>":   PN = "11"  !CDS_PN = "11";
"VSS<90>":   PN = "9"  !CDS_PN = "9";
"VSS<91>":   PN = "6"  !CDS_PN = "6";
"VSS<92>":   PN = "4"  !CDS_PN = "4";
"VSS<93>":   PN = "2"  !CDS_PN = "2";
BODY = "SCONN288_H44441003","I46": #LOCATION = "J6M1" !CDS_LOCATION = "J6M1" #SEC = "2" !CDS_SEC = "2";
"DQS0N":   PN = "152"  !CDS_PN = "152";
"DQS0P":   PN = "153"  !CDS_PN = "153";
"DQS1N":   PN = "163"  !CDS_PN = "163";
"DQS1P":   PN = "164"  !CDS_PN = "164";
"DQS2N":   PN = "174"  !CDS_PN = "174";
"DQS2P":   PN = "175"  !CDS_PN = "175";
"DQS3N":   PN = "185"  !CDS_PN = "185";
"DQS3P":   PN = "186"  !CDS_PN = "186";
"DQS4N":   PN = "244"  !CDS_PN = "244";
"DQS4P":   PN = "245"  !CDS_PN = "245";
"DQS5N":   PN = "255"  !CDS_PN = "255";
"DQS5P":   PN = "256"  !CDS_PN = "256";
"DQS6N":   PN = "266"  !CDS_PN = "266";
"DQS6P":   PN = "267"  !CDS_PN = "267";
"DQS7N":   PN = "277"  !CDS_PN = "277";
"DQS7P":   PN = "278"  !CDS_PN = "278";
"DQS8N":   PN = "196"  !CDS_PN = "196";
"DQS8P":   PN = "197"  !CDS_PN = "197";
"DQS9N":   PN = "8"  !CDS_PN = "8";
"DQS9P":   PN = "7"  !CDS_PN = "7";
"DQS10N":   PN = "19"  !CDS_PN = "19";
"DQS10P":   PN = "18"  !CDS_PN = "18";
"DQS11N":   PN = "30"  !CDS_PN = "30";
"DQS11P":   PN = "29"  !CDS_PN = "29";
"DQS12N":   PN = "41"  !CDS_PN = "41";
"DQS12P":   PN = "40"  !CDS_PN = "40";
"DQS13N":   PN = "100"  !CDS_PN = "100";
"DQS13P":   PN = "99"  !CDS_PN = "99";
"DQS14N":   PN = "111"  !CDS_PN = "111";
"DQS14P":   PN = "110"  !CDS_PN = "110";
"DQS15N":   PN = "122"  !CDS_PN = "122";
"DQS15P":   PN = "121"  !CDS_PN = "121";
"DQS16N":   PN = "133"  !CDS_PN = "133";
"DQS16P":   PN = "132"  !CDS_PN = "132";
"DQS17N":   PN = "52"  !CDS_PN = "52";
"DQS17P":   PN = "51"  !CDS_PN = "51";
BODY = "SCONN288_H44441003","I50": #LOCATION = "J6M1" !CDS_LOCATION = "J6M1" #SEC = "4" !CDS_SEC = "4";
"12V<0>":   PN = "145"  !CDS_PN = "145";
"12V<1>":   PN = "1"  !CDS_PN = "1";
"VDD<0>":   PN = "236"  !CDS_PN = "236";
"VDD<1>":   PN = "233"  !CDS_PN = "233";
"VDD<2>":   PN = "231"  !CDS_PN = "231";
"VDD<3>":   PN = "229"  !CDS_PN = "229";
"VDD<4>":   PN = "226"  !CDS_PN = "226";
"VDD<5>":   PN = "223"  !CDS_PN = "223";
"VDD<6>":   PN = "220"  !CDS_PN = "220";
"VDD<7>":   PN = "217"  !CDS_PN = "217";
"VDD<8>":   PN = "215"  !CDS_PN = "215";
"VDD<9>":   PN = "212"  !CDS_PN = "212";
"VDD<10>":   PN = "209"  !CDS_PN = "209";
"VDD<11>":   PN = "206"  !CDS_PN = "206";
"VDD<12>":   PN = "204"  !CDS_PN = "204";
"VDD<13>":   PN = "92"  !CDS_PN = "92";
"VDD<14>":   PN = "90"  !CDS_PN = "90";
"VDD<15>":   PN = "88"  !CDS_PN = "88";
"VDD<16>":   PN = "85"  !CDS_PN = "85";
"VDD<17>":   PN = "83"  !CDS_PN = "83";
"VDD<18>":   PN = "80"  !CDS_PN = "80";
"VDD<19>":   PN = "76"  !CDS_PN = "76";
"VDD<20>":   PN = "73"  !CDS_PN = "73";
"VDD<21>":   PN = "70"  !CDS_PN = "70";
"VDD<22>":   PN = "67"  !CDS_PN = "67";
"VDD<23>":   PN = "64"  !CDS_PN = "64";
"VDD<24>":   PN = "61"  !CDS_PN = "61";
"VDD<25>":   PN = "59"  !CDS_PN = "59";
"VPP<0>":   PN = "287"  !CDS_PN = "287";
"VPP<1>":   PN = "286"  !CDS_PN = "286";
"VPP<2>":   PN = "288"  !CDS_PN = "288";
"VPP<3>":   PN = "143"  !CDS_PN = "143";
"VPP<4>":   PN = "142"  !CDS_PN = "142";
"VTT<0>":   PN = "221"  !CDS_PN = "221";
"VTT<1>":   PN = "77"  !CDS_PN = "77";
BODY = "SCONN288_H44441003","I158": #LOCATION = "J6M1" !CDS_LOCATION = "J6M1" #SEC = "1" !CDS_SEC = "1";
"A0":   PN = "79"  !CDS_PN = "79";
"A1":   PN = "72"  !CDS_PN = "72";
"A2":   PN = "216"  !CDS_PN = "216";
"A3":   PN = "71"  !CDS_PN = "71";
"A4":   PN = "214"  !CDS_PN = "214";
"A5":   PN = "213"  !CDS_PN = "213";
"A6":   PN = "69"  !CDS_PN = "69";
"A7":   PN = "211"  !CDS_PN = "211";
"A8":   PN = "68"  !CDS_PN = "68";
"A9":   PN = "66"  !CDS_PN = "66";
"A10":   PN = "225"  !CDS_PN = "225";
"A11":   PN = "210"  !CDS_PN = "210";
"A12":   PN = "65"  !CDS_PN = "65";
"A13":   PN = "232"  !CDS_PN = "232";
"A14_WE_N":   PN = "228"  !CDS_PN = "228";
"A15_CAS_N":   PN = "86"  !CDS_PN = "86";
"A16_RAS_N":   PN = "82"  !CDS_PN = "82";
"A17":   PN = "234"  !CDS_PN = "234";
"ACT_N":   PN = "62"  !CDS_PN = "62";
"ALERT_N":   PN = "208"  !CDS_PN = "208";
"BA<0>":   PN = "81"  !CDS_PN = "81";
"BA<1>":   PN = "224"  !CDS_PN = "224";
"BG<0>":   PN = "63"  !CDS_PN = "63";
"BG<1>":   PN = "207"  !CDS_PN = "207";
"C<2>":   PN = "235"  !CDS_PN = "235";
"CB<0>":   PN = "49"  !CDS_PN = "49";
"CB<1>":   PN = "194"  !CDS_PN = "194";
"CB<2>":   PN = "56"  !CDS_PN = "56";
"CB<3>":   PN = "201"  !CDS_PN = "201";
"CB<4>":   PN = "47"  !CDS_PN = "47";
"CB<5>":   PN = "192"  !CDS_PN = "192";
"CB<6>":   PN = "54"  !CDS_PN = "54";
"CB<7>":   PN = "199"  !CDS_PN = "199";
"CK0N":   PN = "75"  !CDS_PN = "75";
"CK0P":   PN = "74"  !CDS_PN = "74";
"CK1N":   PN = "219"  !CDS_PN = "219";
"CK1P":   PN = "218"  !CDS_PN = "218";
"CKE<0>":   PN = "60"  !CDS_PN = "60";
"CKE<1>":   PN = "203"  !CDS_PN = "203";
"DQ<0>":   PN = "5"  !CDS_PN = "5";
"DQ<1>":   PN = "150"  !CDS_PN = "150";
"DQ<2>":   PN = "12"  !CDS_PN = "12";
"DQ<3>":   PN = "157"  !CDS_PN = "157";
"DQ<4>":   PN = "3"  !CDS_PN = "3";
"DQ<5>":   PN = "148"  !CDS_PN = "148";
"DQ<6>":   PN = "10"  !CDS_PN = "10";
"DQ<7>":   PN = "155"  !CDS_PN = "155";
"DQ<8>":   PN = "16"  !CDS_PN = "16";
"DQ<9>":   PN = "161"  !CDS_PN = "161";
"DQ<10>":   PN = "23"  !CDS_PN = "23";
"DQ<11>":   PN = "168"  !CDS_PN = "168";
"DQ<12>":   PN = "14"  !CDS_PN = "14";
"DQ<13>":   PN = "159"  !CDS_PN = "159";
"DQ<14>":   PN = "21"  !CDS_PN = "21";
"DQ<15>":   PN = "166"  !CDS_PN = "166";
"DQ<16>":   PN = "27"  !CDS_PN = "27";
"DQ<17>":   PN = "172"  !CDS_PN = "172";
"DQ<18>":   PN = "34"  !CDS_PN = "34";
"DQ<19>":   PN = "179"  !CDS_PN = "179";
"DQ<20>":   PN = "25"  !CDS_PN = "25";
"DQ<21>":   PN = "170"  !CDS_PN = "170";
"DQ<22>":   PN = "32"  !CDS_PN = "32";
"DQ<23>":   PN = "177"  !CDS_PN = "177";
"DQ<24>":   PN = "38"  !CDS_PN = "38";
"DQ<25>":   PN = "183"  !CDS_PN = "183";
"DQ<26>":   PN = "45"  !CDS_PN = "45";
"DQ<27>":   PN = "190"  !CDS_PN = "190";
"DQ<28>":   PN = "36"  !CDS_PN = "36";
"DQ<29>":   PN = "181"  !CDS_PN = "181";
"DQ<30>":   PN = "43"  !CDS_PN = "43";
"DQ<31>":   PN = "188"  !CDS_PN = "188";
"DQ<32>":   PN = "97"  !CDS_PN = "97";
"DQ<33>":   PN = "242"  !CDS_PN = "242";
"DQ<34>":   PN = "104"  !CDS_PN = "104";
"DQ<35>":   PN = "249"  !CDS_PN = "249";
"DQ<36>":   PN = "95"  !CDS_PN = "95";
"DQ<37>":   PN = "240"  !CDS_PN = "240";
"DQ<38>":   PN = "102"  !CDS_PN = "102";
"DQ<39>":   PN = "247"  !CDS_PN = "247";
"DQ<40>":   PN = "108"  !CDS_PN = "108";
"DQ<41>":   PN = "253"  !CDS_PN = "253";
"DQ<42>":   PN = "115"  !CDS_PN = "115";
"DQ<43>":   PN = "260"  !CDS_PN = "260";
"DQ<44>":   PN = "106"  !CDS_PN = "106";
"DQ<45>":   PN = "251"  !CDS_PN = "251";
"DQ<46>":   PN = "113"  !CDS_PN = "113";
"DQ<47>":   PN = "258"  !CDS_PN = "258";
"DQ<48>":   PN = "119"  !CDS_PN = "119";
"DQ<49>":   PN = "264"  !CDS_PN = "264";
"DQ<50>":   PN = "126"  !CDS_PN = "126";
"DQ<51>":   PN = "271"  !CDS_PN = "271";
"DQ<52>":   PN = "117"  !CDS_PN = "117";
"DQ<53>":   PN = "262"  !CDS_PN = "262";
"DQ<54>":   PN = "124"  !CDS_PN = "124";
"DQ<55>":   PN = "269"  !CDS_PN = "269";
"DQ<56>":   PN = "130"  !CDS_PN = "130";
"DQ<57>":   PN = "275"  !CDS_PN = "275";
"DQ<58>":   PN = "137"  !CDS_PN = "137";
"DQ<59>":   PN = "282"  !CDS_PN = "282";
"DQ<60>":   PN = "128"  !CDS_PN = "128";
"DQ<61>":   PN = "273"  !CDS_PN = "273";
"DQ<62>":   PN = "135"  !CDS_PN = "135";
"DQ<63>":   PN = "280"  !CDS_PN = "280";
"EVENT_N":   PN = "78"  !CDS_PN = "78";
"ODT<0>":   PN = "87"  !CDS_PN = "87";
"ODT<1>":   PN = "91"  !CDS_PN = "91";
"PAR":   PN = "222"  !CDS_PN = "222";
"RESET_N":   PN = "58"  !CDS_PN = "58";
"RFU<0>":   PN = "205"  !CDS_PN = "205";
"RFU<1>":   PN = "227"  !CDS_PN = "227";
"RFU<2>":   PN = "144"  !CDS_PN = "144";
"S0_N":   PN = "84"  !CDS_PN = "84";
"S1_N":   PN = "89"  !CDS_PN = "89";
"S2_N_C<0>":   PN = "93"  !CDS_PN = "93";
"S3_N_C<1>":   PN = "237"  !CDS_PN = "237";
"SA<0>":   PN = "139"  !CDS_PN = "139";
"SA<1>":   PN = "140"  !CDS_PN = "140";
"SA<2>":   PN = "238"  !CDS_PN = "238";
"SAVE_N_NC":   PN = "230"  !CDS_PN = "230";
"SCL":   PN = "141"  !CDS_PN = "141";
"SDA":   PN = "285"  !CDS_PN = "285";
"VDDSPD":   PN = "284"  !CDS_PN = "284";
"VREFCA":   PN = "146"  !CDS_PN = "146";
BODY = "CAP_A","I177": #LOCATION = "C6M1" !CDS_LOCATION = "C6M1" #SEC = "1" !CDS_SEC = "1";
"A":   PN = "1"  !CDS_PN = "1";
"B":   PN = "2"  !CDS_PN = "2";
DRAWING = "@baseboard_fab2_lib.baseboard_fab2(sch_1):page51";
BODY = "SCONN288_H44441004","I43": #LOCATION = "J4A2" !CDS_LOCATION = "J4A2" #SEC = "3" !CDS_SEC = "3";
"VSS<0>":   PN = "283"  !CDS_PN = "283";
"VSS<1>":   PN = "281"  !CDS_PN = "281";
"VSS<2>":   PN = "279"  !CDS_PN = "279";
"VSS<3>":   PN = "276"  !CDS_PN = "276";
"VSS<4>":   PN = "274"  !CDS_PN = "274";
"VSS<5>":   PN = "272"  !CDS_PN = "272";
"VSS<6>":   PN = "270"  !CDS_PN = "270";
"VSS<7>":   PN = "268"  !CDS_PN = "268";
"VSS<8>":   PN = "265"  !CDS_PN = "265";
"VSS<9>":   PN = "263"  !CDS_PN = "263";
"VSS<10>":   PN = "261"  !CDS_PN = "261";
"VSS<11>":   PN = "259"  !CDS_PN = "259";
"VSS<12>":   PN = "257"  !CDS_PN = "257";
"VSS<13>":   PN = "254"  !CDS_PN = "254";
"VSS<14>":   PN = "252"  !CDS_PN = "252";
"VSS<15>":   PN = "250"  !CDS_PN = "250";
"VSS<16>":   PN = "248"  !CDS_PN = "248";
"VSS<17>":   PN = "246"  !CDS_PN = "246";
"VSS<18>":   PN = "243"  !CDS_PN = "243";
"VSS<19>":   PN = "241"  !CDS_PN = "241";
"VSS<20>":   PN = "239"  !CDS_PN = "239";
"VSS<21>":   PN = "202"  !CDS_PN = "202";
"VSS<22>":   PN = "200"  !CDS_PN = "200";
"VSS<23>":   PN = "198"  !CDS_PN = "198";
"VSS<24>":   PN = "195"  !CDS_PN = "195";
"VSS<25>":   PN = "193"  !CDS_PN = "193";
"VSS<26>":   PN = "191"  !CDS_PN = "191";
"VSS<27>":   PN = "189"  !CDS_PN = "189";
"VSS<28>":   PN = "187"  !CDS_PN = "187";
"VSS<29>":   PN = "184"  !CDS_PN = "184";
"VSS<30>":   PN = "182"  !CDS_PN = "182";
"VSS<31>":   PN = "180"  !CDS_PN = "180";
"VSS<32>":   PN = "178"  !CDS_PN = "178";
"VSS<33>":   PN = "176"  !CDS_PN = "176";
"VSS<34>":   PN = "173"  !CDS_PN = "173";
"VSS<35>":   PN = "171"  !CDS_PN = "171";
"VSS<36>":   PN = "169"  !CDS_PN = "169";
"VSS<37>":   PN = "167"  !CDS_PN = "167";
"VSS<38>":   PN = "165"  !CDS_PN = "165";
"VSS<39>":   PN = "162"  !CDS_PN = "162";
"VSS<40>":   PN = "160"  !CDS_PN = "160";
"VSS<41>":   PN = "158"  !CDS_PN = "158";
"VSS<42>":   PN = "156"  !CDS_PN = "156";
"VSS<43>":   PN = "154"  !CDS_PN = "154";
"VSS<44>":   PN = "151"  !CDS_PN = "151";
"VSS<45>":   PN = "149"  !CDS_PN = "149";
"VSS<46>":   PN = "147"  !CDS_PN = "147";
"VSS<47>":   PN = "138"  !CDS_PN = "138";
"VSS<48>":   PN = "136"  !CDS_PN = "136";
"VSS<49>":   PN = "134"  !CDS_PN = "134";
"VSS<50>":   PN = "131"  !CDS_PN = "131";
"VSS<51>":   PN = "129"  !CDS_PN = "129";
"VSS<52>":   PN = "127"  !CDS_PN = "127";
"VSS<53>":   PN = "125"  !CDS_PN = "125";
"VSS<54>":   PN = "123"  !CDS_PN = "123";
"VSS<55>":   PN = "120"  !CDS_PN = "120";
"VSS<56>":   PN = "118"  !CDS_PN = "118";
"VSS<57>":   PN = "116"  !CDS_PN = "116";
"VSS<58>":   PN = "114"  !CDS_PN = "114";
"VSS<59>":   PN = "112"  !CDS_PN = "112";
"VSS<60>":   PN = "109"  !CDS_PN = "109";
"VSS<61>":   PN = "107"  !CDS_PN = "107";
"VSS<62>":   PN = "105"  !CDS_PN = "105";
"VSS<63>":   PN = "103"  !CDS_PN = "103";
"VSS<64>":   PN = "101"  !CDS_PN = "101";
"VSS<65>":   PN = "98"  !CDS_PN = "98";
"VSS<66>":   PN = "96"  !CDS_PN = "96";
"VSS<67>":   PN = "94"  !CDS_PN = "94";
"VSS<68>":   PN = "57"  !CDS_PN = "57";
"VSS<69>":   PN = "55"  !CDS_PN = "55";
"VSS<70>":   PN = "53"  !CDS_PN = "53";
"VSS<71>":   PN = "50"  !CDS_PN = "50";
"VSS<72>":   PN = "48"  !CDS_PN = "48";
"VSS<73>":   PN = "46"  !CDS_PN = "46";
"VSS<74>":   PN = "44"  !CDS_PN = "44";
"VSS<75>":   PN = "42"  !CDS_PN = "42";
"VSS<76>":   PN = "39"  !CDS_PN = "39";
"VSS<77>":   PN = "37"  !CDS_PN = "37";
"VSS<78>":   PN = "35"  !CDS_PN = "35";
"VSS<79>":   PN = "33"  !CDS_PN = "33";
"VSS<80>":   PN = "31"  !CDS_PN = "31";
"VSS<81>":   PN = "28"  !CDS_PN = "28";
"VSS<82>":   PN = "26"  !CDS_PN = "26";
"VSS<83>":   PN = "24"  !CDS_PN = "24";
"VSS<84>":   PN = "22"  !CDS_PN = "22";
"VSS<85>":   PN = "20"  !CDS_PN = "20";
"VSS<86>":   PN = "17"  !CDS_PN = "17";
"VSS<87>":   PN = "15"  !CDS_PN = "15";
"VSS<88>":   PN = "13"  !CDS_PN = "13";
"VSS<89>":   PN = "11"  !CDS_PN = "11";
"VSS<90>":   PN = "9"  !CDS_PN = "9";
"VSS<91>":   PN = "6"  !CDS_PN = "6";
"VSS<92>":   PN = "4"  !CDS_PN = "4";
"VSS<93>":   PN = "2"  !CDS_PN = "2";
BODY = "SCONN288_H44441004","I66": #LOCATION = "J4A2" !CDS_LOCATION = "J4A2" #SEC = "2" !CDS_SEC = "2";
"DQS0N":   PN = "152"  !CDS_PN = "152";
"DQS0P":   PN = "153"  !CDS_PN = "153";
"DQS1N":   PN = "163"  !CDS_PN = "163";
"DQS1P":   PN = "164"  !CDS_PN = "164";
"DQS2N":   PN = "174"  !CDS_PN = "174";
"DQS2P":   PN = "175"  !CDS_PN = "175";
"DQS3N":   PN = "185"  !CDS_PN = "185";
"DQS3P":   PN = "186"  !CDS_PN = "186";
"DQS4N":   PN = "244"  !CDS_PN = "244";
"DQS4P":   PN = "245"  !CDS_PN = "245";
"DQS5N":   PN = "255"  !CDS_PN = "255";
"DQS5P":   PN = "256"  !CDS_PN = "256";
"DQS6N":   PN = "266"  !CDS_PN = "266";
"DQS6P":   PN = "267"  !CDS_PN = "267";
"DQS7N":   PN = "277"  !CDS_PN = "277";
"DQS7P":   PN = "278"  !CDS_PN = "278";
"DQS8N":   PN = "196"  !CDS_PN = "196";
"DQS8P":   PN = "197"  !CDS_PN = "197";
"DQS9N":   PN = "8"  !CDS_PN = "8";
"DQS9P":   PN = "7"  !CDS_PN = "7";
"DQS10N":   PN = "19"  !CDS_PN = "19";
"DQS10P":   PN = "18"  !CDS_PN = "18";
"DQS11N":   PN = "30"  !CDS_PN = "30";
"DQS11P":   PN = "29"  !CDS_PN = "29";
"DQS12N":   PN = "41"  !CDS_PN = "41";
"DQS12P":   PN = "40"  !CDS_PN = "40";
"DQS13N":   PN = "100"  !CDS_PN = "100";
"DQS13P":   PN = "99"  !CDS_PN = "99";
"DQS14N":   PN = "111"  !CDS_PN = "111";
"DQS14P":   PN = "110"  !CDS_PN = "110";
"DQS15N":   PN = "122"  !CDS_PN = "122";
"DQS15P":   PN = "121"  !CDS_PN = "121";
"DQS16N":   PN = "133"  !CDS_PN = "133";
"DQS16P":   PN = "132"  !CDS_PN = "132";
"DQS17N":   PN = "52"  !CDS_PN = "52";
"DQS17P":   PN = "51"  !CDS_PN = "51";
BODY = "SCONN288_H44441004","I111": #LOCATION = "J4A2" !CDS_LOCATION = "J4A2" #SEC = "1" !CDS_SEC = "1";
"A0":   PN = "79"  !CDS_PN = "79";
"A1":   PN = "72"  !CDS_PN = "72";
"A2":   PN = "216"  !CDS_PN = "216";
"A3":   PN = "71"  !CDS_PN = "71";
"A4":   PN = "214"  !CDS_PN = "214";
"A5":   PN = "213"  !CDS_PN = "213";
"A6":   PN = "69"  !CDS_PN = "69";
"A7":   PN = "211"  !CDS_PN = "211";
"A8":   PN = "68"  !CDS_PN = "68";
"A9":   PN = "66"  !CDS_PN = "66";
"A10":   PN = "225"  !CDS_PN = "225";
"A11":   PN = "210"  !CDS_PN = "210";
"A12":   PN = "65"  !CDS_PN = "65";
"A13":   PN = "232"  !CDS_PN = "232";
"A14_WE_N":   PN = "228"  !CDS_PN = "228";
"A15_CAS_N":   PN = "86"  !CDS_PN = "86";
"A16_RAS_N":   PN = "82"  !CDS_PN = "82";
"A17":   PN = "234"  !CDS_PN = "234";
"ACT_N":   PN = "62"  !CDS_PN = "62";
"ALERT_N":   PN = "208"  !CDS_PN = "208";
"BA<0>":   PN = "81"  !CDS_PN = "81";
"BA<1>":   PN = "224"  !CDS_PN = "224";
"BG<0>":   PN = "63"  !CDS_PN = "63";
"BG<1>":   PN = "207"  !CDS_PN = "207";
"C<2>":   PN = "235"  !CDS_PN = "235";
"CB<0>":   PN = "49"  !CDS_PN = "49";
"CB<1>":   PN = "194"  !CDS_PN = "194";
"CB<2>":   PN = "56"  !CDS_PN = "56";
"CB<3>":   PN = "201"  !CDS_PN = "201";
"CB<4>":   PN = "47"  !CDS_PN = "47";
"CB<5>":   PN = "192"  !CDS_PN = "192";
"CB<6>":   PN = "54"  !CDS_PN = "54";
"CB<7>":   PN = "199"  !CDS_PN = "199";
"CK0N":   PN = "75"  !CDS_PN = "75";
"CK0P":   PN = "74"  !CDS_PN = "74";
"CK1N":   PN = "219"  !CDS_PN = "219";
"CK1P":   PN = "218"  !CDS_PN = "218";
"CKE<0>":   PN = "60"  !CDS_PN = "60";
"CKE<1>":   PN = "203"  !CDS_PN = "203";
"DQ<0>":   PN = "5"  !CDS_PN = "5";
"DQ<1>":   PN = "150"  !CDS_PN = "150";
"DQ<2>":   PN = "12"  !CDS_PN = "12";
"DQ<3>":   PN = "157"  !CDS_PN = "157";
"DQ<4>":   PN = "3"  !CDS_PN = "3";
"DQ<5>":   PN = "148"  !CDS_PN = "148";
"DQ<6>":   PN = "10"  !CDS_PN = "10";
"DQ<7>":   PN = "155"  !CDS_PN = "155";
"DQ<8>":   PN = "16"  !CDS_PN = "16";
"DQ<9>":   PN = "161"  !CDS_PN = "161";
"DQ<10>":   PN = "23"  !CDS_PN = "23";
"DQ<11>":   PN = "168"  !CDS_PN = "168";
"DQ<12>":   PN = "14"  !CDS_PN = "14";
"DQ<13>":   PN = "159"  !CDS_PN = "159";
"DQ<14>":   PN = "21"  !CDS_PN = "21";
"DQ<15>":   PN = "166"  !CDS_PN = "166";
"DQ<16>":   PN = "27"  !CDS_PN = "27";
"DQ<17>":   PN = "172"  !CDS_PN = "172";
"DQ<18>":   PN = "34"  !CDS_PN = "34";
"DQ<19>":   PN = "179"  !CDS_PN = "179";
"DQ<20>":   PN = "25"  !CDS_PN = "25";
"DQ<21>":   PN = "170"  !CDS_PN = "170";
"DQ<22>":   PN = "32"  !CDS_PN = "32";
"DQ<23>":   PN = "177"  !CDS_PN = "177";
"DQ<24>":   PN = "38"  !CDS_PN = "38";
"DQ<25>":   PN = "183"  !CDS_PN = "183";
"DQ<26>":   PN = "45"  !CDS_PN = "45";
"DQ<27>":   PN = "190"  !CDS_PN = "190";
"DQ<28>":   PN = "36"  !CDS_PN = "36";
"DQ<29>":   PN = "181"  !CDS_PN = "181";
"DQ<30>":   PN = "43"  !CDS_PN = "43";
"DQ<31>":   PN = "188"  !CDS_PN = "188";
"DQ<32>":   PN = "97"  !CDS_PN = "97";
"DQ<33>":   PN = "242"  !CDS_PN = "242";
"DQ<34>":   PN = "104"  !CDS_PN = "104";
"DQ<35>":   PN = "249"  !CDS_PN = "249";
"DQ<36>":   PN = "95"  !CDS_PN = "95";
"DQ<37>":   PN = "240"  !CDS_PN = "240";
"DQ<38>":   PN = "102"  !CDS_PN = "102";
"DQ<39>":   PN = "247"  !CDS_PN = "247";
"DQ<40>":   PN = "108"  !CDS_PN = "108";
"DQ<41>":   PN = "253"  !CDS_PN = "253";
"DQ<42>":   PN = "115"  !CDS_PN = "115";
"DQ<43>":   PN = "260"  !CDS_PN = "260";
"DQ<44>":   PN = "106"  !CDS_PN = "106";
"DQ<45>":   PN = "251"  !CDS_PN = "251";
"DQ<46>":   PN = "113"  !CDS_PN = "113";
"DQ<47>":   PN = "258"  !CDS_PN = "258";
"DQ<48>":   PN = "119"  !CDS_PN = "119";
"DQ<49>":   PN = "264"  !CDS_PN = "264";
"DQ<50>":   PN = "126"  !CDS_PN = "126";
"DQ<51>":   PN = "271"  !CDS_PN = "271";
"DQ<52>":   PN = "117"  !CDS_PN = "117";
"DQ<53>":   PN = "262"  !CDS_PN = "262";
"DQ<54>":   PN = "124"  !CDS_PN = "124";
"DQ<55>":   PN = "269"  !CDS_PN = "269";
"DQ<56>":   PN = "130"  !CDS_PN = "130";
"DQ<57>":   PN = "275"  !CDS_PN = "275";
"DQ<58>":   PN = "137"  !CDS_PN = "137";
"DQ<59>":   PN = "282"  !CDS_PN = "282";
"DQ<60>":   PN = "128"  !CDS_PN = "128";
"DQ<61>":   PN = "273"  !CDS_PN = "273";
"DQ<62>":   PN = "135"  !CDS_PN = "135";
"DQ<63>":   PN = "280"  !CDS_PN = "280";
"EVENT_N":   PN = "78"  !CDS_PN = "78";
"ODT<0>":   PN = "87"  !CDS_PN = "87";
"ODT<1>":   PN = "91"  !CDS_PN = "91";
"PAR":   PN = "222"  !CDS_PN = "222";
"RESET_N":   PN = "58"  !CDS_PN = "58";
"RFU<0>":   PN = "205"  !CDS_PN = "205";
"RFU<1>":   PN = "227"  !CDS_PN = "227";
"RFU<2>":   PN = "144"  !CDS_PN = "144";
"S0_N":   PN = "84"  !CDS_PN = "84";
"S1_N":   PN = "89"  !CDS_PN = "89";
"S2_N_C<0>":   PN = "93"  !CDS_PN = "93";
"S3_N_C<1>":   PN = "237"  !CDS_PN = "237";
"SA<0>":   PN = "139"  !CDS_PN = "139";
"SA<1>":   PN = "140"  !CDS_PN = "140";
"SA<2>":   PN = "238"  !CDS_PN = "238";
"SAVE_N_NC":   PN = "230"  !CDS_PN = "230";
"SCL":   PN = "141"  !CDS_PN = "141";
"SDA":   PN = "285"  !CDS_PN = "285";
"VDDSPD":   PN = "284"  !CDS_PN = "284";
"VREFCA":   PN = "146"  !CDS_PN = "146";
BODY = "SCONN288_H44441004","I167": #LOCATION = "J4A2" !CDS_LOCATION = "J4A2" #SEC = "4" !CDS_SEC = "4";
"12V<0>":   PN = "145"  !CDS_PN = "145";
"12V<1>":   PN = "1"  !CDS_PN = "1";
"VDD<0>":   PN = "236"  !CDS_PN = "236";
"VDD<1>":   PN = "233"  !CDS_PN = "233";
"VDD<2>":   PN = "231"  !CDS_PN = "231";
"VDD<3>":   PN = "229"  !CDS_PN = "229";
"VDD<4>":   PN = "226"  !CDS_PN = "226";
"VDD<5>":   PN = "223"  !CDS_PN = "223";
"VDD<6>":   PN = "220"  !CDS_PN = "220";
"VDD<7>":   PN = "217"  !CDS_PN = "217";
"VDD<8>":   PN = "215"  !CDS_PN = "215";
"VDD<9>":   PN = "212"  !CDS_PN = "212";
"VDD<10>":   PN = "209"  !CDS_PN = "209";
"VDD<11>":   PN = "206"  !CDS_PN = "206";
"VDD<12>":   PN = "204"  !CDS_PN = "204";
"VDD<13>":   PN = "92"  !CDS_PN = "92";
"VDD<14>":   PN = "90"  !CDS_PN = "90";
"VDD<15>":   PN = "88"  !CDS_PN = "88";
"VDD<16>":   PN = "85"  !CDS_PN = "85";
"VDD<17>":   PN = "83"  !CDS_PN = "83";
"VDD<18>":   PN = "80"  !CDS_PN = "80";
"VDD<19>":   PN = "76"  !CDS_PN = "76";
"VDD<20>":   PN = "73"  !CDS_PN = "73";
"VDD<21>":   PN = "70"  !CDS_PN = "70";
"VDD<22>":   PN = "67"  !CDS_PN = "67";
"VDD<23>":   PN = "64"  !CDS_PN = "64";
"VDD<24>":   PN = "61"  !CDS_PN = "61";
"VDD<25>":   PN = "59"  !CDS_PN = "59";
"VPP<0>":   PN = "287"  !CDS_PN = "287";
"VPP<1>":   PN = "286"  !CDS_PN = "286";
"VPP<2>":   PN = "288"  !CDS_PN = "288";
"VPP<3>":   PN = "143"  !CDS_PN = "143";
"VPP<4>":   PN = "142"  !CDS_PN = "142";
"VTT<0>":   PN = "221"  !CDS_PN = "221";
"VTT<1>":   PN = "77"  !CDS_PN = "77";
BODY = "CAP_A","I175": #LOCATION = "C6L6" !CDS_LOCATION = "C6L6" #SEC = "1" !CDS_SEC = "1";
"A":   PN = "1"  !CDS_PN = "1";
"B":   PN = "2"  !CDS_PN = "2";
DRAWING = "@baseboard_fab2_lib.baseboard_fab2(sch_1):page52";
BODY = "CAP_A","I3": #LOCATION = "C4A18" !CDS_LOCATION = "C4A18" #SEC = "1" !CDS_SEC = "1";
"A":   PN = "1"  !CDS_PN = "1";
"B":   PN = "2"  !CDS_PN = "2";
BODY = "SCONN288_H44441003","I12": #LOCATION = "J6L2" !CDS_LOCATION = "J6L2" #SEC = "1" !CDS_SEC = "1";
"A0":   PN = "79"  !CDS_PN = "79";
"A1":   PN = "72"  !CDS_PN = "72";
"A2":   PN = "216"  !CDS_PN = "216";
"A3":   PN = "71"  !CDS_PN = "71";
"A4":   PN = "214"  !CDS_PN = "214";
"A5":   PN = "213"  !CDS_PN = "213";
"A6":   PN = "69"  !CDS_PN = "69";
"A7":   PN = "211"  !CDS_PN = "211";
"A8":   PN = "68"  !CDS_PN = "68";
"A9":   PN = "66"  !CDS_PN = "66";
"A10":   PN = "225"  !CDS_PN = "225";
"A11":   PN = "210"  !CDS_PN = "210";
"A12":   PN = "65"  !CDS_PN = "65";
"A13":   PN = "232"  !CDS_PN = "232";
"A14_WE_N":   PN = "228"  !CDS_PN = "228";
"A15_CAS_N":   PN = "86"  !CDS_PN = "86";
"A16_RAS_N":   PN = "82"  !CDS_PN = "82";
"A17":   PN = "234"  !CDS_PN = "234";
"ACT_N":   PN = "62"  !CDS_PN = "62";
"ALERT_N":   PN = "208"  !CDS_PN = "208";
"BA<0>":   PN = "81"  !CDS_PN = "81";
"BA<1>":   PN = "224"  !CDS_PN = "224";
"BG<0>":   PN = "63"  !CDS_PN = "63";
"BG<1>":   PN = "207"  !CDS_PN = "207";
"C<2>":   PN = "235"  !CDS_PN = "235";
"CB<0>":   PN = "49"  !CDS_PN = "49";
"CB<1>":   PN = "194"  !CDS_PN = "194";
"CB<2>":   PN = "56"  !CDS_PN = "56";
"CB<3>":   PN = "201"  !CDS_PN = "201";
"CB<4>":   PN = "47"  !CDS_PN = "47";
"CB<5>":   PN = "192"  !CDS_PN = "192";
"CB<6>":   PN = "54"  !CDS_PN = "54";
"CB<7>":   PN = "199"  !CDS_PN = "199";
"CK0N":   PN = "75"  !CDS_PN = "75";
"CK0P":   PN = "74"  !CDS_PN = "74";
"CK1N":   PN = "219"  !CDS_PN = "219";
"CK1P":   PN = "218"  !CDS_PN = "218";
"CKE<0>":   PN = "60"  !CDS_PN = "60";
"CKE<1>":   PN = "203"  !CDS_PN = "203";
"DQ<0>":   PN = "5"  !CDS_PN = "5";
"DQ<1>":   PN = "150"  !CDS_PN = "150";
"DQ<2>":   PN = "12"  !CDS_PN = "12";
"DQ<3>":   PN = "157"  !CDS_PN = "157";
"DQ<4>":   PN = "3"  !CDS_PN = "3";
"DQ<5>":   PN = "148"  !CDS_PN = "148";
"DQ<6>":   PN = "10"  !CDS_PN = "10";
"DQ<7>":   PN = "155"  !CDS_PN = "155";
"DQ<8>":   PN = "16"  !CDS_PN = "16";
"DQ<9>":   PN = "161"  !CDS_PN = "161";
"DQ<10>":   PN = "23"  !CDS_PN = "23";
"DQ<11>":   PN = "168"  !CDS_PN = "168";
"DQ<12>":   PN = "14"  !CDS_PN = "14";
"DQ<13>":   PN = "159"  !CDS_PN = "159";
"DQ<14>":   PN = "21"  !CDS_PN = "21";
"DQ<15>":   PN = "166"  !CDS_PN = "166";
"DQ<16>":   PN = "27"  !CDS_PN = "27";
"DQ<17>":   PN = "172"  !CDS_PN = "172";
"DQ<18>":   PN = "34"  !CDS_PN = "34";
"DQ<19>":   PN = "179"  !CDS_PN = "179";
"DQ<20>":   PN = "25"  !CDS_PN = "25";
"DQ<21>":   PN = "170"  !CDS_PN = "170";
"DQ<22>":   PN = "32"  !CDS_PN = "32";
"DQ<23>":   PN = "177"  !CDS_PN = "177";
"DQ<24>":   PN = "38"  !CDS_PN = "38";
"DQ<25>":   PN = "183"  !CDS_PN = "183";
"DQ<26>":   PN = "45"  !CDS_PN = "45";
"DQ<27>":   PN = "190"  !CDS_PN = "190";
"DQ<28>":   PN = "36"  !CDS_PN = "36";
"DQ<29>":   PN = "181"  !CDS_PN = "181";
"DQ<30>":   PN = "43"  !CDS_PN = "43";
"DQ<31>":   PN = "188"  !CDS_PN = "188";
"DQ<32>":   PN = "97"  !CDS_PN = "97";
"DQ<33>":   PN = "242"  !CDS_PN = "242";
"DQ<34>":   PN = "104"  !CDS_PN = "104";
"DQ<35>":   PN = "249"  !CDS_PN = "249";
"DQ<36>":   PN = "95"  !CDS_PN = "95";
"DQ<37>":   PN = "240"  !CDS_PN = "240";
"DQ<38>":   PN = "102"  !CDS_PN = "102";
"DQ<39>":   PN = "247"  !CDS_PN = "247";
"DQ<40>":   PN = "108"  !CDS_PN = "108";
"DQ<41>":   PN = "253"  !CDS_PN = "253";
"DQ<42>":   PN = "115"  !CDS_PN = "115";
"DQ<43>":   PN = "260"  !CDS_PN = "260";
"DQ<44>":   PN = "106"  !CDS_PN = "106";
"DQ<45>":   PN = "251"  !CDS_PN = "251";
"DQ<46>":   PN = "113"  !CDS_PN = "113";
"DQ<47>":   PN = "258"  !CDS_PN = "258";
"DQ<48>":   PN = "119"  !CDS_PN = "119";
"DQ<49>":   PN = "264"  !CDS_PN = "264";
"DQ<50>":   PN = "126"  !CDS_PN = "126";
"DQ<51>":   PN = "271"  !CDS_PN = "271";
"DQ<52>":   PN = "117"  !CDS_PN = "117";
"DQ<53>":   PN = "262"  !CDS_PN = "262";
"DQ<54>":   PN = "124"  !CDS_PN = "124";
"DQ<55>":   PN = "269"  !CDS_PN = "269";
"DQ<56>":   PN = "130"  !CDS_PN = "130";
"DQ<57>":   PN = "275"  !CDS_PN = "275";
"DQ<58>":   PN = "137"  !CDS_PN = "137";
"DQ<59>":   PN = "282"  !CDS_PN = "282";
"DQ<60>":   PN = "128"  !CDS_PN = "128";
"DQ<61>":   PN = "273"  !CDS_PN = "273";
"DQ<62>":   PN = "135"  !CDS_PN = "135";
"DQ<63>":   PN = "280"  !CDS_PN = "280";
"EVENT_N":   PN = "78"  !CDS_PN = "78";
"ODT<0>":   PN = "87"  !CDS_PN = "87";
"ODT<1>":   PN = "91"  !CDS_PN = "91";
"PAR":   PN = "222"  !CDS_PN = "222";
"RESET_N":   PN = "58"  !CDS_PN = "58";
"RFU<0>":   PN = "205"  !CDS_PN = "205";
"RFU<1>":   PN = "227"  !CDS_PN = "227";
"RFU<2>":   PN = "144"  !CDS_PN = "144";
"S0_N":   PN = "84"  !CDS_PN = "84";
"S1_N":   PN = "89"  !CDS_PN = "89";
"S2_N_C<0>":   PN = "93"  !CDS_PN = "93";
"S3_N_C<1>":   PN = "237"  !CDS_PN = "237";
"SA<0>":   PN = "139"  !CDS_PN = "139";
"SA<1>":   PN = "140"  !CDS_PN = "140";
"SA<2>":   PN = "238"  !CDS_PN = "238";
"SAVE_N_NC":   PN = "230"  !CDS_PN = "230";
"SCL":   PN = "141"  !CDS_PN = "141";
"SDA":   PN = "285"  !CDS_PN = "285";
"VDDSPD":   PN = "284"  !CDS_PN = "284";
"VREFCA":   PN = "146"  !CDS_PN = "146";
BODY = "SCONN288_H44441003","I55": #LOCATION = "J6L2" !CDS_LOCATION = "J6L2" #SEC = "4" !CDS_SEC = "4";
"12V<0>":   PN = "145"  !CDS_PN = "145";
"12V<1>":   PN = "1"  !CDS_PN = "1";
"VDD<0>":   PN = "236"  !CDS_PN = "236";
"VDD<1>":   PN = "233"  !CDS_PN = "233";
"VDD<2>":   PN = "231"  !CDS_PN = "231";
"VDD<3>":   PN = "229"  !CDS_PN = "229";
"VDD<4>":   PN = "226"  !CDS_PN = "226";
"VDD<5>":   PN = "223"  !CDS_PN = "223";
"VDD<6>":   PN = "220"  !CDS_PN = "220";
"VDD<7>":   PN = "217"  !CDS_PN = "217";
"VDD<8>":   PN = "215"  !CDS_PN = "215";
"VDD<9>":   PN = "212"  !CDS_PN = "212";
"VDD<10>":   PN = "209"  !CDS_PN = "209";
"VDD<11>":   PN = "206"  !CDS_PN = "206";
"VDD<12>":   PN = "204"  !CDS_PN = "204";
"VDD<13>":   PN = "92"  !CDS_PN = "92";
"VDD<14>":   PN = "90"  !CDS_PN = "90";
"VDD<15>":   PN = "88"  !CDS_PN = "88";
"VDD<16>":   PN = "85"  !CDS_PN = "85";
"VDD<17>":   PN = "83"  !CDS_PN = "83";
"VDD<18>":   PN = "80"  !CDS_PN = "80";
"VDD<19>":   PN = "76"  !CDS_PN = "76";
"VDD<20>":   PN = "73"  !CDS_PN = "73";
"VDD<21>":   PN = "70"  !CDS_PN = "70";
"VDD<22>":   PN = "67"  !CDS_PN = "67";
"VDD<23>":   PN = "64"  !CDS_PN = "64";
"VDD<24>":   PN = "61"  !CDS_PN = "61";
"VDD<25>":   PN = "59"  !CDS_PN = "59";
"VPP<0>":   PN = "287"  !CDS_PN = "287";
"VPP<1>":   PN = "286"  !CDS_PN = "286";
"VPP<2>":   PN = "288"  !CDS_PN = "288";
"VPP<3>":   PN = "143"  !CDS_PN = "143";
"VPP<4>":   PN = "142"  !CDS_PN = "142";
"VTT<0>":   PN = "221"  !CDS_PN = "221";
"VTT<1>":   PN = "77"  !CDS_PN = "77";
BODY = "SCONN288_H44441003","I100": #LOCATION = "J6L2" !CDS_LOCATION = "J6L2" #SEC = "2" !CDS_SEC = "2";
"DQS0N":   PN = "152"  !CDS_PN = "152";
"DQS0P":   PN = "153"  !CDS_PN = "153";
"DQS1N":   PN = "163"  !CDS_PN = "163";
"DQS1P":   PN = "164"  !CDS_PN = "164";
"DQS2N":   PN = "174"  !CDS_PN = "174";
"DQS2P":   PN = "175"  !CDS_PN = "175";
"DQS3N":   PN = "185"  !CDS_PN = "185";
"DQS3P":   PN = "186"  !CDS_PN = "186";
"DQS4N":   PN = "244"  !CDS_PN = "244";
"DQS4P":   PN = "245"  !CDS_PN = "245";
"DQS5N":   PN = "255"  !CDS_PN = "255";
"DQS5P":   PN = "256"  !CDS_PN = "256";
"DQS6N":   PN = "266"  !CDS_PN = "266";
"DQS6P":   PN = "267"  !CDS_PN = "267";
"DQS7N":   PN = "277"  !CDS_PN = "277";
"DQS7P":   PN = "278"  !CDS_PN = "278";
"DQS8N":   PN = "196"  !CDS_PN = "196";
"DQS8P":   PN = "197"  !CDS_PN = "197";
"DQS9N":   PN = "8"  !CDS_PN = "8";
"DQS9P":   PN = "7"  !CDS_PN = "7";
"DQS10N":   PN = "19"  !CDS_PN = "19";
"DQS10P":   PN = "18"  !CDS_PN = "18";
"DQS11N":   PN = "30"  !CDS_PN = "30";
"DQS11P":   PN = "29"  !CDS_PN = "29";
"DQS12N":   PN = "41"  !CDS_PN = "41";
"DQS12P":   PN = "40"  !CDS_PN = "40";
"DQS13N":   PN = "100"  !CDS_PN = "100";
"DQS13P":   PN = "99"  !CDS_PN = "99";
"DQS14N":   PN = "111"  !CDS_PN = "111";
"DQS14P":   PN = "110"  !CDS_PN = "110";
"DQS15N":   PN = "122"  !CDS_PN = "122";
"DQS15P":   PN = "121"  !CDS_PN = "121";
"DQS16N":   PN = "133"  !CDS_PN = "133";
"DQS16P":   PN = "132"  !CDS_PN = "132";
"DQS17N":   PN = "52"  !CDS_PN = "52";
"DQS17P":   PN = "51"  !CDS_PN = "51";
BODY = "SCONN288_H44441003","I138": #LOCATION = "J6L2" !CDS_LOCATION = "J6L2" #SEC = "3" !CDS_SEC = "3";
"VSS<0>":   PN = "283"  !CDS_PN = "283";
"VSS<1>":   PN = "281"  !CDS_PN = "281";
"VSS<2>":   PN = "279"  !CDS_PN = "279";
"VSS<3>":   PN = "276"  !CDS_PN = "276";
"VSS<4>":   PN = "274"  !CDS_PN = "274";
"VSS<5>":   PN = "272"  !CDS_PN = "272";
"VSS<6>":   PN = "270"  !CDS_PN = "270";
"VSS<7>":   PN = "268"  !CDS_PN = "268";
"VSS<8>":   PN = "265"  !CDS_PN = "265";
"VSS<9>":   PN = "263"  !CDS_PN = "263";
"VSS<10>":   PN = "261"  !CDS_PN = "261";
"VSS<11>":   PN = "259"  !CDS_PN = "259";
"VSS<12>":   PN = "257"  !CDS_PN = "257";
"VSS<13>":   PN = "254"  !CDS_PN = "254";
"VSS<14>":   PN = "252"  !CDS_PN = "252";
"VSS<15>":   PN = "250"  !CDS_PN = "250";
"VSS<16>":   PN = "248"  !CDS_PN = "248";
"VSS<17>":   PN = "246"  !CDS_PN = "246";
"VSS<18>":   PN = "243"  !CDS_PN = "243";
"VSS<19>":   PN = "241"  !CDS_PN = "241";
"VSS<20>":   PN = "239"  !CDS_PN = "239";
"VSS<21>":   PN = "202"  !CDS_PN = "202";
"VSS<22>":   PN = "200"  !CDS_PN = "200";
"VSS<23>":   PN = "198"  !CDS_PN = "198";
"VSS<24>":   PN = "195"  !CDS_PN = "195";
"VSS<25>":   PN = "193"  !CDS_PN = "193";
"VSS<26>":   PN = "191"  !CDS_PN = "191";
"VSS<27>":   PN = "189"  !CDS_PN = "189";
"VSS<28>":   PN = "187"  !CDS_PN = "187";
"VSS<29>":   PN = "184"  !CDS_PN = "184";
"VSS<30>":   PN = "182"  !CDS_PN = "182";
"VSS<31>":   PN = "180"  !CDS_PN = "180";
"VSS<32>":   PN = "178"  !CDS_PN = "178";
"VSS<33>":   PN = "176"  !CDS_PN = "176";
"VSS<34>":   PN = "173"  !CDS_PN = "173";
"VSS<35>":   PN = "171"  !CDS_PN = "171";
"VSS<36>":   PN = "169"  !CDS_PN = "169";
"VSS<37>":   PN = "167"  !CDS_PN = "167";
"VSS<38>":   PN = "165"  !CDS_PN = "165";
"VSS<39>":   PN = "162"  !CDS_PN = "162";
"VSS<40>":   PN = "160"  !CDS_PN = "160";
"VSS<41>":   PN = "158"  !CDS_PN = "158";
"VSS<42>":   PN = "156"  !CDS_PN = "156";
"VSS<43>":   PN = "154"  !CDS_PN = "154";
"VSS<44>":   PN = "151"  !CDS_PN = "151";
"VSS<45>":   PN = "149"  !CDS_PN = "149";
"VSS<46>":   PN = "147"  !CDS_PN = "147";
"VSS<47>":   PN = "138"  !CDS_PN = "138";
"VSS<48>":   PN = "136"  !CDS_PN = "136";
"VSS<49>":   PN = "134"  !CDS_PN = "134";
"VSS<50>":   PN = "131"  !CDS_PN = "131";
"VSS<51>":   PN = "129"  !CDS_PN = "129";
"VSS<52>":   PN = "127"  !CDS_PN = "127";
"VSS<53>":   PN = "125"  !CDS_PN = "125";
"VSS<54>":   PN = "123"  !CDS_PN = "123";
"VSS<55>":   PN = "120"  !CDS_PN = "120";
"VSS<56>":   PN = "118"  !CDS_PN = "118";
"VSS<57>":   PN = "116"  !CDS_PN = "116";
"VSS<58>":   PN = "114"  !CDS_PN = "114";
"VSS<59>":   PN = "112"  !CDS_PN = "112";
"VSS<60>":   PN = "109"  !CDS_PN = "109";
"VSS<61>":   PN = "107"  !CDS_PN = "107";
"VSS<62>":   PN = "105"  !CDS_PN = "105";
"VSS<63>":   PN = "103"  !CDS_PN = "103";
"VSS<64>":   PN = "101"  !CDS_PN = "101";
"VSS<65>":   PN = "98"  !CDS_PN = "98";
"VSS<66>":   PN = "96"  !CDS_PN = "96";
"VSS<67>":   PN = "94"  !CDS_PN = "94";
"VSS<68>":   PN = "57"  !CDS_PN = "57";
"VSS<69>":   PN = "55"  !CDS_PN = "55";
"VSS<70>":   PN = "53"  !CDS_PN = "53";
"VSS<71>":   PN = "50"  !CDS_PN = "50";
"VSS<72>":   PN = "48"  !CDS_PN = "48";
"VSS<73>":   PN = "46"  !CDS_PN = "46";
"VSS<74>":   PN = "44"  !CDS_PN = "44";
"VSS<75>":   PN = "42"  !CDS_PN = "42";
"VSS<76>":   PN = "39"  !CDS_PN = "39";
"VSS<77>":   PN = "37"  !CDS_PN = "37";
"VSS<78>":   PN = "35"  !CDS_PN = "35";
"VSS<79>":   PN = "33"  !CDS_PN = "33";
"VSS<80>":   PN = "31"  !CDS_PN = "31";
"VSS<81>":   PN = "28"  !CDS_PN = "28";
"VSS<82>":   PN = "26"  !CDS_PN = "26";
"VSS<83>":   PN = "24"  !CDS_PN = "24";
"VSS<84>":   PN = "22"  !CDS_PN = "22";
"VSS<85>":   PN = "20"  !CDS_PN = "20";
"VSS<86>":   PN = "17"  !CDS_PN = "17";
"VSS<87>":   PN = "15"  !CDS_PN = "15";
"VSS<88>":   PN = "13"  !CDS_PN = "13";
"VSS<89>":   PN = "11"  !CDS_PN = "11";
"VSS<90>":   PN = "9"  !CDS_PN = "9";
"VSS<91>":   PN = "6"  !CDS_PN = "6";
"VSS<92>":   PN = "4"  !CDS_PN = "4";
"VSS<93>":   PN = "2"  !CDS_PN = "2";
DRAWING = "@baseboard_fab2_lib.baseboard_fab2(sch_1):page53";
BODY = "SCONN288_H44441004","I43": #LOCATION = "J4A1" !CDS_LOCATION = "J4A1" #SEC = "3" !CDS_SEC = "3";
"VSS<0>":   PN = "283"  !CDS_PN = "283";
"VSS<1>":   PN = "281"  !CDS_PN = "281";
"VSS<2>":   PN = "279"  !CDS_PN = "279";
"VSS<3>":   PN = "276"  !CDS_PN = "276";
"VSS<4>":   PN = "274"  !CDS_PN = "274";
"VSS<5>":   PN = "272"  !CDS_PN = "272";
"VSS<6>":   PN = "270"  !CDS_PN = "270";
"VSS<7>":   PN = "268"  !CDS_PN = "268";
"VSS<8>":   PN = "265"  !CDS_PN = "265";
"VSS<9>":   PN = "263"  !CDS_PN = "263";
"VSS<10>":   PN = "261"  !CDS_PN = "261";
"VSS<11>":   PN = "259"  !CDS_PN = "259";
"VSS<12>":   PN = "257"  !CDS_PN = "257";
"VSS<13>":   PN = "254"  !CDS_PN = "254";
"VSS<14>":   PN = "252"  !CDS_PN = "252";
"VSS<15>":   PN = "250"  !CDS_PN = "250";
"VSS<16>":   PN = "248"  !CDS_PN = "248";
"VSS<17>":   PN = "246"  !CDS_PN = "246";
"VSS<18>":   PN = "243"  !CDS_PN = "243";
"VSS<19>":   PN = "241"  !CDS_PN = "241";
"VSS<20>":   PN = "239"  !CDS_PN = "239";
"VSS<21>":   PN = "202"  !CDS_PN = "202";
"VSS<22>":   PN = "200"  !CDS_PN = "200";
"VSS<23>":   PN = "198"  !CDS_PN = "198";
"VSS<24>":   PN = "195"  !CDS_PN = "195";
"VSS<25>":   PN = "193"  !CDS_PN = "193";
"VSS<26>":   PN = "191"  !CDS_PN = "191";
"VSS<27>":   PN = "189"  !CDS_PN = "189";
"VSS<28>":   PN = "187"  !CDS_PN = "187";
"VSS<29>":   PN = "184"  !CDS_PN = "184";
"VSS<30>":   PN = "182"  !CDS_PN = "182";
"VSS<31>":   PN = "180"  !CDS_PN = "180";
"VSS<32>":   PN = "178"  !CDS_PN = "178";
"VSS<33>":   PN = "176"  !CDS_PN = "176";
"VSS<34>":   PN = "173"  !CDS_PN = "173";
"VSS<35>":   PN = "171"  !CDS_PN = "171";
"VSS<36>":   PN = "169"  !CDS_PN = "169";
"VSS<37>":   PN = "167"  !CDS_PN = "167";
"VSS<38>":   PN = "165"  !CDS_PN = "165";
"VSS<39>":   PN = "162"  !CDS_PN = "162";
"VSS<40>":   PN = "160"  !CDS_PN = "160";
"VSS<41>":   PN = "158"  !CDS_PN = "158";
"VSS<42>":   PN = "156"  !CDS_PN = "156";
"VSS<43>":   PN = "154"  !CDS_PN = "154";
"VSS<44>":   PN = "151"  !CDS_PN = "151";
"VSS<45>":   PN = "149"  !CDS_PN = "149";
"VSS<46>":   PN = "147"  !CDS_PN = "147";
"VSS<47>":   PN = "138"  !CDS_PN = "138";
"VSS<48>":   PN = "136"  !CDS_PN = "136";
"VSS<49>":   PN = "134"  !CDS_PN = "134";
"VSS<50>":   PN = "131"  !CDS_PN = "131";
"VSS<51>":   PN = "129"  !CDS_PN = "129";
"VSS<52>":   PN = "127"  !CDS_PN = "127";
"VSS<53>":   PN = "125"  !CDS_PN = "125";
"VSS<54>":   PN = "123"  !CDS_PN = "123";
"VSS<55>":   PN = "120"  !CDS_PN = "120";
"VSS<56>":   PN = "118"  !CDS_PN = "118";
"VSS<57>":   PN = "116"  !CDS_PN = "116";
"VSS<58>":   PN = "114"  !CDS_PN = "114";
"VSS<59>":   PN = "112"  !CDS_PN = "112";
"VSS<60>":   PN = "109"  !CDS_PN = "109";
"VSS<61>":   PN = "107"  !CDS_PN = "107";
"VSS<62>":   PN = "105"  !CDS_PN = "105";
"VSS<63>":   PN = "103"  !CDS_PN = "103";
"VSS<64>":   PN = "101"  !CDS_PN = "101";
"VSS<65>":   PN = "98"  !CDS_PN = "98";
"VSS<66>":   PN = "96"  !CDS_PN = "96";
"VSS<67>":   PN = "94"  !CDS_PN = "94";
"VSS<68>":   PN = "57"  !CDS_PN = "57";
"VSS<69>":   PN = "55"  !CDS_PN = "55";
"VSS<70>":   PN = "53"  !CDS_PN = "53";
"VSS<71>":   PN = "50"  !CDS_PN = "50";
"VSS<72>":   PN = "48"  !CDS_PN = "48";
"VSS<73>":   PN = "46"  !CDS_PN = "46";
"VSS<74>":   PN = "44"  !CDS_PN = "44";
"VSS<75>":   PN = "42"  !CDS_PN = "42";
"VSS<76>":   PN = "39"  !CDS_PN = "39";
"VSS<77>":   PN = "37"  !CDS_PN = "37";
"VSS<78>":   PN = "35"  !CDS_PN = "35";
"VSS<79>":   PN = "33"  !CDS_PN = "33";
"VSS<80>":   PN = "31"  !CDS_PN = "31";
"VSS<81>":   PN = "28"  !CDS_PN = "28";
"VSS<82>":   PN = "26"  !CDS_PN = "26";
"VSS<83>":   PN = "24"  !CDS_PN = "24";
"VSS<84>":   PN = "22"  !CDS_PN = "22";
"VSS<85>":   PN = "20"  !CDS_PN = "20";
"VSS<86>":   PN = "17"  !CDS_PN = "17";
"VSS<87>":   PN = "15"  !CDS_PN = "15";
"VSS<88>":   PN = "13"  !CDS_PN = "13";
"VSS<89>":   PN = "11"  !CDS_PN = "11";
"VSS<90>":   PN = "9"  !CDS_PN = "9";
"VSS<91>":   PN = "6"  !CDS_PN = "6";
"VSS<92>":   PN = "4"  !CDS_PN = "4";
"VSS<93>":   PN = "2"  !CDS_PN = "2";
BODY = "SCONN288_H44441004","I66": #LOCATION = "J4A1" !CDS_LOCATION = "J4A1" #SEC = "2" !CDS_SEC = "2";
"DQS0N":   PN = "152"  !CDS_PN = "152";
"DQS0P":   PN = "153"  !CDS_PN = "153";
"DQS1N":   PN = "163"  !CDS_PN = "163";
"DQS1P":   PN = "164"  !CDS_PN = "164";
"DQS2N":   PN = "174"  !CDS_PN = "174";
"DQS2P":   PN = "175"  !CDS_PN = "175";
"DQS3N":   PN = "185"  !CDS_PN = "185";
"DQS3P":   PN = "186"  !CDS_PN = "186";
"DQS4N":   PN = "244"  !CDS_PN = "244";
"DQS4P":   PN = "245"  !CDS_PN = "245";
"DQS5N":   PN = "255"  !CDS_PN = "255";
"DQS5P":   PN = "256"  !CDS_PN = "256";
"DQS6N":   PN = "266"  !CDS_PN = "266";
"DQS6P":   PN = "267"  !CDS_PN = "267";
"DQS7N":   PN = "277"  !CDS_PN = "277";
"DQS7P":   PN = "278"  !CDS_PN = "278";
"DQS8N":   PN = "196"  !CDS_PN = "196";
"DQS8P":   PN = "197"  !CDS_PN = "197";
"DQS9N":   PN = "8"  !CDS_PN = "8";
"DQS9P":   PN = "7"  !CDS_PN = "7";
"DQS10N":   PN = "19"  !CDS_PN = "19";
"DQS10P":   PN = "18"  !CDS_PN = "18";
"DQS11N":   PN = "30"  !CDS_PN = "30";
"DQS11P":   PN = "29"  !CDS_PN = "29";
"DQS12N":   PN = "41"  !CDS_PN = "41";
"DQS12P":   PN = "40"  !CDS_PN = "40";
"DQS13N":   PN = "100"  !CDS_PN = "100";
"DQS13P":   PN = "99"  !CDS_PN = "99";
"DQS14N":   PN = "111"  !CDS_PN = "111";
"DQS14P":   PN = "110"  !CDS_PN = "110";
"DQS15N":   PN = "122"  !CDS_PN = "122";
"DQS15P":   PN = "121"  !CDS_PN = "121";
"DQS16N":   PN = "133"  !CDS_PN = "133";
"DQS16P":   PN = "132"  !CDS_PN = "132";
"DQS17N":   PN = "52"  !CDS_PN = "52";
"DQS17P":   PN = "51"  !CDS_PN = "51";
BODY = "SCONN288_H44441004","I111": #LOCATION = "J4A1" !CDS_LOCATION = "J4A1" #SEC = "1" !CDS_SEC = "1";
"A0":   PN = "79"  !CDS_PN = "79";
"A1":   PN = "72"  !CDS_PN = "72";
"A2":   PN = "216"  !CDS_PN = "216";
"A3":   PN = "71"  !CDS_PN = "71";
"A4":   PN = "214"  !CDS_PN = "214";
"A5":   PN = "213"  !CDS_PN = "213";
"A6":   PN = "69"  !CDS_PN = "69";
"A7":   PN = "211"  !CDS_PN = "211";
"A8":   PN = "68"  !CDS_PN = "68";
"A9":   PN = "66"  !CDS_PN = "66";
"A10":   PN = "225"  !CDS_PN = "225";
"A11":   PN = "210"  !CDS_PN = "210";
"A12":   PN = "65"  !CDS_PN = "65";
"A13":   PN = "232"  !CDS_PN = "232";
"A14_WE_N":   PN = "228"  !CDS_PN = "228";
"A15_CAS_N":   PN = "86"  !CDS_PN = "86";
"A16_RAS_N":   PN = "82"  !CDS_PN = "82";
"A17":   PN = "234"  !CDS_PN = "234";
"ACT_N":   PN = "62"  !CDS_PN = "62";
"ALERT_N":   PN = "208"  !CDS_PN = "208";
"BA<0>":   PN = "81"  !CDS_PN = "81";
"BA<1>":   PN = "224"  !CDS_PN = "224";
"BG<0>":   PN = "63"  !CDS_PN = "63";
"BG<1>":   PN = "207"  !CDS_PN = "207";
"C<2>":   PN = "235"  !CDS_PN = "235";
"CB<0>":   PN = "49"  !CDS_PN = "49";
"CB<1>":   PN = "194"  !CDS_PN = "194";
"CB<2>":   PN = "56"  !CDS_PN = "56";
"CB<3>":   PN = "201"  !CDS_PN = "201";
"CB<4>":   PN = "47"  !CDS_PN = "47";
"CB<5>":   PN = "192"  !CDS_PN = "192";
"CB<6>":   PN = "54"  !CDS_PN = "54";
"CB<7>":   PN = "199"  !CDS_PN = "199";
"CK0N":   PN = "75"  !CDS_PN = "75";
"CK0P":   PN = "74"  !CDS_PN = "74";
"CK1N":   PN = "219"  !CDS_PN = "219";
"CK1P":   PN = "218"  !CDS_PN = "218";
"CKE<0>":   PN = "60"  !CDS_PN = "60";
"CKE<1>":   PN = "203"  !CDS_PN = "203";
"DQ<0>":   PN = "5"  !CDS_PN = "5";
"DQ<1>":   PN = "150"  !CDS_PN = "150";
"DQ<2>":   PN = "12"  !CDS_PN = "12";
"DQ<3>":   PN = "157"  !CDS_PN = "157";
"DQ<4>":   PN = "3"  !CDS_PN = "3";
"DQ<5>":   PN = "148"  !CDS_PN = "148";
"DQ<6>":   PN = "10"  !CDS_PN = "10";
"DQ<7>":   PN = "155"  !CDS_PN = "155";
"DQ<8>":   PN = "16"  !CDS_PN = "16";
"DQ<9>":   PN = "161"  !CDS_PN = "161";
"DQ<10>":   PN = "23"  !CDS_PN = "23";
"DQ<11>":   PN = "168"  !CDS_PN = "168";
"DQ<12>":   PN = "14"  !CDS_PN = "14";
"DQ<13>":   PN = "159"  !CDS_PN = "159";
"DQ<14>":   PN = "21"  !CDS_PN = "21";
"DQ<15>":   PN = "166"  !CDS_PN = "166";
"DQ<16>":   PN = "27"  !CDS_PN = "27";
"DQ<17>":   PN = "172"  !CDS_PN = "172";
"DQ<18>":   PN = "34"  !CDS_PN = "34";
"DQ<19>":   PN = "179"  !CDS_PN = "179";
"DQ<20>":   PN = "25"  !CDS_PN = "25";
"DQ<21>":   PN = "170"  !CDS_PN = "170";
"DQ<22>":   PN = "32"  !CDS_PN = "32";
"DQ<23>":   PN = "177"  !CDS_PN = "177";
"DQ<24>":   PN = "38"  !CDS_PN = "38";
"DQ<25>":   PN = "183"  !CDS_PN = "183";
"DQ<26>":   PN = "45"  !CDS_PN = "45";
"DQ<27>":   PN = "190"  !CDS_PN = "190";
"DQ<28>":   PN = "36"  !CDS_PN = "36";
"DQ<29>":   PN = "181"  !CDS_PN = "181";
"DQ<30>":   PN = "43"  !CDS_PN = "43";
"DQ<31>":   PN = "188"  !CDS_PN = "188";
"DQ<32>":   PN = "97"  !CDS_PN = "97";
"DQ<33>":   PN = "242"  !CDS_PN = "242";
"DQ<34>":   PN = "104"  !CDS_PN = "104";
"DQ<35>":   PN = "249"  !CDS_PN = "249";
"DQ<36>":   PN = "95"  !CDS_PN = "95";
"DQ<37>":   PN = "240"  !CDS_PN = "240";
"DQ<38>":   PN = "102"  !CDS_PN = "102";
"DQ<39>":   PN = "247"  !CDS_PN = "247";
"DQ<40>":   PN = "108"  !CDS_PN = "108";
"DQ<41>":   PN = "253"  !CDS_PN = "253";
"DQ<42>":   PN = "115"  !CDS_PN = "115";
"DQ<43>":   PN = "260"  !CDS_PN = "260";
"DQ<44>":   PN = "106"  !CDS_PN = "106";
"DQ<45>":   PN = "251"  !CDS_PN = "251";
"DQ<46>":   PN = "113"  !CDS_PN = "113";
"DQ<47>":   PN = "258"  !CDS_PN = "258";
"DQ<48>":   PN = "119"  !CDS_PN = "119";
"DQ<49>":   PN = "264"  !CDS_PN = "264";
"DQ<50>":   PN = "126"  !CDS_PN = "126";
"DQ<51>":   PN = "271"  !CDS_PN = "271";
"DQ<52>":   PN = "117"  !CDS_PN = "117";
"DQ<53>":   PN = "262"  !CDS_PN = "262";
"DQ<54>":   PN = "124"  !CDS_PN = "124";
"DQ<55>":   PN = "269"  !CDS_PN = "269";
"DQ<56>":   PN = "130"  !CDS_PN = "130";
"DQ<57>":   PN = "275"  !CDS_PN = "275";
"DQ<58>":   PN = "137"  !CDS_PN = "137";
"DQ<59>":   PN = "282"  !CDS_PN = "282";
"DQ<60>":   PN = "128"  !CDS_PN = "128";
"DQ<61>":   PN = "273"  !CDS_PN = "273";
"DQ<62>":   PN = "135"  !CDS_PN = "135";
"DQ<63>":   PN = "280"  !CDS_PN = "280";
"EVENT_N":   PN = "78"  !CDS_PN = "78";
"ODT<0>":   PN = "87"  !CDS_PN = "87";
"ODT<1>":   PN = "91"  !CDS_PN = "91";
"PAR":   PN = "222"  !CDS_PN = "222";
"RESET_N":   PN = "58"  !CDS_PN = "58";
"RFU<0>":   PN = "205"  !CDS_PN = "205";
"RFU<1>":   PN = "227"  !CDS_PN = "227";
"RFU<2>":   PN = "144"  !CDS_PN = "144";
"S0_N":   PN = "84"  !CDS_PN = "84";
"S1_N":   PN = "89"  !CDS_PN = "89";
"S2_N_C<0>":   PN = "93"  !CDS_PN = "93";
"S3_N_C<1>":   PN = "237"  !CDS_PN = "237";
"SA<0>":   PN = "139"  !CDS_PN = "139";
"SA<1>":   PN = "140"  !CDS_PN = "140";
"SA<2>":   PN = "238"  !CDS_PN = "238";
"SAVE_N_NC":   PN = "230"  !CDS_PN = "230";
"SCL":   PN = "141"  !CDS_PN = "141";
"SDA":   PN = "285"  !CDS_PN = "285";
"VDDSPD":   PN = "284"  !CDS_PN = "284";
"VREFCA":   PN = "146"  !CDS_PN = "146";
BODY = "SCONN288_H44441004","I171": #LOCATION = "J4A1" !CDS_LOCATION = "J4A1" #SEC = "4" !CDS_SEC = "4";
"12V<0>":   PN = "145"  !CDS_PN = "145";
"12V<1>":   PN = "1"  !CDS_PN = "1";
"VDD<0>":   PN = "236"  !CDS_PN = "236";
"VDD<1>":   PN = "233"  !CDS_PN = "233";
"VDD<2>":   PN = "231"  !CDS_PN = "231";
"VDD<3>":   PN = "229"  !CDS_PN = "229";
"VDD<4>":   PN = "226"  !CDS_PN = "226";
"VDD<5>":   PN = "223"  !CDS_PN = "223";
"VDD<6>":   PN = "220"  !CDS_PN = "220";
"VDD<7>":   PN = "217"  !CDS_PN = "217";
"VDD<8>":   PN = "215"  !CDS_PN = "215";
"VDD<9>":   PN = "212"  !CDS_PN = "212";
"VDD<10>":   PN = "209"  !CDS_PN = "209";
"VDD<11>":   PN = "206"  !CDS_PN = "206";
"VDD<12>":   PN = "204"  !CDS_PN = "204";
"VDD<13>":   PN = "92"  !CDS_PN = "92";
"VDD<14>":   PN = "90"  !CDS_PN = "90";
"VDD<15>":   PN = "88"  !CDS_PN = "88";
"VDD<16>":   PN = "85"  !CDS_PN = "85";
"VDD<17>":   PN = "83"  !CDS_PN = "83";
"VDD<18>":   PN = "80"  !CDS_PN = "80";
"VDD<19>":   PN = "76"  !CDS_PN = "76";
"VDD<20>":   PN = "73"  !CDS_PN = "73";
"VDD<21>":   PN = "70"  !CDS_PN = "70";
"VDD<22>":   PN = "67"  !CDS_PN = "67";
"VDD<23>":   PN = "64"  !CDS_PN = "64";
"VDD<24>":   PN = "61"  !CDS_PN = "61";
"VDD<25>":   PN = "59"  !CDS_PN = "59";
"VPP<0>":   PN = "287"  !CDS_PN = "287";
"VPP<1>":   PN = "286"  !CDS_PN = "286";
"VPP<2>":   PN = "288"  !CDS_PN = "288";
"VPP<3>":   PN = "143"  !CDS_PN = "143";
"VPP<4>":   PN = "142"  !CDS_PN = "142";
"VTT<0>":   PN = "221"  !CDS_PN = "221";
"VTT<1>":   PN = "77"  !CDS_PN = "77";
BODY = "CAP_A","I178": #LOCATION = "C6L1" !CDS_LOCATION = "C6L1" #SEC = "1" !CDS_SEC = "1";
"A":   PN = "1"  !CDS_PN = "1";
"B":   PN = "2"  !CDS_PN = "2";
DRAWING = "@baseboard_fab2_lib.baseboard_fab2(sch_1):page54";
BODY = "SCONN288_H44441003","I43": #LOCATION = "J6L1" !CDS_LOCATION = "J6L1" #SEC = "3" !CDS_SEC = "3";
"VSS<0>":   PN = "283"  !CDS_PN = "283";
"VSS<1>":   PN = "281"  !CDS_PN = "281";
"VSS<2>":   PN = "279"  !CDS_PN = "279";
"VSS<3>":   PN = "276"  !CDS_PN = "276";
"VSS<4>":   PN = "274"  !CDS_PN = "274";
"VSS<5>":   PN = "272"  !CDS_PN = "272";
"VSS<6>":   PN = "270"  !CDS_PN = "270";
"VSS<7>":   PN = "268"  !CDS_PN = "268";
"VSS<8>":   PN = "265"  !CDS_PN = "265";
"VSS<9>":   PN = "263"  !CDS_PN = "263";
"VSS<10>":   PN = "261"  !CDS_PN = "261";
"VSS<11>":   PN = "259"  !CDS_PN = "259";
"VSS<12>":   PN = "257"  !CDS_PN = "257";
"VSS<13>":   PN = "254"  !CDS_PN = "254";
"VSS<14>":   PN = "252"  !CDS_PN = "252";
"VSS<15>":   PN = "250"  !CDS_PN = "250";
"VSS<16>":   PN = "248"  !CDS_PN = "248";
"VSS<17>":   PN = "246"  !CDS_PN = "246";
"VSS<18>":   PN = "243"  !CDS_PN = "243";
"VSS<19>":   PN = "241"  !CDS_PN = "241";
"VSS<20>":   PN = "239"  !CDS_PN = "239";
"VSS<21>":   PN = "202"  !CDS_PN = "202";
"VSS<22>":   PN = "200"  !CDS_PN = "200";
"VSS<23>":   PN = "198"  !CDS_PN = "198";
"VSS<24>":   PN = "195"  !CDS_PN = "195";
"VSS<25>":   PN = "193"  !CDS_PN = "193";
"VSS<26>":   PN = "191"  !CDS_PN = "191";
"VSS<27>":   PN = "189"  !CDS_PN = "189";
"VSS<28>":   PN = "187"  !CDS_PN = "187";
"VSS<29>":   PN = "184"  !CDS_PN = "184";
"VSS<30>":   PN = "182"  !CDS_PN = "182";
"VSS<31>":   PN = "180"  !CDS_PN = "180";
"VSS<32>":   PN = "178"  !CDS_PN = "178";
"VSS<33>":   PN = "176"  !CDS_PN = "176";
"VSS<34>":   PN = "173"  !CDS_PN = "173";
"VSS<35>":   PN = "171"  !CDS_PN = "171";
"VSS<36>":   PN = "169"  !CDS_PN = "169";
"VSS<37>":   PN = "167"  !CDS_PN = "167";
"VSS<38>":   PN = "165"  !CDS_PN = "165";
"VSS<39>":   PN = "162"  !CDS_PN = "162";
"VSS<40>":   PN = "160"  !CDS_PN = "160";
"VSS<41>":   PN = "158"  !CDS_PN = "158";
"VSS<42>":   PN = "156"  !CDS_PN = "156";
"VSS<43>":   PN = "154"  !CDS_PN = "154";
"VSS<44>":   PN = "151"  !CDS_PN = "151";
"VSS<45>":   PN = "149"  !CDS_PN = "149";
"VSS<46>":   PN = "147"  !CDS_PN = "147";
"VSS<47>":   PN = "138"  !CDS_PN = "138";
"VSS<48>":   PN = "136"  !CDS_PN = "136";
"VSS<49>":   PN = "134"  !CDS_PN = "134";
"VSS<50>":   PN = "131"  !CDS_PN = "131";
"VSS<51>":   PN = "129"  !CDS_PN = "129";
"VSS<52>":   PN = "127"  !CDS_PN = "127";
"VSS<53>":   PN = "125"  !CDS_PN = "125";
"VSS<54>":   PN = "123"  !CDS_PN = "123";
"VSS<55>":   PN = "120"  !CDS_PN = "120";
"VSS<56>":   PN = "118"  !CDS_PN = "118";
"VSS<57>":   PN = "116"  !CDS_PN = "116";
"VSS<58>":   PN = "114"  !CDS_PN = "114";
"VSS<59>":   PN = "112"  !CDS_PN = "112";
"VSS<60>":   PN = "109"  !CDS_PN = "109";
"VSS<61>":   PN = "107"  !CDS_PN = "107";
"VSS<62>":   PN = "105"  !CDS_PN = "105";
"VSS<63>":   PN = "103"  !CDS_PN = "103";
"VSS<64>":   PN = "101"  !CDS_PN = "101";
"VSS<65>":   PN = "98"  !CDS_PN = "98";
"VSS<66>":   PN = "96"  !CDS_PN = "96";
"VSS<67>":   PN = "94"  !CDS_PN = "94";
"VSS<68>":   PN = "57"  !CDS_PN = "57";
"VSS<69>":   PN = "55"  !CDS_PN = "55";
"VSS<70>":   PN = "53"  !CDS_PN = "53";
"VSS<71>":   PN = "50"  !CDS_PN = "50";
"VSS<72>":   PN = "48"  !CDS_PN = "48";
"VSS<73>":   PN = "46"  !CDS_PN = "46";
"VSS<74>":   PN = "44"  !CDS_PN = "44";
"VSS<75>":   PN = "42"  !CDS_PN = "42";
"VSS<76>":   PN = "39"  !CDS_PN = "39";
"VSS<77>":   PN = "37"  !CDS_PN = "37";
"VSS<78>":   PN = "35"  !CDS_PN = "35";
"VSS<79>":   PN = "33"  !CDS_PN = "33";
"VSS<80>":   PN = "31"  !CDS_PN = "31";
"VSS<81>":   PN = "28"  !CDS_PN = "28";
"VSS<82>":   PN = "26"  !CDS_PN = "26";
"VSS<83>":   PN = "24"  !CDS_PN = "24";
"VSS<84>":   PN = "22"  !CDS_PN = "22";
"VSS<85>":   PN = "20"  !CDS_PN = "20";
"VSS<86>":   PN = "17"  !CDS_PN = "17";
"VSS<87>":   PN = "15"  !CDS_PN = "15";
"VSS<88>":   PN = "13"  !CDS_PN = "13";
"VSS<89>":   PN = "11"  !CDS_PN = "11";
"VSS<90>":   PN = "9"  !CDS_PN = "9";
"VSS<91>":   PN = "6"  !CDS_PN = "6";
"VSS<92>":   PN = "4"  !CDS_PN = "4";
"VSS<93>":   PN = "2"  !CDS_PN = "2";
BODY = "SCONN288_H44441003","I66": #LOCATION = "J6L1" !CDS_LOCATION = "J6L1" #SEC = "2" !CDS_SEC = "2";
"DQS0N":   PN = "152"  !CDS_PN = "152";
"DQS0P":   PN = "153"  !CDS_PN = "153";
"DQS1N":   PN = "163"  !CDS_PN = "163";
"DQS1P":   PN = "164"  !CDS_PN = "164";
"DQS2N":   PN = "174"  !CDS_PN = "174";
"DQS2P":   PN = "175"  !CDS_PN = "175";
"DQS3N":   PN = "185"  !CDS_PN = "185";
"DQS3P":   PN = "186"  !CDS_PN = "186";
"DQS4N":   PN = "244"  !CDS_PN = "244";
"DQS4P":   PN = "245"  !CDS_PN = "245";
"DQS5N":   PN = "255"  !CDS_PN = "255";
"DQS5P":   PN = "256"  !CDS_PN = "256";
"DQS6N":   PN = "266"  !CDS_PN = "266";
"DQS6P":   PN = "267"  !CDS_PN = "267";
"DQS7N":   PN = "277"  !CDS_PN = "277";
"DQS7P":   PN = "278"  !CDS_PN = "278";
"DQS8N":   PN = "196"  !CDS_PN = "196";
"DQS8P":   PN = "197"  !CDS_PN = "197";
"DQS9N":   PN = "8"  !CDS_PN = "8";
"DQS9P":   PN = "7"  !CDS_PN = "7";
"DQS10N":   PN = "19"  !CDS_PN = "19";
"DQS10P":   PN = "18"  !CDS_PN = "18";
"DQS11N":   PN = "30"  !CDS_PN = "30";
"DQS11P":   PN = "29"  !CDS_PN = "29";
"DQS12N":   PN = "41"  !CDS_PN = "41";
"DQS12P":   PN = "40"  !CDS_PN = "40";
"DQS13N":   PN = "100"  !CDS_PN = "100";
"DQS13P":   PN = "99"  !CDS_PN = "99";
"DQS14N":   PN = "111"  !CDS_PN = "111";
"DQS14P":   PN = "110"  !CDS_PN = "110";
"DQS15N":   PN = "122"  !CDS_PN = "122";
"DQS15P":   PN = "121"  !CDS_PN = "121";
"DQS16N":   PN = "133"  !CDS_PN = "133";
"DQS16P":   PN = "132"  !CDS_PN = "132";
"DQS17N":   PN = "52"  !CDS_PN = "52";
"DQS17P":   PN = "51"  !CDS_PN = "51";
BODY = "SCONN288_H44441003","I111": #LOCATION = "J6L1" !CDS_LOCATION = "J6L1" #SEC = "1" !CDS_SEC = "1";
"A0":   PN = "79"  !CDS_PN = "79";
"A1":   PN = "72"  !CDS_PN = "72";
"A2":   PN = "216"  !CDS_PN = "216";
"A3":   PN = "71"  !CDS_PN = "71";
"A4":   PN = "214"  !CDS_PN = "214";
"A5":   PN = "213"  !CDS_PN = "213";
"A6":   PN = "69"  !CDS_PN = "69";
"A7":   PN = "211"  !CDS_PN = "211";
"A8":   PN = "68"  !CDS_PN = "68";
"A9":   PN = "66"  !CDS_PN = "66";
"A10":   PN = "225"  !CDS_PN = "225";
"A11":   PN = "210"  !CDS_PN = "210";
"A12":   PN = "65"  !CDS_PN = "65";
"A13":   PN = "232"  !CDS_PN = "232";
"A14_WE_N":   PN = "228"  !CDS_PN = "228";
"A15_CAS_N":   PN = "86"  !CDS_PN = "86";
"A16_RAS_N":   PN = "82"  !CDS_PN = "82";
"A17":   PN = "234"  !CDS_PN = "234";
"ACT_N":   PN = "62"  !CDS_PN = "62";
"ALERT_N":   PN = "208"  !CDS_PN = "208";
"BA<0>":   PN = "81"  !CDS_PN = "81";
"BA<1>":   PN = "224"  !CDS_PN = "224";
"BG<0>":   PN = "63"  !CDS_PN = "63";
"BG<1>":   PN = "207"  !CDS_PN = "207";
"C<2>":   PN = "235"  !CDS_PN = "235";
"CB<0>":   PN = "49"  !CDS_PN = "49";
"CB<1>":   PN = "194"  !CDS_PN = "194";
"CB<2>":   PN = "56"  !CDS_PN = "56";
"CB<3>":   PN = "201"  !CDS_PN = "201";
"CB<4>":   PN = "47"  !CDS_PN = "47";
"CB<5>":   PN = "192"  !CDS_PN = "192";
"CB<6>":   PN = "54"  !CDS_PN = "54";
"CB<7>":   PN = "199"  !CDS_PN = "199";
"CK0N":   PN = "75"  !CDS_PN = "75";
"CK0P":   PN = "74"  !CDS_PN = "74";
"CK1N":   PN = "219"  !CDS_PN = "219";
"CK1P":   PN = "218"  !CDS_PN = "218";
"CKE<0>":   PN = "60"  !CDS_PN = "60";
"CKE<1>":   PN = "203"  !CDS_PN = "203";
"DQ<0>":   PN = "5"  !CDS_PN = "5";
"DQ<1>":   PN = "150"  !CDS_PN = "150";
"DQ<2>":   PN = "12"  !CDS_PN = "12";
"DQ<3>":   PN = "157"  !CDS_PN = "157";
"DQ<4>":   PN = "3"  !CDS_PN = "3";
"DQ<5>":   PN = "148"  !CDS_PN = "148";
"DQ<6>":   PN = "10"  !CDS_PN = "10";
"DQ<7>":   PN = "155"  !CDS_PN = "155";
"DQ<8>":   PN = "16"  !CDS_PN = "16";
"DQ<9>":   PN = "161"  !CDS_PN = "161";
"DQ<10>":   PN = "23"  !CDS_PN = "23";
"DQ<11>":   PN = "168"  !CDS_PN = "168";
"DQ<12>":   PN = "14"  !CDS_PN = "14";
"DQ<13>":   PN = "159"  !CDS_PN = "159";
"DQ<14>":   PN = "21"  !CDS_PN = "21";
"DQ<15>":   PN = "166"  !CDS_PN = "166";
"DQ<16>":   PN = "27"  !CDS_PN = "27";
"DQ<17>":   PN = "172"  !CDS_PN = "172";
"DQ<18>":   PN = "34"  !CDS_PN = "34";
"DQ<19>":   PN = "179"  !CDS_PN = "179";
"DQ<20>":   PN = "25"  !CDS_PN = "25";
"DQ<21>":   PN = "170"  !CDS_PN = "170";
"DQ<22>":   PN = "32"  !CDS_PN = "32";
"DQ<23>":   PN = "177"  !CDS_PN = "177";
"DQ<24>":   PN = "38"  !CDS_PN = "38";
"DQ<25>":   PN = "183"  !CDS_PN = "183";
"DQ<26>":   PN = "45"  !CDS_PN = "45";
"DQ<27>":   PN = "190"  !CDS_PN = "190";
"DQ<28>":   PN = "36"  !CDS_PN = "36";
"DQ<29>":   PN = "181"  !CDS_PN = "181";
"DQ<30>":   PN = "43"  !CDS_PN = "43";
"DQ<31>":   PN = "188"  !CDS_PN = "188";
"DQ<32>":   PN = "97"  !CDS_PN = "97";
"DQ<33>":   PN = "242"  !CDS_PN = "242";
"DQ<34>":   PN = "104"  !CDS_PN = "104";
"DQ<35>":   PN = "249"  !CDS_PN = "249";
"DQ<36>":   PN = "95"  !CDS_PN = "95";
"DQ<37>":   PN = "240"  !CDS_PN = "240";
"DQ<38>":   PN = "102"  !CDS_PN = "102";
"DQ<39>":   PN = "247"  !CDS_PN = "247";
"DQ<40>":   PN = "108"  !CDS_PN = "108";
"DQ<41>":   PN = "253"  !CDS_PN = "253";
"DQ<42>":   PN = "115"  !CDS_PN = "115";
"DQ<43>":   PN = "260"  !CDS_PN = "260";
"DQ<44>":   PN = "106"  !CDS_PN = "106";
"DQ<45>":   PN = "251"  !CDS_PN = "251";
"DQ<46>":   PN = "113"  !CDS_PN = "113";
"DQ<47>":   PN = "258"  !CDS_PN = "258";
"DQ<48>":   PN = "119"  !CDS_PN = "119";
"DQ<49>":   PN = "264"  !CDS_PN = "264";
"DQ<50>":   PN = "126"  !CDS_PN = "126";
"DQ<51>":   PN = "271"  !CDS_PN = "271";
"DQ<52>":   PN = "117"  !CDS_PN = "117";
"DQ<53>":   PN = "262"  !CDS_PN = "262";
"DQ<54>":   PN = "124"  !CDS_PN = "124";
"DQ<55>":   PN = "269"  !CDS_PN = "269";
"DQ<56>":   PN = "130"  !CDS_PN = "130";
"DQ<57>":   PN = "275"  !CDS_PN = "275";
"DQ<58>":   PN = "137"  !CDS_PN = "137";
"DQ<59>":   PN = "282"  !CDS_PN = "282";
"DQ<60>":   PN = "128"  !CDS_PN = "128";
"DQ<61>":   PN = "273"  !CDS_PN = "273";
"DQ<62>":   PN = "135"  !CDS_PN = "135";
"DQ<63>":   PN = "280"  !CDS_PN = "280";
"EVENT_N":   PN = "78"  !CDS_PN = "78";
"ODT<0>":   PN = "87"  !CDS_PN = "87";
"ODT<1>":   PN = "91"  !CDS_PN = "91";
"PAR":   PN = "222"  !CDS_PN = "222";
"RESET_N":   PN = "58"  !CDS_PN = "58";
"RFU<0>":   PN = "205"  !CDS_PN = "205";
"RFU<1>":   PN = "227"  !CDS_PN = "227";
"RFU<2>":   PN = "144"  !CDS_PN = "144";
"S0_N":   PN = "84"  !CDS_PN = "84";
"S1_N":   PN = "89"  !CDS_PN = "89";
"S2_N_C<0>":   PN = "93"  !CDS_PN = "93";
"S3_N_C<1>":   PN = "237"  !CDS_PN = "237";
"SA<0>":   PN = "139"  !CDS_PN = "139";
"SA<1>":   PN = "140"  !CDS_PN = "140";
"SA<2>":   PN = "238"  !CDS_PN = "238";
"SAVE_N_NC":   PN = "230"  !CDS_PN = "230";
"SCL":   PN = "141"  !CDS_PN = "141";
"SDA":   PN = "285"  !CDS_PN = "285";
"VDDSPD":   PN = "284"  !CDS_PN = "284";
"VREFCA":   PN = "146"  !CDS_PN = "146";
BODY = "SCONN288_H44441003","I170": #LOCATION = "J6L1" !CDS_LOCATION = "J6L1" #SEC = "4" !CDS_SEC = "4";
"12V<0>":   PN = "145"  !CDS_PN = "145";
"12V<1>":   PN = "1"  !CDS_PN = "1";
"VDD<0>":   PN = "236"  !CDS_PN = "236";
"VDD<1>":   PN = "233"  !CDS_PN = "233";
"VDD<2>":   PN = "231"  !CDS_PN = "231";
"VDD<3>":   PN = "229"  !CDS_PN = "229";
"VDD<4>":   PN = "226"  !CDS_PN = "226";
"VDD<5>":   PN = "223"  !CDS_PN = "223";
"VDD<6>":   PN = "220"  !CDS_PN = "220";
"VDD<7>":   PN = "217"  !CDS_PN = "217";
"VDD<8>":   PN = "215"  !CDS_PN = "215";
"VDD<9>":   PN = "212"  !CDS_PN = "212";
"VDD<10>":   PN = "209"  !CDS_PN = "209";
"VDD<11>":   PN = "206"  !CDS_PN = "206";
"VDD<12>":   PN = "204"  !CDS_PN = "204";
"VDD<13>":   PN = "92"  !CDS_PN = "92";
"VDD<14>":   PN = "90"  !CDS_PN = "90";
"VDD<15>":   PN = "88"  !CDS_PN = "88";
"VDD<16>":   PN = "85"  !CDS_PN = "85";
"VDD<17>":   PN = "83"  !CDS_PN = "83";
"VDD<18>":   PN = "80"  !CDS_PN = "80";
"VDD<19>":   PN = "76"  !CDS_PN = "76";
"VDD<20>":   PN = "73"  !CDS_PN = "73";
"VDD<21>":   PN = "70"  !CDS_PN = "70";
"VDD<22>":   PN = "67"  !CDS_PN = "67";
"VDD<23>":   PN = "64"  !CDS_PN = "64";
"VDD<24>":   PN = "61"  !CDS_PN = "61";
"VDD<25>":   PN = "59"  !CDS_PN = "59";
"VPP<0>":   PN = "287"  !CDS_PN = "287";
"VPP<1>":   PN = "286"  !CDS_PN = "286";
"VPP<2>":   PN = "288"  !CDS_PN = "288";
"VPP<3>":   PN = "143"  !CDS_PN = "143";
"VPP<4>":   PN = "142"  !CDS_PN = "142";
"VTT<0>":   PN = "221"  !CDS_PN = "221";
"VTT<1>":   PN = "77"  !CDS_PN = "77";
BODY = "CAP_A","I179": #LOCATION = "C4A5" !CDS_LOCATION = "C4A5" #SEC = "1" !CDS_SEC = "1";
"A":   PN = "1"  !CDS_PN = "1";
"B":   PN = "2"  !CDS_PN = "2";
DRAWING = "@baseboard_fab2_lib.baseboard_fab2(sch_1):page55";
BODY = "RES","I4": #LOCATION = "R9N1" !CDS_LOCATION = "R9N1" #SEC = "1" !CDS_SEC = "1";
"A":   PN = "1"  !CDS_PN = "1";
"B":   PN = "2"  !CDS_PN = "2";
BODY = "RES","I7": #LOCATION = "R9N2" !CDS_LOCATION = "R9N2" #SEC = "1" !CDS_SEC = "1";
"A":   PN = "1"  !CDS_PN = "1";
"B":   PN = "2"  !CDS_PN = "2";
BODY = "RES","I19": #LOCATION = "R3B2" !CDS_LOCATION = "R3B2" #SEC = "1" !CDS_SEC = "1";
"A":   PN = "1"  !CDS_PN = "1";
"B":   PN = "2"  !CDS_PN = "2";
BODY = "RES","I21": #LOCATION = "R3B4" !CDS_LOCATION = "R3B4" #SEC = "1" !CDS_SEC = "1";
"A":   PN = "1"  !CDS_PN = "1";
"B":   PN = "2"  !CDS_PN = "2";
BODY = "RES","I24": #LOCATION = "R1C2" !CDS_LOCATION = "R1C2" &SEC = "1" #&CDS_SEC = "1";
"A":   PN = "1"  !CDS_PN = "1";
"B":   PN = "2"  !CDS_PN = "2";
BODY = "RES","I25": #LOCATION = "R1C3" !CDS_LOCATION = "R1C3" &SEC = "1" #&CDS_SEC = "1";
"A":   PN = "1"  !CDS_PN = "1";
"B":   PN = "2"  !CDS_PN = "2";
BODY = "RES","I26": #LOCATION = "R1C1" !CDS_LOCATION = "R1C1" &SEC = "1" #&CDS_SEC = "1";
"A":   PN = "1"  !CDS_PN = "1";
"B":   PN = "2"  !CDS_PN = "2";
BODY = "RES","I27": #LOCATION = "R3B1" !CDS_LOCATION = "R3B1" &SEC = "1" #&CDS_SEC = "1";
"A":   PN = "1"  !CDS_PN = "1";
"B":   PN = "2"  !CDS_PN = "2";
BODY = "RES","I28": #LOCATION = "R3B5" !CDS_LOCATION = "R3B5" &SEC = "1" #&CDS_SEC = "1";
"A":   PN = "1"  !CDS_PN = "1";
"B":   PN = "2"  !CDS_PN = "2";
BODY = "RES","I29": #LOCATION = "R3B3" !CDS_LOCATION = "R3B3" &SEC = "1" #&CDS_SEC = "1";
"A":   PN = "1"  !CDS_PN = "1";
"B":   PN = "2"  !CDS_PN = "2";
BODY = "RES","I115": #LOCATION = "R7P19" !CDS_LOCATION = "R7P19" #SEC = "1" !CDS_SEC = "1";
"A":   PN = "1"  !CDS_PN = "1";
"B":   PN = "2"  !CDS_PN = "2";
BODY = "RES","I116": #LOCATION = "R3D1" !CDS_LOCATION = "R3D1" #SEC = "1" !CDS_SEC = "1";
"A":   PN = "1"  !CDS_PN = "1";
"B":   PN = "2"  !CDS_PN = "2";
BODY = "RES","I117": #LOCATION = "R3D2" !CDS_LOCATION = "R3D2" #SEC = "1" !CDS_SEC = "1";
"A":   PN = "1"  !CDS_PN = "1";
"B":   PN = "2"  !CDS_PN = "2";
BODY = "RES","I118": #LOCATION = "R3D3" !CDS_LOCATION = "R3D3" #SEC = "1" !CDS_SEC = "1";
"A":   PN = "1"  !CDS_PN = "1";
"B":   PN = "2"  !CDS_PN = "2";
BODY = "RES","I119": #LOCATION = "R7P16" !CDS_LOCATION = "R7P16" #SEC = "1" !CDS_SEC = "1";
"A":   PN = "1"  !CDS_PN = "1";
"B":   PN = "2"  !CDS_PN = "2";
BODY = "RES","I123": #LOCATION = "R7P8" !CDS_LOCATION = "R7P8" #SEC = "1" !CDS_SEC = "1";
"A":   PN = "1"  !CDS_PN = "1";
"B":   PN = "2"  !CDS_PN = "2";
BODY = "RES","I124": #LOCATION = "R7P10" !CDS_LOCATION = "R7P10" #SEC = "1" !CDS_SEC = "1";
"A":   PN = "1"  !CDS_PN = "1";
"B":   PN = "2"  !CDS_PN = "2";
BODY = "RES","I125": #LOCATION = "R3D19" !CDS_LOCATION = "R3D19" #SEC = "1" !CDS_SEC = "1";
"A":   PN = "1"  !CDS_PN = "1";
"B":   PN = "2"  !CDS_PN = "2";
BODY = "RES","I126": #LOCATION = "R7P11" !CDS_LOCATION = "R7P11" #SEC = "1" !CDS_SEC = "1";
"A":   PN = "1"  !CDS_PN = "1";
"B":   PN = "2"  !CDS_PN = "2";
BODY = "RES","I140": #LOCATION = "R7P17" !CDS_LOCATION = "R7P17" #SEC = "1" !CDS_SEC = "1";
"A":   PN = "1"  !CDS_PN = "1";
"B":   PN = "2"  !CDS_PN = "2";
BODY = "SOCKET_P_MECH_A","I152": #LOCATION = "XRU2" !CDS_LOCATION = "XRU2";
BODY = "SOCKET_P_MECH_A","I153": #LOCATION = "XLU2" !CDS_LOCATION = "XLU2";
BODY = "RES","I155": #LOCATION = "R3D4" !CDS_LOCATION = "R3D4" #SEC = "1" !CDS_SEC = "1";
"A":   PN = "1"  !CDS_PN = "1";
"B":   PN = "2"  !CDS_PN = "2";
BODY = "RES","I156": #LOCATION = "R7P26" !CDS_LOCATION = "R7P26" #SEC = "1" !CDS_SEC = "1";
"A":   PN = "1"  !CDS_PN = "1";
"B":   PN = "2"  !CDS_PN = "2";
BODY = "RES","I157": #LOCATION = "R8N1" !CDS_LOCATION = "R8N1" #SEC = "1" !CDS_SEC = "1";
"A":   PN = "1"  !CDS_PN = "1";
"B":   PN = "2"  !CDS_PN = "2";
BODY = "RES","I158": #LOCATION = "R8N4" !CDS_LOCATION = "R8N4" #SEC = "1" !CDS_SEC = "1";
"A":   PN = "1"  !CDS_PN = "1";
"B":   PN = "2"  !CDS_PN = "2";
BODY = "RES","I159": #LOCATION = "R8N3" !CDS_LOCATION = "R8N3" #SEC = "1" !CDS_SEC = "1";
"A":   PN = "1"  !CDS_PN = "1";
"B":   PN = "2"  !CDS_PN = "2";
BODY = "RES","I160": #LOCATION = "R8N5" !CDS_LOCATION = "R8N5" #SEC = "1" !CDS_SEC = "1";
"A":   PN = "1"  !CDS_PN = "1";
"B":   PN = "2"  !CDS_PN = "2";
BODY = "RES","I161": #LOCATION = "R8N2" !CDS_LOCATION = "R8N2" #SEC = "1" !CDS_SEC = "1";
"A":   PN = "1"  !CDS_PN = "1";
"B":   PN = "2"  !CDS_PN = "2";
BODY = "RES","I170": #LOCATION = "R7P25" !CDS_LOCATION = "R7P25" #SEC = "1" !CDS_SEC = "1";
"A":   PN = "1"  !CDS_PN = "1";
"B":   PN = "2"  !CDS_PN = "2";
BODY = "SKX_EXT_B","I172": #LOCATION = "U2D1" !CDS_LOCATION = "U2D1" #SEC = "1" !CDS_SEC = "1";
"BCLK0_DN":   PN = "AU24"  !CDS_PN = "AU24";
"BCLK0_DP":   PN = "AW24"  !CDS_PN = "AW24";
"BCLK1_DN":   PN = "CR26"  !CDS_PN = "CR26";
"BCLK1_DP":   PN = "CP27"  !CDS_PN = "CP27";
"BCLK2_DN":   PN = "CT25"  !CDS_PN = "CT25";
"BCLK2_DP":   PN = "CU26"  !CDS_PN = "CU26";
"BIST_ENABLE":   PN = "BA20"  !CDS_PN = "BA20";
"BMCINIT":   PN = "BD23"  !CDS_PN = "BD23";
"BPM<0>_N":   PN = "AJ10"  !CDS_PN = "AJ10";
"BPM<1>_N":   PN = "AH11"  !CDS_PN = "AH11";
"BPM<2>_N":   PN = "AG10"  !CDS_PN = "AG10";
"BPM<3>_N":   PN = "AF11"  !CDS_PN = "AF11";
"BPM<4>_N":   PN = "AA12"  !CDS_PN = "AA12";
"BPM<5>_N":   PN = "Y11"  !CDS_PN = "Y11";
"BPM<6>_N":   PN = "AE12"  !CDS_PN = "AE12";
"BPM<7>_N":   PN = "AC12"  !CDS_PN = "AC12";
"CATERR_N":   PN = "AL14"  !CDS_PN = "AL14";
"DDR0_CAVREF":   PN = "AJ64"  !CDS_PN = "AJ64";
"DDR1_CAVREF":   PN = "AK63"  !CDS_PN = "AK63";
"DDR2_CAVREF":   PN = "AH63"  !CDS_PN = "AH63";
"DDR3_CAVREF":   PN = "CP61"  !CDS_PN = "CP61";
"DDR4_CAVREF":   PN = "CT61"  !CDS_PN = "CT61";
"DDR5_CAVREF":   PN = "CV61"  !CDS_PN = "CV61";
"DDR012_DRAM_PWR_OK":   PN = "AN30"  !CDS_PN = "AN30";
"DDR012_RCOMP<0>":   PN = "Y43"  !CDS_PN = "Y43";
"DDR012_RCOMP<1>":   PN = "AB43"  !CDS_PN = "AB43";
"DDR012_RCOMP<2>":   PN = "AC42"  !CDS_PN = "AC42";
"DDR012_RESET_N":   PN = "U64"  !CDS_PN = "U64";
"DDR012_SPDSCL":   PN = "AJ18"  !CDS_PN = "AJ18";
"DDR012_SPDSDA":   PN = "AF17"  !CDS_PN = "AF17";
"DDR345_DRAM_PWR_OK":   PN = "CR28"  !CDS_PN = "CR28";
"DDR345_RCOMP<0>":   PN = "DC48"  !CDS_PN = "DC48";
"DDR345_RCOMP<1>":   PN = "DD47"  !CDS_PN = "DD47";
"DDR345_RCOMP<2>":   PN = "DD49"  !CDS_PN = "DD49";
"DDR345_RESET_N":   PN = "DV63"  !CDS_PN = "DV63";
"DDR345_SPDSCL":   PN = "AE18"  !CDS_PN = "AE18";
"DDR345_SPDSDA":   PN = "AD17"  !CDS_PN = "AD17";
"EAR_N":   PN = "AJ14"  !CDS_PN = "AJ14";
"ERROR<0>_N":   PN = "AJ12"  !CDS_PN = "AJ12";
"ERROR<1>_N":   PN = "AK11"  !CDS_PN = "AK11";
"ERROR<2>_N":   PN = "AL12"  !CDS_PN = "AL12";
"FRMAGENT":   PN = "AV17"  !CDS_PN = "AV17";
"LEGACY_SKT":   PN = "AE20"  !CDS_PN = "AE20";
"MCP01_RBIAS<0>":   PN = "CU32"  !CDS_PN = "CU32";
"MCP01_RBIAS<1>":   PN = "CT31"  !CDS_PN = "CT31";
"MEM_HOT_C012_N":   PN = "AH13"  !CDS_PN = "AH13";
"MEM_HOT_C345_N":   PN = "AF13"  !CDS_PN = "AF13";
"MSMI_N":   PN = "AN20"  !CDS_PN = "AN20";
"NMI":   PN = "AP11"  !CDS_PN = "AP11";
"PE3_RBIAS<0>":   PN = "CP29"  !CDS_PN = "CP29";
"PE3_RBIAS<1>":   PN = "CR30"  !CDS_PN = "CR30";
"PE012_RBIAS<0>":   PN = "CN30"  !CDS_PN = "CN30";
"PE012_RBIAS<1>":   PN = "CL30"  !CDS_PN = "CL30";
"PE_HP_SCL":   PN = "AM19"  !CDS_PN = "AM19";
"PE_HP_SDA":   PN = "AL18"  !CDS_PN = "AL18";
"PECI":   PN = "AU12"  !CDS_PN = "AU12";
"PIROM_ADDR<0>":   PN = "CU58"  !CDS_PN = "CU58";
"PIROM_ADDR<1>":   PN = "CV57"  !CDS_PN = "CV57";
"PIROM_ADDR<2>":   PN = "CW56"  !CDS_PN = "CW56";
"PKGID<0>":   PN = "DC72"  !CDS_PN = "DC72";
"PKGID<1>":   PN = "CW72"  !CDS_PN = "CW72";
"PKGID<2>":   PN = "DA72"  !CDS_PN = "DA72";
"PM_FAST_WAKE_N":   PN = "AF15"  !CDS_PN = "AF15";
"PMSYNC":   PN = "AR14"  !CDS_PN = "AR14";
"PMSYNC_CLK":   PN = "AT19"  !CDS_PN = "AT19";
"PRDY_N":   PN = "AG16"  !CDS_PN = "AG16";
"PREQ_N":   PN = "AR12"  !CDS_PN = "AR12";
"PROC_ID<0>":   PN = "CY71"  !CDS_PN = "CY71";
"PROC_ID<1>":   PN = "DB71"  !CDS_PN = "DB71";
"PROCDIS_N":   PN = "AB17"  !CDS_PN = "AB17";
"PROCHOT_N":   PN = "AC16"  !CDS_PN = "AC16";
"PWRGOOD":   PN = "BC24"  !CDS_PN = "BC24";
"RESET_N":   PN = "AP21"  !CDS_PN = "AP21";
"SAFE_MODE_BOOT":   PN = "AR18"  !CDS_PN = "AR18";
"SKTOCC_N":   PN = "AB13"  !CDS_PN = "AB13";
"SM_WP":   PN = "CV59"  !CDS_PN = "CV59";
"SMBCLK":   PN = "CT59"  !CDS_PN = "CT59";
"SMBDAT":   PN = "CW58"  !CDS_PN = "CW58";
"SOCKET_ID<0>":   PN = "AU22"  !CDS_PN = "AU22";
"SOCKET_ID<1>":   PN = "AU16"  !CDS_PN = "AU16";
"SOCKET_ID<2>":   PN = "AU20"  !CDS_PN = "AU20";
"SVIDALERT<0>_N":   PN = "DE44"  !CDS_PN = "DE44";
"SVIDALERT<1>_N":   PN = "DL44"  !CDS_PN = "DL44";
"SVIDCLK<0>":   PN = "DC44"  !CDS_PN = "DC44";
"SVIDCLK<1>":   PN = "DG44"  !CDS_PN = "DG44";
"SVIDDATA<0>":   PN = "DB45"  !CDS_PN = "DB45";
"SVIDDATA<1>":   PN = "DJ44"  !CDS_PN = "DJ44";
"TCK":   PN = "AA14"  !CDS_PN = "AA14";
"TDI":   PN = "AC14"  !CDS_PN = "AC14";
"TDO":   PN = "AE14"  !CDS_PN = "AE14";
"TEST_12":   PN = "AY19"  !CDS_PN = "AY19";
"TEST_13":   PN = "DB51"  !CDS_PN = "DB51";
"TEST_14":   PN = "DC50"  !CDS_PN = "DC50";
"TEST_15":   PN = "AW14"  !CDS_PN = "AW14";
"THERMTRIP_N":   PN = "AB15"  !CDS_PN = "AB15";
"TMS":   PN = "W14"  !CDS_PN = "W14";
"TRST_N":   PN = "Y13"  !CDS_PN = "Y13";
"TSC_SYNC":   PN = "AM11"  !CDS_PN = "AM11";
"TXT_AGENT":   PN = "AW18"  !CDS_PN = "AW18";
"TXT_PLTEN":   PN = "AV15"  !CDS_PN = "AV15";
"UPI01_RBIAS<0>":   PN = "AT29"  !CDS_PN = "AT29";
"UPI01_RBIAS<1>":   PN = "AP29"  !CDS_PN = "AP29";
"UPI2_RBIAS<0>":   PN = "CL28"  !CDS_PN = "CL28";
"UPI2_RBIAS<1>":   PN = "CK29"  !CDS_PN = "CK29";
BODY = "RES","I181": #LOCATION = "R6P39" !CDS_LOCATION = "R6P39" #SEC = "1" !CDS_SEC = "1";
"A":   PN = "1"  !CDS_PN = "1";
"B":   PN = "2"  !CDS_PN = "2";
DRAWING = "@baseboard_fab2_lib.baseboard_fab2(sch_1):page56";
BODY = "SKX_EXT_B","I169": #LOCATION = "U2D1" !CDS_LOCATION = "U2D1" #SEC = "2" !CDS_SEC = "2";
"DEBUG_EN_N":   PN = "AV21"  !CDS_PN = "AV21";
"DMIMODE_OVERRIDE":   PN = "AW12"  !CDS_PN = "AW12";
"FIVR_FAULT":   PN = "AU14"  !CDS_PN = "AU14";
"PWR_DEBUG_N":   PN = "AP17"  !CDS_PN = "AP17";
"RSVD<194>":   PN = "AP61"  !CDS_PN = "AP61";
"RSVD<195>":   PN = "AP27"  !CDS_PN = "AP27";
"RSVD<196>":   PN = "AP25"  !CDS_PN = "AP25";
"RSVD<197>":   PN = "AP23"  !CDS_PN = "AP23";
"RSVD<198>":   PN = "AN62"  !CDS_PN = "AN62";
"RSVD<199>":   PN = "AN60"  !CDS_PN = "AN60";
"RSVD<200>":   PN = "AN26"  !CDS_PN = "AN26";
"RSVD<201>":   PN = "AN24"  !CDS_PN = "AN24";
"RSVD<202>":   PN = "AN22"  !CDS_PN = "AN22";
"RSVD<203>":   PN = "AN18"  !CDS_PN = "AN18";
"RSVD<204>":   PN = "AM61"  !CDS_PN = "AM61";
"RSVD<205>":   PN = "AM59"  !CDS_PN = "AM59";
"RSVD<206>":   PN = "AM27"  !CDS_PN = "AM27";
"RSVD<207>":   PN = "AM25"  !CDS_PN = "AM25";
"RSVD<208>":   PN = "AM23"  !CDS_PN = "AM23";
"RSVD<209>":   PN = "AM21"  !CDS_PN = "AM21";
"RSVD<210>":   PN = "AL62"  !CDS_PN = "AL62";
"RSVD<211>":   PN = "AL60"  !CDS_PN = "AL60";
"RSVD<212>":   PN = "AL58"  !CDS_PN = "AL58";
"RSVD<213>":   PN = "AL26"  !CDS_PN = "AL26";
"RSVD<214>":   PN = "AL22"  !CDS_PN = "AL22";
"RSVD<215>":   PN = "AL20"  !CDS_PN = "AL20";
"RSVD<216>":   PN = "AK69"  !CDS_PN = "AK69";
"RSVD<217>":   PN = "AK61"  !CDS_PN = "AK61";
"RSVD<218>":   PN = "AK59"  !CDS_PN = "AK59";
"RSVD<219>":   PN = "AK57"  !CDS_PN = "AK57";
"RSVD<220>":   PN = "AK27"  !CDS_PN = "AK27";
"RSVD<221>":   PN = "AK21"  !CDS_PN = "AK21";
"RSVD<222>":   PN = "AJ70"  !CDS_PN = "AJ70";
"RSVD<223>":   PN = "AJ62"  !CDS_PN = "AJ62";
"RSVD<224>":   PN = "AJ60"  !CDS_PN = "AJ60";
"RSVD<225>":   PN = "AJ58"  !CDS_PN = "AJ58";
"RSVD<226>":   PN = "AJ56"  !CDS_PN = "AJ56";
"RSVD<227>":   PN = "AJ20"  !CDS_PN = "AJ20";
"RSVD<228>":   PN = "AH73"  !CDS_PN = "AH73";
"RSVD<229>":   PN = "AH71"  !CDS_PN = "AH71";
"RSVD<230>":   PN = "AH57"  !CDS_PN = "AH57";
"RSVD<231>":   PN = "AH55"  !CDS_PN = "AH55";
"RSVD<232>":   PN = "AH19"  !CDS_PN = "AH19";
"RSVD<233>":   PN = "AH15"  !CDS_PN = "AH15";
"RSVD<234>":   PN = "AG72"  !CDS_PN = "AG72";
"RSVD<235>":   PN = "AG56"  !CDS_PN = "AG56";
"RSVD<236>":   PN = "AG54"  !CDS_PN = "AG54";
"RSVD<237>":   PN = "AG52"  !CDS_PN = "AG52";
"RSVD<238>":   PN = "AG50"  !CDS_PN = "AG50";
"RSVD<239>":   PN = "AG48"  !CDS_PN = "AG48";
"RSVD<240>":   PN = "AG20"  !CDS_PN = "AG20";
"RSVD<241>":   PN = "AF71"  !CDS_PN = "AF71";
"RSVD<242>":   PN = "AF53"  !CDS_PN = "AF53";
"RSVD<243>":   PN = "AF51"  !CDS_PN = "AF51";
"RSVD<244>":   PN = "AF49"  !CDS_PN = "AF49";
"RSVD<245>":   PN = "AF47"  !CDS_PN = "AF47";
"RSVD<246>":   PN = "AF19"  !CDS_PN = "AF19";
"RSVD<247>":   PN = "AE72"  !CDS_PN = "AE72";
"RSVD<248>":   PN = "AE52"  !CDS_PN = "AE52";
"RSVD<249>":   PN = "AE50"  !CDS_PN = "AE50";
"RSVD<250>":   PN = "AE48"  !CDS_PN = "AE48";
"RSVD<251>":   PN = "AE46"  !CDS_PN = "AE46";
"RSVD<252>":   PN = "AD51"  !CDS_PN = "AD51";
"RSVD<253>":   PN = "AD49"  !CDS_PN = "AD49";
"RSVD<254>":   PN = "AD47"  !CDS_PN = "AD47";
"RSVD<256>":   PN = "Y65"  !CDS_PN = "Y65";
"RSVD<257>":   PN = "Y23"  !CDS_PN = "Y23";
"RSVD<258>":   PN = "W66"  !CDS_PN = "W66";
"RSVD<259>":   PN = "V67"  !CDS_PN = "V67";
"RSVD<260>":   PN = "V65"  !CDS_PN = "V65";
"RSVD<261>":   PN = "U66"  !CDS_PN = "U66";
"RSVD<262>":   PN = "T67"  !CDS_PN = "T67";
"RSVD<263>":   PN = "R66"  !CDS_PN = "R66";
"RSVD<264>":   PN = "R62"  !CDS_PN = "R62";
"RSVD<265>":   PN = "P65"  !CDS_PN = "P65";
"RSVD<266>":   PN = "M63"  !CDS_PN = "M63";
"RSVD<267>":   PN = "K61"  !CDS_PN = "K61";
"RSVD<268>":   PN = "J62"  !CDS_PN = "J62";
"RSVD<269>":   PN = "J46"  !CDS_PN = "J46";
"RSVD<270>":   PN = "H85"  !CDS_PN = "H85";
"RSVD<271>":   PN = "H83"  !CDS_PN = "H83";
"RSVD<272>":   PN = "H1"  !CDS_PN = "H1";
"RSVD<273>":   PN = "G84"  !CDS_PN = "G84";
"RSVD<274>":   PN = "G64"  !CDS_PN = "G64";
"RSVD<275>":   PN = "G2"  !CDS_PN = "G2";
"RSVD<276>":   PN = "F83"  !CDS_PN = "F83";
"RSVD<277>":   PN = "F65"  !CDS_PN = "F65";
"RSVD<278>":   PN = "F23"  !CDS_PN = "F23";
"RSVD<279>":   PN = "F3"  !CDS_PN = "F3";
"RSVD<280>":   PN = "E84"  !CDS_PN = "E84";
"RSVD<281>":   PN = "E24"  !CDS_PN = "E24";
"RSVD<282>":   PN = "E4"  !CDS_PN = "E4";
"RSVD<283>":   PN = "E2"  !CDS_PN = "E2";
"RSVD<284>":   PN = "D83"  !CDS_PN = "D83";
"RSVD<285>":   PN = "D65"  !CDS_PN = "D65";
"RSVD<286>":   PN = "D17"  !CDS_PN = "D17";
"RSVD<287>":   PN = "D5"  !CDS_PN = "D5";
"RSVD<288>":   PN = "C82"  !CDS_PN = "C82";
"RSVD<289>":   PN = "C24"  !CDS_PN = "C24";
"RSVD<290>":   PN = "C18"  !CDS_PN = "C18";
"RSVD<291>":   PN = "C6"  !CDS_PN = "C6";
"RSVD<292>":   PN = "B81"  !CDS_PN = "B81";
"RSVD<293>":   PN = "B77"  !CDS_PN = "B77";
"RSVD<294>":   PN = "B17"  !CDS_PN = "B17";
"RSVD<295>":   PN = "B15"  !CDS_PN = "B15";
"RSVD<296>":   PN = "B13"  !CDS_PN = "B13";
"RSVD<298>":   PN = "B7"  !CDS_PN = "B7";
"RSVD<299>":   PN = "B3"  !CDS_PN = "B3";
"RSVD<300>":   PN = "A24"  !CDS_PN = "A24";
"RSVD<301>":   PN = "A16"  !CDS_PN = "A16";
"RSVD<302>":   PN = "A14"  !CDS_PN = "A14";
"RSVD<303>":   PN = "A6"  !CDS_PN = "A6";
"RSVD<304>":   PN = "A4"  !CDS_PN = "A4";
"TEST_1":   PN = "AF45"  !CDS_PN = "AF45";
"TEST_2":   PN = "AG46"  !CDS_PN = "AG46";
"TEST_3":   PN = "AM13"  !CDS_PN = "AM13";
"TEST_4":   PN = "AN12"  !CDS_PN = "AN12";
"TEST_5":   PN = "AN14"  !CDS_PN = "AN14";
"TEST_11":   PN = "AY13"  !CDS_PN = "AY13";
BODY = "RES","I173": #LOCATION = "R8P3" !CDS_LOCATION = "R8P3" #SEC = "1" !CDS_SEC = "1";
"A":   PN = "1"  !CDS_PN = "1";
"B":   PN = "2"  !CDS_PN = "2";
BODY = "RES","I174": #LOCATION = "R8R1" !CDS_LOCATION = "R8R1" #SEC = "1" !CDS_SEC = "1";
"A":   PN = "1"  !CDS_PN = "1";
"B":   PN = "2"  !CDS_PN = "2";
DRAWING = "@baseboard_fab2_lib.baseboard_fab2(sch_1):page57";
BODY = "SKX_EXT_B","I172": #LOCATION = "U2D1" !CDS_LOCATION = "U2D1" #SEC = "3" !CDS_SEC = "3";
"DDR0_ACT_N":   PN = "J60"  !CDS_PN = "J60";
"DDR0_ALERT_N":   PN = "B61"  !CDS_PN = "B61";
"DDR0_BA<0>":   PN = "C52"  !CDS_PN = "C52";
"DDR0_BA<1>":   PN = "G54"  !CDS_PN = "G54";
"DDR0_BG<0>":   PN = "D61"  !CDS_PN = "D61";
"DDR0_BG<1>":   PN = "F63"  !CDS_PN = "F63";
"DDR0_CID<2>":   PN = "G46"  !CDS_PN = "G46";
"DDR0_CKE<0>":   PN = "C62"  !CDS_PN = "C62";
"DDR0_CKE<1>":   PN = "C64"  !CDS_PN = "C64";
"DDR0_CKE<2>":   PN = "B63"  !CDS_PN = "B63";
"DDR0_CKE<3>":   PN = "D63"  !CDS_PN = "D63";
"DDR0_CLK_DN<0>":   PN = "F55"  !CDS_PN = "F55";
"DDR0_CLK_DN<1>":   PN = "C54"  !CDS_PN = "C54";
"DDR0_CLK_DN<2>":   PN = "J56"  !CDS_PN = "J56";
"DDR0_CLK_DN<3>":   PN = "C56"  !CDS_PN = "C56";
"DDR0_CLK_DP<0>":   PN = "D55"  !CDS_PN = "D55";
"DDR0_CLK_DP<1>":   PN = "B55"  !CDS_PN = "B55";
"DDR0_CLK_DP<2>":   PN = "G56"  !CDS_PN = "G56";
"DDR0_CLK_DP<3>":   PN = "B57"  !CDS_PN = "B57";
"DDR0_CS<0>_N":   PN = "G52"  !CDS_PN = "G52";
"DDR0_CS<1>_N":   PN = "F49"  !CDS_PN = "F49";
"DDR0_CS<2>_N":   PN = "D47"  !CDS_PN = "D47";
"DDR0_CS<3>_N":   PN = "F47"  !CDS_PN = "F47";
"DDR0_CS<4>_N":   PN = "B51"  !CDS_PN = "B51";
"DDR0_CS<5>_N":   PN = "D49"  !CDS_PN = "D49";
"DDR0_CS<6>_N":   PN = "F45"  !CDS_PN = "F45";
"DDR0_CS<7>_N":   PN = "K45"  !CDS_PN = "K45";
"DDR0_DQ<0>":   PN = "AN86"  !CDS_PN = "AN86";
"DDR0_DQ<1>":   PN = "AN84"  !CDS_PN = "AN84";
"DDR0_DQ<2>":   PN = "AE86"  !CDS_PN = "AE86";
"DDR0_DQ<3>":   PN = "AE84"  !CDS_PN = "AE84";
"DDR0_DQ<4>":   PN = "AR86"  !CDS_PN = "AR86";
"DDR0_DQ<5>":   PN = "AR84"  !CDS_PN = "AR84";
"DDR0_DQ<6>":   PN = "AG86"  !CDS_PN = "AG86";
"DDR0_DQ<7>":   PN = "AG84"  !CDS_PN = "AG84";
"DDR0_DQ<8>":   PN = "W86"  !CDS_PN = "W86";
"DDR0_DQ<9>":   PN = "W84"  !CDS_PN = "W84";
"DDR0_DQ<10>":   PN = "L86"  !CDS_PN = "L86";
"DDR0_DQ<11>":   PN = "L84"  !CDS_PN = "L84";
"DDR0_DQ<12>":   PN = "AA86"  !CDS_PN = "AA86";
"DDR0_DQ<13>":   PN = "AA84"  !CDS_PN = "AA84";
"DDR0_DQ<14>":   PN = "N86"  !CDS_PN = "N86";
"DDR0_DQ<15>":   PN = "N84"  !CDS_PN = "N84";
"DDR0_DQ<16>":   PN = "V81"  !CDS_PN = "V81";
"DDR0_DQ<17>":   PN = "T79"  !CDS_PN = "T79";
"DDR0_DQ<18>":   PN = "N82"  !CDS_PN = "N82";
"DDR0_DQ<19>":   PN = "M81"  !CDS_PN = "M81";
"DDR0_DQ<20>":   PN = "W80"  !CDS_PN = "W80";
"DDR0_DQ<21>":   PN = "V79"  !CDS_PN = "V79";
"DDR0_DQ<22>":   PN = "R82"  !CDS_PN = "R82";
"DDR0_DQ<23>":   PN = "N80"  !CDS_PN = "N80";
"DDR0_DQ<24>":   PN = "L76"  !CDS_PN = "L76";
"DDR0_DQ<25>":   PN = "R76"  !CDS_PN = "R76";
"DDR0_DQ<26>":   PN = "M73"  !CDS_PN = "M73";
"DDR0_DQ<27>":   PN = "P73"  !CDS_PN = "P73";
"DDR0_DQ<28>":   PN = "M77"  !CDS_PN = "M77";
"DDR0_DQ<29>":   PN = "P77"  !CDS_PN = "P77";
"DDR0_DQ<30>":   PN = "L74"  !CDS_PN = "L74";
"DDR0_DQ<31>":   PN = "R74"  !CDS_PN = "R74";
"DDR0_DQ<32>":   PN = "C42"  !CDS_PN = "C42";
"DDR0_DQ<33>":   PN = "B41"  !CDS_PN = "B41";
"DDR0_DQ<34>":   PN = "C38"  !CDS_PN = "C38";
"DDR0_DQ<35>":   PN = "E38"  !CDS_PN = "E38";
"DDR0_DQ<36>":   PN = "E42"  !CDS_PN = "E42";
"DDR0_DQ<37>":   PN = "F41"  !CDS_PN = "F41";
"DDR0_DQ<38>":   PN = "B39"  !CDS_PN = "B39";
"DDR0_DQ<39>":   PN = "F39"  !CDS_PN = "F39";
"DDR0_DQ<40>":   PN = "K37"  !CDS_PN = "K37";
"DDR0_DQ<41>":   PN = "P37"  !CDS_PN = "P37";
"DDR0_DQ<42>":   PN = "L34"  !CDS_PN = "L34";
"DDR0_DQ<43>":   PN = "N34"  !CDS_PN = "N34";
"DDR0_DQ<44>":   PN = "L38"  !CDS_PN = "L38";
"DDR0_DQ<45>":   PN = "N38"  !CDS_PN = "N38";
"DDR0_DQ<46>":   PN = "K35"  !CDS_PN = "K35";
"DDR0_DQ<47>":   PN = "P35"  !CDS_PN = "P35";
"DDR0_DQ<48>":   PN = "K31"  !CDS_PN = "K31";
"DDR0_DQ<49>":   PN = "P31"  !CDS_PN = "P31";
"DDR0_DQ<50>":   PN = "L28"  !CDS_PN = "L28";
"DDR0_DQ<51>":   PN = "N28"  !CDS_PN = "N28";
"DDR0_DQ<52>":   PN = "L32"  !CDS_PN = "L32";
"DDR0_DQ<53>":   PN = "N32"  !CDS_PN = "N32";
"DDR0_DQ<54>":   PN = "K29"  !CDS_PN = "K29";
"DDR0_DQ<55>":   PN = "P29"  !CDS_PN = "P29";
"DDR0_DQ<56>":   PN = "K25"  !CDS_PN = "K25";
"DDR0_DQ<57>":   PN = "P25"  !CDS_PN = "P25";
"DDR0_DQ<58>":   PN = "P23"  !CDS_PN = "P23";
"DDR0_DQ<59>":   PN = "T23"  !CDS_PN = "T23";
"DDR0_DQ<60>":   PN = "L26"  !CDS_PN = "L26";
"DDR0_DQ<61>":   PN = "N26"  !CDS_PN = "N26";
"DDR0_DQ<62>":   PN = "H23"  !CDS_PN = "H23";
"DDR0_DQ<63>":   PN = "K23"  !CDS_PN = "K23";
"DDR0_DQS_DN<0>":   PN = "AJ84"  !CDS_PN = "AJ84";
"DDR0_DQS_DN<1>":   PN = "R84"  !CDS_PN = "R84";
"DDR0_DQS_DN<2>":   PN = "P79"  !CDS_PN = "P79";
"DDR0_DQS_DN<3>":   PN = "T75"  !CDS_PN = "T75";
"DDR0_DQS_DN<4>":   PN = "G40"  !CDS_PN = "G40";
"DDR0_DQS_DN<5>":   PN = "R36"  !CDS_PN = "R36";
"DDR0_DQS_DN<6>":   PN = "R30"  !CDS_PN = "R30";
"DDR0_DQS_DN<7>":   PN = "N24"  !CDS_PN = "N24";
"DDR0_DQS_DN<8>":   PN = "AH67"  !CDS_PN = "AH67";
"DDR0_DQS_DN<9>":   PN = "AL84"  !CDS_PN = "AL84";
"DDR0_DQS_DN<10>":   PN = "U84"  !CDS_PN = "U84";
"DDR0_DQS_DN<11>":   PN = "U82"  !CDS_PN = "U82";
"DDR0_DQS_DN<12>":   PN = "K75"  !CDS_PN = "K75";
"DDR0_DQS_DN<13>":   PN = "A40"  !CDS_PN = "A40";
"DDR0_DQS_DN<14>":   PN = "J36"  !CDS_PN = "J36";
"DDR0_DQS_DN<15>":   PN = "J30"  !CDS_PN = "J30";
"DDR0_DQS_DN<16>":   PN = "J24"  !CDS_PN = "J24";
"DDR0_DQS_DN<17>":   PN = "AB67"  !CDS_PN = "AB67";
"DDR0_DQS_DP<0>":   PN = "AH85"  !CDS_PN = "AH85";
"DDR0_DQS_DP<1>":   PN = "P85"  !CDS_PN = "P85";
"DDR0_DQS_DP<2>":   PN = "R80"  !CDS_PN = "R80";
"DDR0_DQS_DP<3>":   PN = "P75"  !CDS_PN = "P75";
"DDR0_DQS_DP<4>":   PN = "E40"  !CDS_PN = "E40";
"DDR0_DQS_DP<5>":   PN = "N36"  !CDS_PN = "N36";
"DDR0_DQS_DP<6>":   PN = "N30"  !CDS_PN = "N30";
"DDR0_DQS_DP<7>":   PN = "R24"  !CDS_PN = "R24";
"DDR0_DQS_DP<8>":   PN = "AF67"  !CDS_PN = "AF67";
"DDR0_DQS_DP<9>":   PN = "AM85"  !CDS_PN = "AM85";
"DDR0_DQS_DP<10>":   PN = "V85"  !CDS_PN = "V85";
"DDR0_DQS_DP<11>":   PN = "T81"  !CDS_PN = "T81";
"DDR0_DQS_DP<12>":   PN = "M75"  !CDS_PN = "M75";
"DDR0_DQS_DP<13>":   PN = "C40"  !CDS_PN = "C40";
"DDR0_DQS_DP<14>":   PN = "L36"  !CDS_PN = "L36";
"DDR0_DQS_DP<15>":   PN = "L30"  !CDS_PN = "L30";
"DDR0_DQS_DP<16>":   PN = "L24"  !CDS_PN = "L24";
"DDR0_DQS_DP<17>":   PN = "AD67"  !CDS_PN = "AD67";
"DDR0_ECC<0>":   PN = "AC68"  !CDS_PN = "AC68";
"DDR0_ECC<1>":   PN = "AG68"  !CDS_PN = "AG68";
"DDR0_ECC<2>":   PN = "AD65"  !CDS_PN = "AD65";
"DDR0_ECC<3>":   PN = "AF65"  !CDS_PN = "AF65";
"DDR0_ECC<4>":   PN = "AD69"  !CDS_PN = "AD69";
"DDR0_ECC<5>":   PN = "AF69"  !CDS_PN = "AF69";
"DDR0_ECC<6>":   PN = "AC66"  !CDS_PN = "AC66";
"DDR0_ECC<7>":   PN = "AG66"  !CDS_PN = "AG66";
"DDR0_MA<0>":   PN = "F53"  !CDS_PN = "F53";
"DDR0_MA<1>":   PN = "F57"  !CDS_PN = "F57";
"DDR0_MA<2>":   PN = "D57"  !CDS_PN = "D57";
"DDR0_MA<3>":   PN = "C58"  !CDS_PN = "C58";
"DDR0_MA<4>":   PN = "G58"  !CDS_PN = "G58";
"DDR0_MA<5>":   PN = "F59"  !CDS_PN = "F59";
"DDR0_MA<6>":   PN = "D59"  !CDS_PN = "D59";
"DDR0_MA<7>":   PN = "G60"  !CDS_PN = "G60";
"DDR0_MA<8>":   PN = "C60"  !CDS_PN = "C60";
"DDR0_MA<9>":   PN = "F61"  !CDS_PN = "F61";
"DDR0_MA<10>":   PN = "J54"  !CDS_PN = "J54";
"DDR0_MA<11>":   PN = "G62"  !CDS_PN = "G62";
"DDR0_MA<12>":   PN = "J64"  !CDS_PN = "J64";
"DDR0_MA<13>":   PN = "J48"  !CDS_PN = "J48";
"DDR0_MA<14>":   PN = "F51"  !CDS_PN = "F51";
"DDR0_MA<15>":   PN = "K49"  !CDS_PN = "K49";
"DDR0_MA<16>":   PN = "D51"  !CDS_PN = "D51";
"DDR0_MA<17>":   PN = "K47"  !CDS_PN = "K47";
"DDR0_ODT<0>":   PN = "C50"  !CDS_PN = "C50";
"DDR0_ODT<1>":   PN = "C48"  !CDS_PN = "C48";
"DDR0_ODT<2>":   PN = "G50"  !CDS_PN = "G50";
"DDR0_ODT<3>":   PN = "G48"  !CDS_PN = "G48";
"DDR0_PAR":   PN = "D53"  !CDS_PN = "D53";
DRAWING = "@baseboard_fab2_lib.baseboard_fab2(sch_1):page58";
BODY = "SKX_EXT_B","I172": #LOCATION = "U2D1" !CDS_LOCATION = "U2D1" #SEC = "4" !CDS_SEC = "4";
"DDR1_ACT_N":   PN = "T63"  !CDS_PN = "T63";
"DDR1_ALERT_N":   PN = "W62"  !CDS_PN = "W62";
"DDR1_BA<0>":   PN = "T53"  !CDS_PN = "T53";
"DDR1_BA<1>":   PN = "K55"  !CDS_PN = "K55";
"DDR1_BG<0>":   PN = "M61"  !CDS_PN = "M61";
"DDR1_BG<1>":   PN = "N60"  !CDS_PN = "N60";
"DDR1_CID<2>":   PN = "M47"  !CDS_PN = "M47";
"DDR1_CKE<0>":   PN = "N62"  !CDS_PN = "N62";
"DDR1_CKE<1>":   PN = "R64"  !CDS_PN = "R64";
"DDR1_CKE<2>":   PN = "K63"  !CDS_PN = "K63";
"DDR1_CKE<3>":   PN = "L64"  !CDS_PN = "L64";
"DDR1_CLK_DN<0>":   PN = "M53"  !CDS_PN = "M53";
"DDR1_CLK_DN<1>":   PN = "R54"  !CDS_PN = "R54";
"DDR1_CLK_DN<2>":   PN = "N56"  !CDS_PN = "N56";
"DDR1_CLK_DN<3>":   PN = "R56"  !CDS_PN = "R56";
"DDR1_CLK_DP<0>":   PN = "N54"  !CDS_PN = "N54";
"DDR1_CLK_DP<1>":   PN = "T55"  !CDS_PN = "T55";
"DDR1_CLK_DP<2>":   PN = "M57"  !CDS_PN = "M57";
"DDR1_CLK_DP<3>":   PN = "T57"  !CDS_PN = "T57";
"DDR1_CS<0>_N":   PN = "K51"  !CDS_PN = "K51";
"DDR1_CS<1>_N":   PN = "R50"  !CDS_PN = "R50";
"DDR1_CS<2>_N":   PN = "N46"  !CDS_PN = "N46";
"DDR1_CS<3>_N":   PN = "V47"  !CDS_PN = "V47";
"DDR1_CS<4>_N":   PN = "J50"  !CDS_PN = "J50";
"DDR1_CS<5>_N":   PN = "T49"  !CDS_PN = "T49";
"DDR1_CS<6>_N":   PN = "M45"  !CDS_PN = "M45";
"DDR1_CS<7>_N":   PN = "R46"  !CDS_PN = "R46";
"DDR1_DQ<0>":   PN = "AV81"  !CDS_PN = "AV81";
"DDR1_DQ<1>":   PN = "AT79"  !CDS_PN = "AT79";
"DDR1_DQ<2>":   PN = "AN82"  !CDS_PN = "AN82";
"DDR1_DQ<3>":   PN = "AM81"  !CDS_PN = "AM81";
"DDR1_DQ<4>":   PN = "AW80"  !CDS_PN = "AW80";
"DDR1_DQ<5>":   PN = "AV79"  !CDS_PN = "AV79";
"DDR1_DQ<6>":   PN = "AR82"  !CDS_PN = "AR82";
"DDR1_DQ<7>":   PN = "AN80"  !CDS_PN = "AN80";
"DDR1_DQ<8>":   PN = "AH81"  !CDS_PN = "AH81";
"DDR1_DQ<9>":   PN = "AF79"  !CDS_PN = "AF79";
"DDR1_DQ<10>":   PN = "AC82"  !CDS_PN = "AC82";
"DDR1_DQ<11>":   PN = "AB81"  !CDS_PN = "AB81";
"DDR1_DQ<12>":   PN = "AJ80"  !CDS_PN = "AJ80";
"DDR1_DQ<13>":   PN = "AH79"  !CDS_PN = "AH79";
"DDR1_DQ<14>":   PN = "AE82"  !CDS_PN = "AE82";
"DDR1_DQ<15>":   PN = "AC80"  !CDS_PN = "AC80";
"DDR1_DQ<16>":   PN = "E80"  !CDS_PN = "E80";
"DDR1_DQ<17>":   PN = "J80"  !CDS_PN = "J80";
"DDR1_DQ<18>":   PN = "F77"  !CDS_PN = "F77";
"DDR1_DQ<19>":   PN = "H77"  !CDS_PN = "H77";
"DDR1_DQ<20>":   PN = "F81"  !CDS_PN = "F81";
"DDR1_DQ<21>":   PN = "H81"  !CDS_PN = "H81";
"DDR1_DQ<22>":   PN = "E78"  !CDS_PN = "E78";
"DDR1_DQ<23>":   PN = "J78"  !CDS_PN = "J78";
"DDR1_DQ<24>":   PN = "D75"  !CDS_PN = "D75";
"DDR1_DQ<25>":   PN = "C74"  !CDS_PN = "C74";
"DDR1_DQ<26>":   PN = "D71"  !CDS_PN = "D71";
"DDR1_DQ<27>":   PN = "F71"  !CDS_PN = "F71";
"DDR1_DQ<28>":   PN = "F75"  !CDS_PN = "F75";
"DDR1_DQ<29>":   PN = "G74"  !CDS_PN = "G74";
"DDR1_DQ<30>":   PN = "C72"  !CDS_PN = "C72";
"DDR1_DQ<31>":   PN = "G72"  !CDS_PN = "G72";
"DDR1_DQ<32>":   PN = "K43"  !CDS_PN = "K43";
"DDR1_DQ<33>":   PN = "H43"  !CDS_PN = "H43";
"DDR1_DQ<34>":   PN = "L40"  !CDS_PN = "L40";
"DDR1_DQ<35>":   PN = "N40"  !CDS_PN = "N40";
"DDR1_DQ<36>":   PN = "P43"  !CDS_PN = "P43";
"DDR1_DQ<37>":   PN = "T43"  !CDS_PN = "T43";
"DDR1_DQ<38>":   PN = "K41"  !CDS_PN = "K41";
"DDR1_DQ<39>":   PN = "P41"  !CDS_PN = "P41";
"DDR1_DQ<40>":   PN = "C36"  !CDS_PN = "C36";
"DDR1_DQ<41>":   PN = "B35"  !CDS_PN = "B35";
"DDR1_DQ<42>":   PN = "C32"  !CDS_PN = "C32";
"DDR1_DQ<43>":   PN = "E32"  !CDS_PN = "E32";
"DDR1_DQ<44>":   PN = "E36"  !CDS_PN = "E36";
"DDR1_DQ<45>":   PN = "F35"  !CDS_PN = "F35";
"DDR1_DQ<46>":   PN = "B33"  !CDS_PN = "B33";
"DDR1_DQ<47>":   PN = "F33"  !CDS_PN = "F33";
"DDR1_DQ<48>":   PN = "C30"  !CDS_PN = "C30";
"DDR1_DQ<49>":   PN = "B29"  !CDS_PN = "B29";
"DDR1_DQ<50>":   PN = "C26"  !CDS_PN = "C26";
"DDR1_DQ<51>":   PN = "E26"  !CDS_PN = "E26";
"DDR1_DQ<52>":   PN = "E30"  !CDS_PN = "E30";
"DDR1_DQ<53>":   PN = "F29"  !CDS_PN = "F29";
"DDR1_DQ<54>":   PN = "B27"  !CDS_PN = "B27";
"DDR1_DQ<55>":   PN = "F27"  !CDS_PN = "F27";
"DDR1_DQ<56>":   PN = "U28"  !CDS_PN = "U28";
"DDR1_DQ<57>":   PN = "AA28"  !CDS_PN = "AA28";
"DDR1_DQ<58>":   PN = "V25"  !CDS_PN = "V25";
"DDR1_DQ<59>":   PN = "Y25"  !CDS_PN = "Y25";
"DDR1_DQ<60>":   PN = "V29"  !CDS_PN = "V29";
"DDR1_DQ<61>":   PN = "Y29"  !CDS_PN = "Y29";
"DDR1_DQ<62>":   PN = "U26"  !CDS_PN = "U26";
"DDR1_DQ<63>":   PN = "AA26"  !CDS_PN = "AA26";
"DDR1_DQS_DN<0>":   PN = "AP79"  !CDS_PN = "AP79";
"DDR1_DQS_DN<1>":   PN = "AD79"  !CDS_PN = "AD79";
"DDR1_DQS_DN<2>":   PN = "K79"  !CDS_PN = "K79";
"DDR1_DQS_DN<3>":   PN = "H73"  !CDS_PN = "H73";
"DDR1_DQS_DN<4>":   PN = "N42"  !CDS_PN = "N42";
"DDR1_DQS_DN<5>":   PN = "G34"  !CDS_PN = "G34";
"DDR1_DQS_DN<6>":   PN = "G28"  !CDS_PN = "G28";
"DDR1_DQS_DN<7>":   PN = "AB27"  !CDS_PN = "AB27";
"DDR1_DQS_DN<8>":   PN = "N68"  !CDS_PN = "N68";
"DDR1_DQS_DN<9>":   PN = "AU82"  !CDS_PN = "AU82";
"DDR1_DQS_DN<10>":   PN = "AG82"  !CDS_PN = "AG82";
"DDR1_DQS_DN<11>":   PN = "D79"  !CDS_PN = "D79";
"DDR1_DQS_DN<12>":   PN = "B73"  !CDS_PN = "B73";
"DDR1_DQS_DN<13>":   PN = "J42"  !CDS_PN = "J42";
"DDR1_DQS_DN<14>":   PN = "A34"  !CDS_PN = "A34";
"DDR1_DQS_DN<15>":   PN = "A28"  !CDS_PN = "A28";
"DDR1_DQS_DN<16>":   PN = "T27"  !CDS_PN = "T27";
"DDR1_DQS_DN<17>":   PN = "G68"  !CDS_PN = "G68";
"DDR1_DQS_DP<0>":   PN = "AR80"  !CDS_PN = "AR80";
"DDR1_DQS_DP<1>":   PN = "AE80"  !CDS_PN = "AE80";
"DDR1_DQS_DP<2>":   PN = "H79"  !CDS_PN = "H79";
"DDR1_DQS_DP<3>":   PN = "F73"  !CDS_PN = "F73";
"DDR1_DQS_DP<4>":   PN = "R42"  !CDS_PN = "R42";
"DDR1_DQS_DP<5>":   PN = "E34"  !CDS_PN = "E34";
"DDR1_DQS_DP<6>":   PN = "E28"  !CDS_PN = "E28";
"DDR1_DQS_DP<7>":   PN = "Y27"  !CDS_PN = "Y27";
"DDR1_DQS_DP<8>":   PN = "L68"  !CDS_PN = "L68";
"DDR1_DQS_DP<9>":   PN = "AT81"  !CDS_PN = "AT81";
"DDR1_DQS_DP<10>":   PN = "AF81"  !CDS_PN = "AF81";
"DDR1_DQS_DP<11>":   PN = "F79"  !CDS_PN = "F79";
"DDR1_DQS_DP<12>":   PN = "D73"  !CDS_PN = "D73";
"DDR1_DQS_DP<13>":   PN = "L42"  !CDS_PN = "L42";
"DDR1_DQS_DP<14>":   PN = "C34"  !CDS_PN = "C34";
"DDR1_DQS_DP<15>":   PN = "C28"  !CDS_PN = "C28";
"DDR1_DQS_DP<16>":   PN = "V27"  !CDS_PN = "V27";
"DDR1_DQS_DP<17>":   PN = "J68"  !CDS_PN = "J68";
"DDR1_ECC<0>":   PN = "J70"  !CDS_PN = "J70";
"DDR1_ECC<1>":   PN = "H69"  !CDS_PN = "H69";
"DDR1_ECC<2>":   PN = "J66"  !CDS_PN = "J66";
"DDR1_ECC<3>":   PN = "L66"  !CDS_PN = "L66";
"DDR1_ECC<4>":   PN = "L70"  !CDS_PN = "L70";
"DDR1_ECC<5>":   PN = "M69"  !CDS_PN = "M69";
"DDR1_ECC<6>":   PN = "H67"  !CDS_PN = "H67";
"DDR1_ECC<7>":   PN = "M67"  !CDS_PN = "M67";
"DDR1_MA<0>":   PN = "J52"  !CDS_PN = "J52";
"DDR1_MA<1>":   PN = "J58"  !CDS_PN = "J58";
"DDR1_MA<2>":   PN = "K57"  !CDS_PN = "K57";
"DDR1_MA<3>":   PN = "N58"  !CDS_PN = "N58";
"DDR1_MA<4>":   PN = "M59"  !CDS_PN = "M59";
"DDR1_MA<5>":   PN = "R58"  !CDS_PN = "R58";
"DDR1_MA<6>":   PN = "T59"  !CDS_PN = "T59";
"DDR1_MA<7>":   PN = "V61"  !CDS_PN = "V61";
"DDR1_MA<8>":   PN = "W60"  !CDS_PN = "W60";
"DDR1_MA<9>":   PN = "K59"  !CDS_PN = "K59";
"DDR1_MA<10>":   PN = "M55"  !CDS_PN = "M55";
"DDR1_MA<11>":   PN = "R60"  !CDS_PN = "R60";
"DDR1_MA<12>":   PN = "T61"  !CDS_PN = "T61";
"DDR1_MA<13>":   PN = "M51"  !CDS_PN = "M51";
"DDR1_MA<14>":   PN = "T51"  !CDS_PN = "T51";
"DDR1_MA<15>":   PN = "N52"  !CDS_PN = "N52";
"DDR1_MA<16>":   PN = "R52"  !CDS_PN = "R52";
"DDR1_MA<17>":   PN = "N48"  !CDS_PN = "N48";
"DDR1_ODT<0>":   PN = "N50"  !CDS_PN = "N50";
"DDR1_ODT<1>":   PN = "R48"  !CDS_PN = "R48";
"DDR1_ODT<2>":   PN = "M49"  !CDS_PN = "M49";
"DDR1_ODT<3>":   PN = "T47"  !CDS_PN = "T47";
"DDR1_PAR":   PN = "K53"  !CDS_PN = "K53";
DRAWING = "@baseboard_fab2_lib.baseboard_fab2(sch_1):page59";
BODY = "SKX_EXT_B","I172": #LOCATION = "U2D1" !CDS_LOCATION = "U2D1" #SEC = "5" !CDS_SEC = "5";
"DDR2_ACT_N":   PN = "AB61"  !CDS_PN = "AB61";
"DDR2_ALERT_N":   PN = "AD61"  !CDS_PN = "AD61";
"DDR2_BA<0>":   PN = "W52"  !CDS_PN = "W52";
"DDR2_BA<1>":   PN = "AE56"  !CDS_PN = "AE56";
"DDR2_BG<0>":   PN = "AA60"  !CDS_PN = "AA60";
"DDR2_BG<1>":   PN = "AE62"  !CDS_PN = "AE62";
"DDR2_CID<2>":   PN = "AB45"  !CDS_PN = "AB45";
"DDR2_CKE<0>":   PN = "AA62"  !CDS_PN = "AA62";
"DDR2_CKE<1>":   PN = "AD63"  !CDS_PN = "AD63";
"DDR2_CKE<2>":   PN = "V63"  !CDS_PN = "V63";
"DDR2_CKE<3>":   PN = "AB63"  !CDS_PN = "AB63";
"DDR2_CLK_DN<0>":   PN = "AA54"  !CDS_PN = "AA54";
"DDR2_CLK_DN<1>":   PN = "W54"  !CDS_PN = "W54";
"DDR2_CLK_DN<2>":   PN = "AA56"  !CDS_PN = "AA56";
"DDR2_CLK_DN<3>":   PN = "W56"  !CDS_PN = "W56";
"DDR2_CLK_DP<0>":   PN = "AB55"  !CDS_PN = "AB55";
"DDR2_CLK_DP<1>":   PN = "V55"  !CDS_PN = "V55";
"DDR2_CLK_DP<2>":   PN = "AB57"  !CDS_PN = "AB57";
"DDR2_CLK_DP<3>":   PN = "V57"  !CDS_PN = "V57";
"DDR2_CS<0>_N":   PN = "V51"  !CDS_PN = "V51";
"DDR2_CS<1>_N":   PN = "AB49"  !CDS_PN = "AB49";
"DDR2_CS<2>_N":   PN = "W46"  !CDS_PN = "W46";
"DDR2_CS<3>_N":   PN = "AA46"  !CDS_PN = "AA46";
"DDR2_CS<4>_N":   PN = "AB51"  !CDS_PN = "AB51";
"DDR2_CS<5>_N":   PN = "W48"  !CDS_PN = "W48";
"DDR2_CS<6>_N":   PN = "T45"  !CDS_PN = "T45";
"DDR2_CS<7>_N":   PN = "V45"  !CDS_PN = "V45";
"DDR2_DQ<0>":   PN = "AR76"  !CDS_PN = "AR76";
"DDR2_DQ<1>":   PN = "AN74"  !CDS_PN = "AN74";
"DDR2_DQ<2>":   PN = "AK77"  !CDS_PN = "AK77";
"DDR2_DQ<3>":   PN = "AJ76"  !CDS_PN = "AJ76";
"DDR2_DQ<4>":   PN = "AT75"  !CDS_PN = "AT75";
"DDR2_DQ<5>":   PN = "AR74"  !CDS_PN = "AR74";
"DDR2_DQ<6>":   PN = "AM77"  !CDS_PN = "AM77";
"DDR2_DQ<7>":   PN = "AK75"  !CDS_PN = "AK75";
"DDR2_DQ<8>":   PN = "AE76"  !CDS_PN = "AE76";
"DDR2_DQ<9>":   PN = "AC74"  !CDS_PN = "AC74";
"DDR2_DQ<10>":   PN = "Y77"  !CDS_PN = "Y77";
"DDR2_DQ<11>":   PN = "W76"  !CDS_PN = "W76";
"DDR2_DQ<12>":   PN = "AF75"  !CDS_PN = "AF75";
"DDR2_DQ<13>":   PN = "AE74"  !CDS_PN = "AE74";
"DDR2_DQ<14>":   PN = "AB77"  !CDS_PN = "AB77";
"DDR2_DQ<15>":   PN = "Y75"  !CDS_PN = "Y75";
"DDR2_DQ<16>":   PN = "W72"  !CDS_PN = "W72";
"DDR2_DQ<17>":   PN = "AA70"  !CDS_PN = "AA70";
"DDR2_DQ<18>":   PN = "R70"  !CDS_PN = "R70";
"DDR2_DQ<19>":   PN = "T69"  !CDS_PN = "T69";
"DDR2_DQ<20>":   PN = "AA72"  !CDS_PN = "AA72";
"DDR2_DQ<21>":   PN = "AB71"  !CDS_PN = "AB71";
"DDR2_DQ<22>":   PN = "T71"  !CDS_PN = "T71";
"DDR2_DQ<23>":   PN = "V69"  !CDS_PN = "V69";
"DDR2_DQ<24>":   PN = "AM67"  !CDS_PN = "AM67";
"DDR2_DQ<25>":   PN = "AT67"  !CDS_PN = "AT67";
"DDR2_DQ<26>":   PN = "AN64"  !CDS_PN = "AN64";
"DDR2_DQ<27>":   PN = "AR64"  !CDS_PN = "AR64";
"DDR2_DQ<28>":   PN = "AN68"  !CDS_PN = "AN68";
"DDR2_DQ<29>":   PN = "AR68"  !CDS_PN = "AR68";
"DDR2_DQ<30>":   PN = "AM65"  !CDS_PN = "AM65";
"DDR2_DQ<31>":   PN = "AT65"  !CDS_PN = "AT65";
"DDR2_DQ<32>":   PN = "U40"  !CDS_PN = "U40";
"DDR2_DQ<33>":   PN = "AA40"  !CDS_PN = "AA40";
"DDR2_DQ<34>":   PN = "V37"  !CDS_PN = "V37";
"DDR2_DQ<35>":   PN = "Y37"  !CDS_PN = "Y37";
"DDR2_DQ<36>":   PN = "V41"  !CDS_PN = "V41";
"DDR2_DQ<37>":   PN = "Y41"  !CDS_PN = "Y41";
"DDR2_DQ<38>":   PN = "U38"  !CDS_PN = "U38";
"DDR2_DQ<39>":   PN = "AA38"  !CDS_PN = "AA38";
"DDR2_DQ<40>":   PN = "U34"  !CDS_PN = "U34";
"DDR2_DQ<41>":   PN = "AA34"  !CDS_PN = "AA34";
"DDR2_DQ<42>":   PN = "V31"  !CDS_PN = "V31";
"DDR2_DQ<43>":   PN = "Y31"  !CDS_PN = "Y31";
"DDR2_DQ<44>":   PN = "V35"  !CDS_PN = "V35";
"DDR2_DQ<45>":   PN = "Y35"  !CDS_PN = "Y35";
"DDR2_DQ<46>":   PN = "U32"  !CDS_PN = "U32";
"DDR2_DQ<47>":   PN = "AA32"  !CDS_PN = "AA32";
"DDR2_DQ<48>":   PN = "AD31"  !CDS_PN = "AD31";
"DDR2_DQ<49>":   PN = "AH31"  !CDS_PN = "AH31";
"DDR2_DQ<50>":   PN = "AE28"  !CDS_PN = "AE28";
"DDR2_DQ<51>":   PN = "AG28"  !CDS_PN = "AG28";
"DDR2_DQ<52>":   PN = "AE32"  !CDS_PN = "AE32";
"DDR2_DQ<53>":   PN = "AG32"  !CDS_PN = "AG32";
"DDR2_DQ<54>":   PN = "AD29"  !CDS_PN = "AD29";
"DDR2_DQ<55>":   PN = "AH29"  !CDS_PN = "AH29";
"DDR2_DQ<56>":   PN = "AD25"  !CDS_PN = "AD25";
"DDR2_DQ<57>":   PN = "AH25"  !CDS_PN = "AH25";
"DDR2_DQ<58>":   PN = "AE22"  !CDS_PN = "AE22";
"DDR2_DQ<59>":   PN = "AG22"  !CDS_PN = "AG22";
"DDR2_DQ<60>":   PN = "AE26"  !CDS_PN = "AE26";
"DDR2_DQ<61>":   PN = "AG26"  !CDS_PN = "AG26";
"DDR2_DQ<62>":   PN = "AD23"  !CDS_PN = "AD23";
"DDR2_DQ<63>":   PN = "AH23"  !CDS_PN = "AH23";
"DDR2_DQS_DN<0>":   PN = "AL74"  !CDS_PN = "AL74";
"DDR2_DQS_DN<1>":   PN = "AA74"  !CDS_PN = "AA74";
"DDR2_DQS_DN<2>":   PN = "Y69"  !CDS_PN = "Y69";
"DDR2_DQS_DN<3>":   PN = "AU66"  !CDS_PN = "AU66";
"DDR2_DQS_DN<4>":   PN = "AB39"  !CDS_PN = "AB39";
"DDR2_DQS_DN<5>":   PN = "AB33"  !CDS_PN = "AB33";
"DDR2_DQS_DN<6>":   PN = "AJ30"  !CDS_PN = "AJ30";
"DDR2_DQS_DN<7>":   PN = "AJ24"  !CDS_PN = "AJ24";
"DDR2_DQS_DN<8>":   PN = "BB71"  !CDS_PN = "BB71";
"DDR2_DQS_DN<9>":   PN = "AP77"  !CDS_PN = "AP77";
"DDR2_DQS_DN<10>":   PN = "AD77"  !CDS_PN = "AD77";
"DDR2_DQS_DN<11>":   PN = "U72"  !CDS_PN = "U72";
"DDR2_DQS_DN<12>":   PN = "AL66"  !CDS_PN = "AL66";
"DDR2_DQS_DN<13>":   PN = "T39"  !CDS_PN = "T39";
"DDR2_DQS_DN<14>":   PN = "T33"  !CDS_PN = "T33";
"DDR2_DQS_DN<15>":   PN = "AC30"  !CDS_PN = "AC30";
"DDR2_DQS_DN<16>":   PN = "AC24"  !CDS_PN = "AC24";
"DDR2_DQS_DN<17>":   PN = "AT71"  !CDS_PN = "AT71";
"DDR2_DQS_DP<0>":   PN = "AM75"  !CDS_PN = "AM75";
"DDR2_DQS_DP<1>":   PN = "AB75"  !CDS_PN = "AB75";
"DDR2_DQS_DP<2>":   PN = "W70"  !CDS_PN = "W70";
"DDR2_DQS_DP<3>":   PN = "AR66"  !CDS_PN = "AR66";
"DDR2_DQS_DP<4>":   PN = "Y39"  !CDS_PN = "Y39";
"DDR2_DQS_DP<5>":   PN = "Y33"  !CDS_PN = "Y33";
"DDR2_DQS_DP<6>":   PN = "AG30"  !CDS_PN = "AG30";
"DDR2_DQS_DP<7>":   PN = "AG24"  !CDS_PN = "AG24";
"DDR2_DQS_DP<8>":   PN = "AY71"  !CDS_PN = "AY71";
"DDR2_DQS_DP<9>":   PN = "AN76"  !CDS_PN = "AN76";
"DDR2_DQS_DP<10>":   PN = "AC76"  !CDS_PN = "AC76";
"DDR2_DQS_DP<11>":   PN = "V71"  !CDS_PN = "V71";
"DDR2_DQS_DP<12>":   PN = "AN66"  !CDS_PN = "AN66";
"DDR2_DQS_DP<13>":   PN = "V39"  !CDS_PN = "V39";
"DDR2_DQS_DP<14>":   PN = "V33"  !CDS_PN = "V33";
"DDR2_DQS_DP<15>":   PN = "AE30"  !CDS_PN = "AE30";
"DDR2_DQS_DP<16>":   PN = "AE24"  !CDS_PN = "AE24";
"DDR2_DQS_DP<17>":   PN = "AV71"  !CDS_PN = "AV71";
"DDR2_ECC<0>":   PN = "AU72"  !CDS_PN = "AU72";
"DDR2_ECC<1>":   PN = "BA72"  !CDS_PN = "BA72";
"DDR2_ECC<2>":   PN = "AV69"  !CDS_PN = "AV69";
"DDR2_ECC<3>":   PN = "AY69"  !CDS_PN = "AY69";
"DDR2_ECC<4>":   PN = "AV73"  !CDS_PN = "AV73";
"DDR2_ECC<5>":   PN = "AY73"  !CDS_PN = "AY73";
"DDR2_ECC<6>":   PN = "AU70"  !CDS_PN = "AU70";
"DDR2_ECC<7>":   PN = "BA70"  !CDS_PN = "BA70";
"DDR2_MA<0>":   PN = "AB53"  !CDS_PN = "AB53";
"DDR2_MA<1>":   PN = "AE58"  !CDS_PN = "AE58";
"DDR2_MA<2>":   PN = "AD57"  !CDS_PN = "AD57";
"DDR2_MA<3>":   PN = "W58"  !CDS_PN = "W58";
"DDR2_MA<4>":   PN = "AA58"  !CDS_PN = "AA58";
"DDR2_MA<5>":   PN = "V59"  !CDS_PN = "V59";
"DDR2_MA<6>":   PN = "AB59"  !CDS_PN = "AB59";
"DDR2_MA<7>":   PN = "AE60"  !CDS_PN = "AE60";
"DDR2_MA<8>":   PN = "AD59"  !CDS_PN = "AD59";
"DDR2_MA<9>":   PN = "AG58"  !CDS_PN = "AG58";
"DDR2_MA<10>":   PN = "AD55"  !CDS_PN = "AD55";
"DDR2_MA<11>":   PN = "AG60"  !CDS_PN = "AG60";
"DDR2_MA<12>":   PN = "AG62"  !CDS_PN = "AG62";
"DDR2_MA<13>":   PN = "AD53"  !CDS_PN = "AD53";
"DDR2_MA<14>":   PN = "W50"  !CDS_PN = "W50";
"DDR2_MA<15>":   PN = "AE54"  !CDS_PN = "AE54";
"DDR2_MA<16>":   PN = "AA52"  !CDS_PN = "AA52";
"DDR2_MA<17>":   PN = "AC46"  !CDS_PN = "AC46";
"DDR2_ODT<0>":   PN = "AA50"  !CDS_PN = "AA50";
"DDR2_ODT<1>":   PN = "AA48"  !CDS_PN = "AA48";
"DDR2_ODT<2>":   PN = "V49"  !CDS_PN = "V49";
"DDR2_ODT<3>":   PN = "AB47"  !CDS_PN = "AB47";
"DDR2_PAR":   PN = "V53"  !CDS_PN = "V53";
DRAWING = "@baseboard_fab2_lib.baseboard_fab2(sch_1):page60";
BODY = "SKX_EXT_B","I172": #LOCATION = "U2D1" !CDS_LOCATION = "U2D1" #SEC = "6" !CDS_SEC = "6";
"DDR3_ACT_N":   PN = "DW60"  !CDS_PN = "DW60";
"DDR3_ALERT_N":   PN = "ED63"  !CDS_PN = "ED63";
"DDR3_BA<0>":   PN = "EE52"  !CDS_PN = "EE52";
"DDR3_BA<1>":   PN = "EA54"  !CDS_PN = "EA54";
"DDR3_BG<0>":   PN = "ED61"  !CDS_PN = "ED61";
"DDR3_BG<1>":   PN = "DW62"  !CDS_PN = "DW62";
"DDR3_CID<2>":   PN = "DV47"  !CDS_PN = "DV47";
"DDR3_CKE<0>":   PN = "EE62"  !CDS_PN = "EE62";
"DDR3_CKE<1>":   PN = "EF63"  !CDS_PN = "EF63";
"DDR3_CKE<2>":   PN = "EA62"  !CDS_PN = "EA62";
"DDR3_CKE<3>":   PN = "EB63"  !CDS_PN = "EB63";
"DDR3_CLK_DN<0>":   PN = "ED55"  !CDS_PN = "ED55";
"DDR3_CLK_DN<1>":   PN = "EF55"  !CDS_PN = "EF55";
"DDR3_CLK_DN<2>":   PN = "DW56"  !CDS_PN = "DW56";
"DDR3_CLK_DN<3>":   PN = "EF57"  !CDS_PN = "EF57";
"DDR3_CLK_DP<0>":   PN = "EB55"  !CDS_PN = "EB55";
"DDR3_CLK_DP<1>":   PN = "EE54"  !CDS_PN = "EE54";
"DDR3_CLK_DP<2>":   PN = "EA56"  !CDS_PN = "EA56";
"DDR3_CLK_DP<3>":   PN = "EE56"  !CDS_PN = "EE56";
"DDR3_CS<0>_N":   PN = "EF51"  !CDS_PN = "EF51";
"DDR3_CS<1>_N":   PN = "ED49"  !CDS_PN = "ED49";
"DDR3_CS<2>_N":   PN = "ED47"  !CDS_PN = "ED47";
"DDR3_CS<3>_N":   PN = "EB47"  !CDS_PN = "EB47";
"DDR3_CS<4>_N":   PN = "EB51"  !CDS_PN = "EB51";
"DDR3_CS<5>_N":   PN = "EB49"  !CDS_PN = "EB49";
"DDR3_CS<6>_N":   PN = "DV45"  !CDS_PN = "DV45";
"DDR3_CS<7>_N":   PN = "EB45"  !CDS_PN = "EB45";
"DDR3_DQ<0>":   PN = "CN84"  !CDS_PN = "CN84";
"DDR3_DQ<1>":   PN = "CN86"  !CDS_PN = "CN86";
"DDR3_DQ<2>":   PN = "DA86"  !CDS_PN = "DA86";
"DDR3_DQ<3>":   PN = "DA84"  !CDS_PN = "DA84";
"DDR3_DQ<4>":   PN = "CL84"  !CDS_PN = "CL84";
"DDR3_DQ<5>":   PN = "CL86"  !CDS_PN = "CL86";
"DDR3_DQ<6>":   PN = "CW86"  !CDS_PN = "CW86";
"DDR3_DQ<7>":   PN = "CW84"  !CDS_PN = "CW84";
"DDR3_DQ<8>":   PN = "DG84"  !CDS_PN = "DG84";
"DDR3_DQ<9>":   PN = "DH85"  !CDS_PN = "DH85";
"DDR3_DQ<10>":   PN = "DV83"  !CDS_PN = "DV83";
"DDR3_DQ<11>":   PN = "DY83"  !CDS_PN = "DY83";
"DDR3_DQ<12>":   PN = "DD85"  !CDS_PN = "DD85";
"DDR3_DQ<13>":   PN = "DE84"  !CDS_PN = "DE84";
"DDR3_DQ<14>":   PN = "DR84"  !CDS_PN = "DR84";
"DDR3_DQ<15>":   PN = "DV85"  !CDS_PN = "DV85";
"DDR3_DQ<16>":   PN = "DM79"  !CDS_PN = "DM79";
"DDR3_DQ<17>":   PN = "DK81"  !CDS_PN = "DK81";
"DDR3_DQ<18>":   PN = "DT81"  !CDS_PN = "DT81";
"DDR3_DQ<19>":   PN = "DR82"  !CDS_PN = "DR82";
"DDR3_DQ<20>":   PN = "DK79"  !CDS_PN = "DK79";
"DDR3_DQ<21>":   PN = "DJ80"  !CDS_PN = "DJ80";
"DDR3_DQ<22>":   PN = "DR80"  !CDS_PN = "DR80";
"DDR3_DQ<23>":   PN = "DN82"  !CDS_PN = "DN82";
"DDR3_DQ<24>":   PN = "DN76"  !CDS_PN = "DN76";
"DDR3_DQ<25>":   PN = "DU76"  !CDS_PN = "DU76";
"DDR3_DQ<26>":   PN = "DP73"  !CDS_PN = "DP73";
"DDR3_DQ<27>":   PN = "DT73"  !CDS_PN = "DT73";
"DDR3_DQ<28>":   PN = "DP77"  !CDS_PN = "DP77";
"DDR3_DQ<29>":   PN = "DT77"  !CDS_PN = "DT77";
"DDR3_DQ<30>":   PN = "DN74"  !CDS_PN = "DN74";
"DDR3_DQ<31>":   PN = "DU74"  !CDS_PN = "DU74";
"DDR3_DQ<32>":   PN = "EC40"  !CDS_PN = "EC40";
"DDR3_DQ<33>":   PN = "ED39"  !CDS_PN = "ED39";
"DDR3_DQ<34>":   PN = "EA36"  !CDS_PN = "EA36";
"DDR3_DQ<35>":   PN = "EC36"  !CDS_PN = "EC36";
"DDR3_DQ<36>":   PN = "DY39"  !CDS_PN = "DY39";
"DDR3_DQ<37>":   PN = "EA40"  !CDS_PN = "EA40";
"DDR3_DQ<38>":   PN = "DY37"  !CDS_PN = "DY37";
"DDR3_DQ<39>":   PN = "ED37"  !CDS_PN = "ED37";
"DDR3_DQ<40>":   PN = "DN36"  !CDS_PN = "DN36";
"DDR3_DQ<41>":   PN = "DU36"  !CDS_PN = "DU36";
"DDR3_DQ<42>":   PN = "DP33"  !CDS_PN = "DP33";
"DDR3_DQ<43>":   PN = "DT33"  !CDS_PN = "DT33";
"DDR3_DQ<44>":   PN = "DP37"  !CDS_PN = "DP37";
"DDR3_DQ<45>":   PN = "DT37"  !CDS_PN = "DT37";
"DDR3_DQ<46>":   PN = "DN34"  !CDS_PN = "DN34";
"DDR3_DQ<47>":   PN = "DU34"  !CDS_PN = "DU34";
"DDR3_DQ<48>":   PN = "DN30"  !CDS_PN = "DN30";
"DDR3_DQ<49>":   PN = "DU30"  !CDS_PN = "DU30";
"DDR3_DQ<50>":   PN = "DP27"  !CDS_PN = "DP27";
"DDR3_DQ<51>":   PN = "DT27"  !CDS_PN = "DT27";
"DDR3_DQ<52>":   PN = "DP31"  !CDS_PN = "DP31";
"DDR3_DQ<53>":   PN = "DT31"  !CDS_PN = "DT31";
"DDR3_DQ<54>":   PN = "DN28"  !CDS_PN = "DN28";
"DDR3_DQ<55>":   PN = "DU28"  !CDS_PN = "DU28";
"DDR3_DQ<56>":   PN = "DN24"  !CDS_PN = "DN24";
"DDR3_DQ<57>":   PN = "DU24"  !CDS_PN = "DU24";
"DDR3_DQ<58>":   PN = "DY21"  !CDS_PN = "DY21";
"DDR3_DQ<59>":   PN = "EB21"  !CDS_PN = "EB21";
"DDR3_DQ<60>":   PN = "DP25"  !CDS_PN = "DP25";
"DDR3_DQ<61>":   PN = "DT25"  !CDS_PN = "DT25";
"DDR3_DQ<62>":   PN = "EC22"  !CDS_PN = "EC22";
"DDR3_DQ<63>":   PN = "DW22"  !CDS_PN = "DW22";
"DDR3_DQS_DN<0>":   PN = "CU84"  !CDS_PN = "CU84";
"DDR3_DQS_DN<1>":   PN = "DN84"  !CDS_PN = "DN84";
"DDR3_DQS_DN<2>":   PN = "DL82"  !CDS_PN = "DL82";
"DDR3_DQS_DN<3>":   PN = "DV75"  !CDS_PN = "DV75";
"DDR3_DQS_DN<4>":   PN = "EE38"  !CDS_PN = "EE38";
"DDR3_DQS_DN<5>":   PN = "DV35"  !CDS_PN = "DV35";
"DDR3_DQS_DN<6>":   PN = "DV29"  !CDS_PN = "DV29";
"DDR3_DQS_DN<7>":   PN = "DV23"  !CDS_PN = "DV23";
"DDR3_DQS_DN<8>":   PN = "DF67"  !CDS_PN = "DF67";
"DDR3_DQS_DN<9>":   PN = "CR84"  !CDS_PN = "CR84";
"DDR3_DQS_DN<10>":   PN = "DM85"  !CDS_PN = "DM85";
"DDR3_DQS_DN<11>":   PN = "DN80"  !CDS_PN = "DN80";
"DDR3_DQS_DN<12>":   PN = "DP75"  !CDS_PN = "DP75";
"DDR3_DQS_DN<13>":   PN = "EA38"  !CDS_PN = "EA38";
"DDR3_DQS_DN<14>":   PN = "DP35"  !CDS_PN = "DP35";
"DDR3_DQS_DN<15>":   PN = "DM29"  !CDS_PN = "DM29";
"DDR3_DQS_DN<16>":   PN = "DM23"  !CDS_PN = "DM23";
"DDR3_DQS_DN<17>":   PN = "DB67"  !CDS_PN = "DB67";
"DDR3_DQS_DP<0>":   PN = "CV85"  !CDS_PN = "CV85";
"DDR3_DQS_DP<1>":   PN = "DP85"  !CDS_PN = "DP85";
"DDR3_DQS_DP<2>":   PN = "DM81"  !CDS_PN = "DM81";
"DDR3_DQS_DP<3>":   PN = "DT75"  !CDS_PN = "DT75";
"DDR3_DQS_DP<4>":   PN = "EC38"  !CDS_PN = "EC38";
"DDR3_DQS_DP<5>":   PN = "DT35"  !CDS_PN = "DT35";
"DDR3_DQS_DP<6>":   PN = "DT29"  !CDS_PN = "DT29";
"DDR3_DQS_DP<7>":   PN = "DT23"  !CDS_PN = "DT23";
"DDR3_DQS_DP<8>":   PN = "DD67"  !CDS_PN = "DD67";
"DDR3_DQS_DP<9>":   PN = "CP85"  !CDS_PN = "CP85";
"DDR3_DQS_DP<10>":   PN = "DL84"  !CDS_PN = "DL84";
"DDR3_DQS_DP<11>":   PN = "DP79"  !CDS_PN = "DP79";
"DDR3_DQS_DP<12>":   PN = "DM75"  !CDS_PN = "DM75";
"DDR3_DQS_DP<13>":   PN = "DW38"  !CDS_PN = "DW38";
"DDR3_DQS_DP<14>":   PN = "DM35"  !CDS_PN = "DM35";
"DDR3_DQS_DP<15>":   PN = "DP29"  !CDS_PN = "DP29";
"DDR3_DQS_DP<16>":   PN = "DP23"  !CDS_PN = "DP23";
"DDR3_DQS_DP<17>":   PN = "CY67"  !CDS_PN = "CY67";
"DDR3_ECC<0>":   PN = "DA68"  !CDS_PN = "DA68";
"DDR3_ECC<1>":   PN = "DE68"  !CDS_PN = "DE68";
"DDR3_ECC<2>":   PN = "DB65"  !CDS_PN = "DB65";
"DDR3_ECC<3>":   PN = "DD65"  !CDS_PN = "DD65";
"DDR3_ECC<4>":   PN = "DB69"  !CDS_PN = "DB69";
"DDR3_ECC<5>":   PN = "DD69"  !CDS_PN = "DD69";
"DDR3_ECC<6>":   PN = "DA66"  !CDS_PN = "DA66";
"DDR3_ECC<7>":   PN = "DE66"  !CDS_PN = "DE66";
"DDR3_MA<0>":   PN = "EB53"  !CDS_PN = "EB53";
"DDR3_MA<1>":   PN = "ED57"  !CDS_PN = "ED57";
"DDR3_MA<2>":   PN = "EE58"  !CDS_PN = "EE58";
"DDR3_MA<3>":   PN = "EB57"  !CDS_PN = "EB57";
"DDR3_MA<4>":   PN = "ED59"  !CDS_PN = "ED59";
"DDR3_MA<5>":   PN = "EA58"  !CDS_PN = "EA58";
"DDR3_MA<6>":   PN = "EE60"  !CDS_PN = "EE60";
"DDR3_MA<7>":   PN = "EA60"  !CDS_PN = "EA60";
"DDR3_MA<8>":   PN = "EB59"  !CDS_PN = "EB59";
"DDR3_MA<9>":   PN = "EF61"  !CDS_PN = "EF61";
"DDR3_MA<10>":   PN = "DW54"  !CDS_PN = "DW54";
"DDR3_MA<11>":   PN = "EB61"  !CDS_PN = "EB61";
"DDR3_MA<12>":   PN = "DT63"  !CDS_PN = "DT63";
"DDR3_MA<13>":   PN = "DW48"  !CDS_PN = "DW48";
"DDR3_MA<14>":   PN = "ED51"  !CDS_PN = "ED51";
"DDR3_MA<15>":   PN = "DV49"  !CDS_PN = "DV49";
"DDR3_MA<16>":   PN = "EA52"  !CDS_PN = "EA52";
"DDR3_MA<17>":   PN = "EA46"  !CDS_PN = "EA46";
"DDR3_ODT<0>":   PN = "EE50"  !CDS_PN = "EE50";
"DDR3_ODT<1>":   PN = "EE48"  !CDS_PN = "EE48";
"DDR3_ODT<2>":   PN = "EA50"  !CDS_PN = "EA50";
"DDR3_ODT<3>":   PN = "EA48"  !CDS_PN = "EA48";
"DDR3_PAR":   PN = "ED53"  !CDS_PN = "ED53";
DRAWING = "@baseboard_fab2_lib.baseboard_fab2(sch_1):page61";
BODY = "SKX_EXT_B","I172": #LOCATION = "U2D1" !CDS_LOCATION = "U2D1" #SEC = "7" !CDS_SEC = "7";
"DDR4_ACT_N":   PN = "DR62"  !CDS_PN = "DR62";
"DDR4_ALERT_N":   PN = "DT61"  !CDS_PN = "DT61";
"DDR4_BA<0>":   PN = "DM53"  !CDS_PN = "DM53";
"DDR4_BA<1>":   PN = "DV55"  !CDS_PN = "DV55";
"DDR4_BG<0>":   PN = "DJ62"  !CDS_PN = "DJ62";
"DDR4_BG<1>":   PN = "DM61"  !CDS_PN = "DM61";
"DDR4_CID<2>":   PN = "DT47"  !CDS_PN = "DT47";
"DDR4_CKE<0>":   PN = "DM63"  !CDS_PN = "DM63";
"DDR4_CKE<1>":   PN = "DN64"  !CDS_PN = "DN64";
"DDR4_CKE<2>":   PN = "DL64"  !CDS_PN = "DL64";
"DDR4_CKE<3>":   PN = "DR64"  !CDS_PN = "DR64";
"DDR4_CLK_DN<0>":   PN = "DM55"  !CDS_PN = "DM55";
"DDR4_CLK_DN<1>":   PN = "DR54"  !CDS_PN = "DR54";
"DDR4_CLK_DN<2>":   PN = "DM57"  !CDS_PN = "DM57";
"DDR4_CLK_DN<3>":   PN = "DT57"  !CDS_PN = "DT57";
"DDR4_CLK_DP<0>":   PN = "DN54"  !CDS_PN = "DN54";
"DDR4_CLK_DP<1>":   PN = "DT53"  !CDS_PN = "DT53";
"DDR4_CLK_DP<2>":   PN = "DN56"  !CDS_PN = "DN56";
"DDR4_CLK_DP<3>":   PN = "DR56"  !CDS_PN = "DR56";
"DDR4_CS<0>_N":   PN = "DV51"  !CDS_PN = "DV51";
"DDR4_CS<1>_N":   PN = "DN50"  !CDS_PN = "DN50";
"DDR4_CS<2>_N":   PN = "DR46"  !CDS_PN = "DR46";
"DDR4_CS<3>_N":   PN = "DK47"  !CDS_PN = "DK47";
"DDR4_CS<4>_N":   PN = "DW50"  !CDS_PN = "DW50";
"DDR4_CS<5>_N":   PN = "DM49"  !CDS_PN = "DM49";
"DDR4_CS<6>_N":   PN = "DT45"  !CDS_PN = "DT45";
"DDR4_CS<7>_N":   PN = "DN46"  !CDS_PN = "DN46";
"DDR4_DQ<0>":   PN = "CM79"  !CDS_PN = "CM79";
"DDR4_DQ<1>":   PN = "CK81"  !CDS_PN = "CK81";
"DDR4_DQ<2>":   PN = "CT81"  !CDS_PN = "CT81";
"DDR4_DQ<3>":   PN = "CR82"  !CDS_PN = "CR82";
"DDR4_DQ<4>":   PN = "CK79"  !CDS_PN = "CK79";
"DDR4_DQ<5>":   PN = "CJ80"  !CDS_PN = "CJ80";
"DDR4_DQ<6>":   PN = "CR80"  !CDS_PN = "CR80";
"DDR4_DQ<7>":   PN = "CN82"  !CDS_PN = "CN82";
"DDR4_DQ<8>":   PN = "DB79"  !CDS_PN = "DB79";
"DDR4_DQ<9>":   PN = "CY81"  !CDS_PN = "CY81";
"DDR4_DQ<10>":   PN = "DE80"  !CDS_PN = "DE80";
"DDR4_DQ<11>":   PN = "DF81"  !CDS_PN = "DF81";
"DDR4_DQ<12>":   PN = "CY79"  !CDS_PN = "CY79";
"DDR4_DQ<13>":   PN = "CW80"  !CDS_PN = "CW80";
"DDR4_DQ<14>":   PN = "DC82"  !CDS_PN = "DC82";
"DDR4_DQ<15>":   PN = "DE82"  !CDS_PN = "DE82";
"DDR4_DQ<16>":   PN = "DW80"  !CDS_PN = "DW80";
"DDR4_DQ<17>":   PN = "EC80"  !CDS_PN = "EC80";
"DDR4_DQ<18>":   PN = "DY77"  !CDS_PN = "DY77";
"DDR4_DQ<19>":   PN = "EB77"  !CDS_PN = "EB77";
"DDR4_DQ<20>":   PN = "DY81"  !CDS_PN = "DY81";
"DDR4_DQ<21>":   PN = "EB81"  !CDS_PN = "EB81";
"DDR4_DQ<22>":   PN = "DW78"  !CDS_PN = "DW78";
"DDR4_DQ<23>":   PN = "EC78"  !CDS_PN = "EC78";
"DDR4_DQ<24>":   PN = "ED75"  !CDS_PN = "ED75";
"DDR4_DQ<25>":   PN = "EE74"  !CDS_PN = "EE74";
"DDR4_DQ<26>":   PN = "EB71"  !CDS_PN = "EB71";
"DDR4_DQ<27>":   PN = "ED71"  !CDS_PN = "ED71";
"DDR4_DQ<28>":   PN = "EA74"  !CDS_PN = "EA74";
"DDR4_DQ<29>":   PN = "EB75"  !CDS_PN = "EB75";
"DDR4_DQ<30>":   PN = "EA72"  !CDS_PN = "EA72";
"DDR4_DQ<31>":   PN = "EE72"  !CDS_PN = "EE72";
"DDR4_DQ<32>":   PN = "DU42"  !CDS_PN = "DU42";
"DDR4_DQ<33>":   PN = "DW42"  !CDS_PN = "DW42";
"DDR4_DQ<34>":   PN = "DP39"  !CDS_PN = "DP39";
"DDR4_DQ<35>":   PN = "DT39"  !CDS_PN = "DT39";
"DDR4_DQ<36>":   PN = "DL42"  !CDS_PN = "DL42";
"DDR4_DQ<37>":   PN = "DN42"  !CDS_PN = "DN42";
"DDR4_DQ<38>":   PN = "DN40"  !CDS_PN = "DN40";
"DDR4_DQ<39>":   PN = "DU40"  !CDS_PN = "DU40";
"DDR4_DQ<40>":   PN = "EC34"  !CDS_PN = "EC34";
"DDR4_DQ<41>":   PN = "ED33"  !CDS_PN = "ED33";
"DDR4_DQ<42>":   PN = "EA30"  !CDS_PN = "EA30";
"DDR4_DQ<43>":   PN = "EC30"  !CDS_PN = "EC30";
"DDR4_DQ<44>":   PN = "DY33"  !CDS_PN = "DY33";
"DDR4_DQ<45>":   PN = "EA34"  !CDS_PN = "EA34";
"DDR4_DQ<46>":   PN = "DY31"  !CDS_PN = "DY31";
"DDR4_DQ<47>":   PN = "ED31"  !CDS_PN = "ED31";
"DDR4_DQ<48>":   PN = "EC28"  !CDS_PN = "EC28";
"DDR4_DQ<49>":   PN = "ED27"  !CDS_PN = "ED27";
"DDR4_DQ<50>":   PN = "EA24"  !CDS_PN = "EA24";
"DDR4_DQ<51>":   PN = "EC24"  !CDS_PN = "EC24";
"DDR4_DQ<52>":   PN = "DY27"  !CDS_PN = "DY27";
"DDR4_DQ<53>":   PN = "EA28"  !CDS_PN = "EA28";
"DDR4_DQ<54>":   PN = "DY25"  !CDS_PN = "DY25";
"DDR4_DQ<55>":   PN = "ED25"  !CDS_PN = "ED25";
"DDR4_DQ<56>":   PN = "DF27"  !CDS_PN = "DF27";
"DDR4_DQ<57>":   PN = "DK27"  !CDS_PN = "DK27";
"DDR4_DQ<58>":   PN = "DD25"  !CDS_PN = "DD25";
"DDR4_DQ<59>":   PN = "DJ24"  !CDS_PN = "DJ24";
"DDR4_DQ<60>":   PN = "DG28"  !CDS_PN = "DG28";
"DDR4_DQ<61>":   PN = "DJ28"  !CDS_PN = "DJ28";
"DDR4_DQ<62>":   PN = "DF25"  !CDS_PN = "DF25";
"DDR4_DQ<63>":   PN = "DK25"  !CDS_PN = "DK25";
"DDR4_DQS_DN<0>":   PN = "CL82"  !CDS_PN = "CL82";
"DDR4_DQS_DN<1>":   PN = "DA82"  !CDS_PN = "DA82";
"DDR4_DQS_DN<2>":   PN = "ED79"  !CDS_PN = "ED79";
"DDR4_DQS_DN<3>":   PN = "EF73"  !CDS_PN = "EF73";
"DDR4_DQS_DN<4>":   PN = "DV41"  !CDS_PN = "DV41";
"DDR4_DQS_DN<5>":   PN = "EE32"  !CDS_PN = "EE32";
"DDR4_DQS_DN<6>":   PN = "EE26"  !CDS_PN = "EE26";
"DDR4_DQS_DN<7>":   PN = "DL26"  !CDS_PN = "DL26";
"DDR4_DQS_DN<8>":   PN = "EB67"  !CDS_PN = "EB67";
"DDR4_DQS_DN<9>":   PN = "CN80"  !CDS_PN = "CN80";
"DDR4_DQS_DN<10>":   PN = "DC80"  !CDS_PN = "DC80";
"DDR4_DQS_DN<11>":   PN = "DY79"  !CDS_PN = "DY79";
"DDR4_DQS_DN<12>":   PN = "EB73"  !CDS_PN = "EB73";
"DDR4_DQS_DN<13>":   PN = "DP41"  !CDS_PN = "DP41";
"DDR4_DQS_DN<14>":   PN = "EA32"  !CDS_PN = "EA32";
"DDR4_DQS_DN<15>":   PN = "EA26"  !CDS_PN = "EA26";
"DDR4_DQS_DN<16>":   PN = "DG26"  !CDS_PN = "DG26";
"DDR4_DQS_DN<17>":   PN = "DV67"  !CDS_PN = "DV67";
"DDR4_DQS_DP<0>":   PN = "CM81"  !CDS_PN = "CM81";
"DDR4_DQS_DP<1>":   PN = "DB81"  !CDS_PN = "DB81";
"DDR4_DQS_DP<2>":   PN = "EB79"  !CDS_PN = "EB79";
"DDR4_DQS_DP<3>":   PN = "ED73"  !CDS_PN = "ED73";
"DDR4_DQS_DP<4>":   PN = "DT41"  !CDS_PN = "DT41";
"DDR4_DQS_DP<5>":   PN = "EC32"  !CDS_PN = "EC32";
"DDR4_DQS_DP<6>":   PN = "EC26"  !CDS_PN = "EC26";
"DDR4_DQS_DP<7>":   PN = "DJ26"  !CDS_PN = "DJ26";
"DDR4_DQS_DP<8>":   PN = "DY67"  !CDS_PN = "DY67";
"DDR4_DQS_DP<9>":   PN = "CP79"  !CDS_PN = "CP79";
"DDR4_DQS_DP<10>":   PN = "DD79"  !CDS_PN = "DD79";
"DDR4_DQS_DP<11>":   PN = "DV79"  !CDS_PN = "DV79";
"DDR4_DQS_DP<12>":   PN = "DY73"  !CDS_PN = "DY73";
"DDR4_DQS_DP<13>":   PN = "DM41"  !CDS_PN = "DM41";
"DDR4_DQS_DP<14>":   PN = "DW32"  !CDS_PN = "DW32";
"DDR4_DQS_DP<15>":   PN = "DW26"  !CDS_PN = "DW26";
"DDR4_DQS_DP<16>":   PN = "DE26"  !CDS_PN = "DE26";
"DDR4_DQS_DP<17>":   PN = "DT67"  !CDS_PN = "DT67";
"DDR4_ECC<0>":   PN = "DY69"  !CDS_PN = "DY69";
"DDR4_ECC<1>":   PN = "EA68"  !CDS_PN = "EA68";
"DDR4_ECC<2>":   PN = "DV65"  !CDS_PN = "DV65";
"DDR4_ECC<3>":   PN = "DY65"  !CDS_PN = "DY65";
"DDR4_ECC<4>":   PN = "DU68"  !CDS_PN = "DU68";
"DDR4_ECC<5>":   PN = "DV69"  !CDS_PN = "DV69";
"DDR4_ECC<6>":   PN = "DU66"  !CDS_PN = "DU66";
"DDR4_ECC<7>":   PN = "EA66"  !CDS_PN = "EA66";
"DDR4_MA<0>":   PN = "DW52"  !CDS_PN = "DW52";
"DDR4_MA<1>":   PN = "DW58"  !CDS_PN = "DW58";
"DDR4_MA<2>":   PN = "DV57"  !CDS_PN = "DV57";
"DDR4_MA<3>":   PN = "DR58"  !CDS_PN = "DR58";
"DDR4_MA<4>":   PN = "DT59"  !CDS_PN = "DT59";
"DDR4_MA<5>":   PN = "DN58"  !CDS_PN = "DN58";
"DDR4_MA<6>":   PN = "DM59"  !CDS_PN = "DM59";
"DDR4_MA<7>":   PN = "DK61"  !CDS_PN = "DK61";
"DDR4_MA<8>":   PN = "DJ60"  !CDS_PN = "DJ60";
"DDR4_MA<9>":   PN = "DV59"  !CDS_PN = "DV59";
"DDR4_MA<10>":   PN = "DT55"  !CDS_PN = "DT55";
"DDR4_MA<11>":   PN = "DR60"  !CDS_PN = "DR60";
"DDR4_MA<12>":   PN = "DN60"  !CDS_PN = "DN60";
"DDR4_MA<13>":   PN = "DT51"  !CDS_PN = "DT51";
"DDR4_MA<14>":   PN = "DM51"  !CDS_PN = "DM51";
"DDR4_MA<15>":   PN = "DR52"  !CDS_PN = "DR52";
"DDR4_MA<16>":   PN = "DN52"  !CDS_PN = "DN52";
"DDR4_MA<17>":   PN = "DR48"  !CDS_PN = "DR48";
"DDR4_ODT<0>":   PN = "DR50"  !CDS_PN = "DR50";
"DDR4_ODT<1>":   PN = "DN48"  !CDS_PN = "DN48";
"DDR4_ODT<2>":   PN = "DT49"  !CDS_PN = "DT49";
"DDR4_ODT<3>":   PN = "DM47"  !CDS_PN = "DM47";
"DDR4_PAR":   PN = "DV53"  !CDS_PN = "DV53";
DRAWING = "@baseboard_fab2_lib.baseboard_fab2(sch_1):page62";
BODY = "SKX_EXT_B","I172": #LOCATION = "U2D1" !CDS_LOCATION = "U2D1" #SEC = "8" !CDS_SEC = "8";
"DDR5_ACT_N":   PN = "DC62"  !CDS_PN = "DC62";
"DDR5_ALERT_N":   PN = "DD61"  !CDS_PN = "DD61";
"DDR5_BA<0>":   PN = "DJ52"  !CDS_PN = "DJ52";
"DDR5_BA<1>":   PN = "DC56"  !CDS_PN = "DC56";
"DDR5_BG<0>":   PN = "DA62"  !CDS_PN = "DA62";
"DDR5_BG<1>":   PN = "DF61"  !CDS_PN = "DF61";
"DDR5_CID<2>":   PN = "DF45"  !CDS_PN = "DF45";
"DDR5_CKE<0>":   PN = "DG62"  !CDS_PN = "DG62";
"DDR5_CKE<1>":   PN = "DD63"  !CDS_PN = "DD63";
"DDR5_CKE<2>":   PN = "DK63"  !CDS_PN = "DK63";
"DDR5_CKE<3>":   PN = "DF63"  !CDS_PN = "DF63";
"DDR5_CLK_DN<0>":   PN = "DK55"  !CDS_PN = "DK55";
"DDR5_CLK_DN<1>":   PN = "DF55"  !CDS_PN = "DF55";
"DDR5_CLK_DN<2>":   PN = "DK57"  !CDS_PN = "DK57";
"DDR5_CLK_DN<3>":   PN = "DF57"  !CDS_PN = "DF57";
"DDR5_CLK_DP<0>":   PN = "DJ54"  !CDS_PN = "DJ54";
"DDR5_CLK_DP<1>":   PN = "DG54"  !CDS_PN = "DG54";
"DDR5_CLK_DP<2>":   PN = "DJ56"  !CDS_PN = "DJ56";
"DDR5_CLK_DP<3>":   PN = "DG56"  !CDS_PN = "DG56";
"DDR5_CS<0>_N":   PN = "DK51"  !CDS_PN = "DK51";
"DDR5_CS<1>_N":   PN = "DF49"  !CDS_PN = "DF49";
"DDR5_CS<2>_N":   PN = "DJ46"  !CDS_PN = "DJ46";
"DDR5_CS<3>_N":   PN = "DG46"  !CDS_PN = "DG46";
"DDR5_CS<4>_N":   PN = "DF51"  !CDS_PN = "DF51";
"DDR5_CS<5>_N":   PN = "DJ48"  !CDS_PN = "DJ48";
"DDR5_CS<6>_N":   PN = "DM45"  !CDS_PN = "DM45";
"DDR5_CS<7>_N":   PN = "DK45"  !CDS_PN = "DK45";
"DDR5_DQ<0>":   PN = "CR74"  !CDS_PN = "CR74";
"DDR5_DQ<1>":   PN = "CN76"  !CDS_PN = "CN76";
"DDR5_DQ<2>":   PN = "CW76"  !CDS_PN = "CW76";
"DDR5_DQ<3>":   PN = "CV77"  !CDS_PN = "CV77";
"DDR5_DQ<4>":   PN = "CN74"  !CDS_PN = "CN74";
"DDR5_DQ<5>":   PN = "CM75"  !CDS_PN = "CM75";
"DDR5_DQ<6>":   PN = "CV75"  !CDS_PN = "CV75";
"DDR5_DQ<7>":   PN = "CT77"  !CDS_PN = "CT77";
"DDR5_DQ<8>":   PN = "DE74"  !CDS_PN = "DE74";
"DDR5_DQ<9>":   PN = "DC76"  !CDS_PN = "DC76";
"DDR5_DQ<10>":   PN = "DH75"  !CDS_PN = "DH75";
"DDR5_DQ<11>":   PN = "DJ76"  !CDS_PN = "DJ76";
"DDR5_DQ<12>":   PN = "DC74"  !CDS_PN = "DC74";
"DDR5_DQ<13>":   PN = "DB75"  !CDS_PN = "DB75";
"DDR5_DQ<14>":   PN = "DF77"  !CDS_PN = "DF77";
"DDR5_DQ<15>":   PN = "DH77"  !CDS_PN = "DH77";
"DDR5_DQ<16>":   PN = "DG70"  !CDS_PN = "DG70";
"DDR5_DQ<17>":   PN = "DJ72"  !CDS_PN = "DJ72";
"DDR5_DQ<18>":   PN = "DM69"  !CDS_PN = "DM69";
"DDR5_DQ<19>":   PN = "DN70"  !CDS_PN = "DN70";
"DDR5_DQ<20>":   PN = "DF71"  !CDS_PN = "DF71";
"DDR5_DQ<21>":   PN = "DG72"  !CDS_PN = "DG72";
"DDR5_DQ<22>":   PN = "DK69"  !CDS_PN = "DK69";
"DDR5_DQ<23>":   PN = "DM71"  !CDS_PN = "DM71";
"DDR5_DQ<24>":   PN = "CN66"  !CDS_PN = "CN66";
"DDR5_DQ<25>":   PN = "CU66"  !CDS_PN = "CU66";
"DDR5_DQ<26>":   PN = "CP63"  !CDS_PN = "CP63";
"DDR5_DQ<27>":   PN = "CT63"  !CDS_PN = "CT63";
"DDR5_DQ<28>":   PN = "CP67"  !CDS_PN = "CP67";
"DDR5_DQ<29>":   PN = "CT67"  !CDS_PN = "CT67";
"DDR5_DQ<30>":   PN = "CN64"  !CDS_PN = "CN64";
"DDR5_DQ<31>":   PN = "CU64"  !CDS_PN = "CU64";
"DDR5_DQ<32>":   PN = "DD41"  !CDS_PN = "DD41";
"DDR5_DQ<33>":   PN = "DG42"  !CDS_PN = "DG42";
"DDR5_DQ<34>":   PN = "DE38"  !CDS_PN = "DE38";
"DDR5_DQ<35>":   PN = "DG38"  !CDS_PN = "DG38";
"DDR5_DQ<36>":   PN = "DA42"  !CDS_PN = "DA42";
"DDR5_DQ<37>":   PN = "DE42"  !CDS_PN = "DE42";
"DDR5_DQ<38>":   PN = "DD39"  !CDS_PN = "DD39";
"DDR5_DQ<39>":   PN = "DH39"  !CDS_PN = "DH39";
"DDR5_DQ<40>":   PN = "DF33"  !CDS_PN = "DF33";
"DDR5_DQ<41>":   PN = "DK33"  !CDS_PN = "DK33";
"DDR5_DQ<42>":   PN = "DG30"  !CDS_PN = "DG30";
"DDR5_DQ<43>":   PN = "DJ30"  !CDS_PN = "DJ30";
"DDR5_DQ<44>":   PN = "DG34"  !CDS_PN = "DG34";
"DDR5_DQ<45>":   PN = "DJ34"  !CDS_PN = "DJ34";
"DDR5_DQ<46>":   PN = "DF31"  !CDS_PN = "DF31";
"DDR5_DQ<47>":   PN = "DK31"  !CDS_PN = "DK31";
"DDR5_DQ<48>":   PN = "CW36"  !CDS_PN = "CW36";
"DDR5_DQ<49>":   PN = "DC36"  !CDS_PN = "DC36";
"DDR5_DQ<50>":   PN = "CY33"  !CDS_PN = "CY33";
"DDR5_DQ<51>":   PN = "DB33"  !CDS_PN = "DB33";
"DDR5_DQ<52>":   PN = "CY37"  !CDS_PN = "CY37";
"DDR5_DQ<53>":   PN = "DB37"  !CDS_PN = "DB37";
"DDR5_DQ<54>":   PN = "CW34"  !CDS_PN = "CW34";
"DDR5_DQ<55>":   PN = "DC34"  !CDS_PN = "DC34";
"DDR5_DQ<56>":   PN = "CW30"  !CDS_PN = "CW30";
"DDR5_DQ<57>":   PN = "DC30"  !CDS_PN = "DC30";
"DDR5_DQ<58>":   PN = "CY27"  !CDS_PN = "CY27";
"DDR5_DQ<59>":   PN = "DB27"  !CDS_PN = "DB27";
"DDR5_DQ<60>":   PN = "CY31"  !CDS_PN = "CY31";
"DDR5_DQ<61>":   PN = "DB31"  !CDS_PN = "DB31";
"DDR5_DQ<62>":   PN = "CW28"  !CDS_PN = "CW28";
"DDR5_DQ<63>":   PN = "DC28"  !CDS_PN = "DC28";
"DDR5_DQS_DN<0>":   PN = "CP77"  !CDS_PN = "CP77";
"DDR5_DQS_DN<1>":   PN = "DD77"  !CDS_PN = "DD77";
"DDR5_DQS_DN<2>":   PN = "DL72"  !CDS_PN = "DL72";
"DDR5_DQS_DN<3>":   PN = "CV65"  !CDS_PN = "CV65";
"DDR5_DQS_DN<4>":   PN = "DG40"  !CDS_PN = "DG40";
"DDR5_DQS_DN<5>":   PN = "DL32"  !CDS_PN = "DL32";
"DDR5_DQS_DN<6>":   PN = "DD35"  !CDS_PN = "DD35";
"DDR5_DQS_DN<7>":   PN = "DD29"  !CDS_PN = "DD29";
"DDR5_DQS_DN<8>":   PN = "CN70"  !CDS_PN = "CN70";
"DDR5_DQS_DN<9>":   PN = "CT75"  !CDS_PN = "CT75";
"DDR5_DQS_DN<10>":   PN = "DF75"  !CDS_PN = "DF75";
"DDR5_DQS_DN<11>":   PN = "DJ70"  !CDS_PN = "DJ70";
"DDR5_DQS_DN<12>":   PN = "CP65"  !CDS_PN = "CP65";
"DDR5_DQS_DN<13>":   PN = "DE40"  !CDS_PN = "DE40";
"DDR5_DQS_DN<14>":   PN = "DG32"  !CDS_PN = "DG32";
"DDR5_DQS_DN<15>":   PN = "CY35"  !CDS_PN = "CY35";
"DDR5_DQS_DN<16>":   PN = "CY29"  !CDS_PN = "CY29";
"DDR5_DQS_DN<17>":   PN = "CJ70"  !CDS_PN = "CJ70";
"DDR5_DQS_DP<0>":   PN = "CR76"  !CDS_PN = "CR76";
"DDR5_DQS_DP<1>":   PN = "DE76"  !CDS_PN = "DE76";
"DDR5_DQS_DP<2>":   PN = "DK71"  !CDS_PN = "DK71";
"DDR5_DQS_DP<3>":   PN = "CT65"  !CDS_PN = "CT65";
"DDR5_DQS_DP<4>":   PN = "DJ40"  !CDS_PN = "DJ40";
"DDR5_DQS_DP<5>":   PN = "DJ32"  !CDS_PN = "DJ32";
"DDR5_DQS_DP<6>":   PN = "DB35"  !CDS_PN = "DB35";
"DDR5_DQS_DP<7>":   PN = "DB29"  !CDS_PN = "DB29";
"DDR5_DQS_DP<8>":   PN = "CL70"  !CDS_PN = "CL70";
"DDR5_DQS_DP<9>":   PN = "CU74"  !CDS_PN = "CU74";
"DDR5_DQS_DP<10>":   PN = "DG74"  !CDS_PN = "DG74";
"DDR5_DQS_DP<11>":   PN = "DH69"  !CDS_PN = "DH69";
"DDR5_DQS_DP<12>":   PN = "CM65"  !CDS_PN = "CM65";
"DDR5_DQS_DP<13>":   PN = "DC40"  !CDS_PN = "DC40";
"DDR5_DQS_DP<14>":   PN = "DE32"  !CDS_PN = "DE32";
"DDR5_DQS_DP<15>":   PN = "CV35"  !CDS_PN = "CV35";
"DDR5_DQS_DP<16>":   PN = "CV29"  !CDS_PN = "CV29";
"DDR5_DQS_DP<17>":   PN = "CG70"  !CDS_PN = "CG70";
"DDR5_ECC<0>":   PN = "CH71"  !CDS_PN = "CH71";
"DDR5_ECC<1>":   PN = "CM71"  !CDS_PN = "CM71";
"DDR5_ECC<2>":   PN = "CJ68"  !CDS_PN = "CJ68";
"DDR5_ECC<3>":   PN = "CL68"  !CDS_PN = "CL68";
"DDR5_ECC<4>":   PN = "CJ72"  !CDS_PN = "CJ72";
"DDR5_ECC<5>":   PN = "CL72"  !CDS_PN = "CL72";
"DDR5_ECC<6>":   PN = "CH69"  !CDS_PN = "CH69";
"DDR5_ECC<7>":   PN = "CM69"  !CDS_PN = "CM69";
"DDR5_MA<0>":   PN = "DF53"  !CDS_PN = "DF53";
"DDR5_MA<1>":   PN = "DC58"  !CDS_PN = "DC58";
"DDR5_MA<2>":   PN = "DD57"  !CDS_PN = "DD57";
"DDR5_MA<3>":   PN = "DG58"  !CDS_PN = "DG58";
"DDR5_MA<4>":   PN = "DJ58"  !CDS_PN = "DJ58";
"DDR5_MA<5>":   PN = "DF59"  !CDS_PN = "DF59";
"DDR5_MA<6>":   PN = "DK59"  !CDS_PN = "DK59";
"DDR5_MA<7>":   PN = "DC60"  !CDS_PN = "DC60";
"DDR5_MA<8>":   PN = "DD59"  !CDS_PN = "DD59";
"DDR5_MA<9>":   PN = "DA58"  !CDS_PN = "DA58";
"DDR5_MA<10>":   PN = "DD55"  !CDS_PN = "DD55";
"DDR5_MA<11>":   PN = "DA60"  !CDS_PN = "DA60";
"DDR5_MA<12>":   PN = "DG60"  !CDS_PN = "DG60";
"DDR5_MA<13>":   PN = "DD53"  !CDS_PN = "DD53";
"DDR5_MA<14>":   PN = "DJ50"  !CDS_PN = "DJ50";
"DDR5_MA<15>":   PN = "DC54"  !CDS_PN = "DC54";
"DDR5_MA<16>":   PN = "DG52"  !CDS_PN = "DG52";
"DDR5_MA<17>":   PN = "DE46"  !CDS_PN = "DE46";
"DDR5_ODT<0>":   PN = "DG50"  !CDS_PN = "DG50";
"DDR5_ODT<1>":   PN = "DG48"  !CDS_PN = "DG48";
"DDR5_ODT<2>":   PN = "DK49"  !CDS_PN = "DK49";
"DDR5_ODT<3>":   PN = "DF47"  !CDS_PN = "DF47";
"DDR5_PAR":   PN = "DK53"  !CDS_PN = "DK53";
DRAWING = "@baseboard_fab2_lib.baseboard_fab2(sch_1):page63";
BODY = "SKX_EXT_B","I23": #LOCATION = "U2D1" !CDS_LOCATION = "U2D1" #SEC = "9" !CDS_SEC = "9";
"CD_HFI0_I2CCLK":   PN = "BN22"  !CDS_PN = "BN22";
"CD_HFI0_I2CDAT":   PN = "BP23"  !CDS_PN = "BP23";
"CD_HFI0_INT_N":   PN = "BP19"  !CDS_PN = "BP19";
"CD_HFI0_LED_N":   PN = "BK21"  !CDS_PN = "BK21";
"CD_HFI0_MODPRST_N":   PN = "BR20"  !CDS_PN = "BR20";
"CD_HFI0_RESET_N":   PN = "BN24"  !CDS_PN = "BN24";
"CD_HFI1_I2CCLK":   PN = "BJ22"  !CDS_PN = "BJ22";
"CD_HFI1_I2CDAT":   PN = "BH23"  !CDS_PN = "BH23";
"CD_HFI1_INT_N":   PN = "BM21"  !CDS_PN = "BM21";
"CD_HFI1_LED_N":   PN = "BM23"  !CDS_PN = "BM23";
"CD_HFI1_MODPRST_N":   PN = "BT19"  !CDS_PN = "BT19";
"CD_HFI1_RESET_N":   PN = "BK23"  !CDS_PN = "BK23";
"CD_HFI_REFCLK_DN":   PN = "BE16"  !CDS_PN = "BE16";
"CD_HFI_REFCLK_DP":   PN = "BG16"  !CDS_PN = "BG16";
"CD_PE_REFCLK_DN":   PN = "BU24"  !CDS_PN = "BU24";
"CD_PE_REFCLK_DP":   PN = "BW24"  !CDS_PN = "BW24";
"CD_POR_N":   PN = "CF25"  !CDS_PN = "CF25";
"CD_TCLK":   PN = "CB23"  !CDS_PN = "CB23";
"CD_TDI":   PN = "BY21"  !CDS_PN = "BY21";
"CD_TDO":   PN = "CC22"  !CDS_PN = "CC22";
"CD_TMS":   PN = "CE24"  !CDS_PN = "CE24";
"CD_TRST_N":   PN = "CD23"  !CDS_PN = "CD23";
"DMI_RX_DN<0>":   PN = "CK9"  !CDS_PN = "CK9";
"DMI_RX_DN<1>":   PN = "CM11"  !CDS_PN = "CM11";
"DMI_RX_DN<2>":   PN = "CR12"  !CDS_PN = "CR12";
"DMI_RX_DN<3>":   PN = "CT11"  !CDS_PN = "CT11";
"DMI_RX_DP<0>":   PN = "CL10"  !CDS_PN = "CL10";
"DMI_RX_DP<1>":   PN = "CN10"  !CDS_PN = "CN10";
"DMI_RX_DP<2>":   PN = "CP11"  !CDS_PN = "CP11";
"DMI_RX_DP<3>":   PN = "CV11"  !CDS_PN = "CV11";
"DMI_TX_DN<0>":   PN = "CG4"  !CDS_PN = "CG4";
"DMI_TX_DN<1>":   PN = "CJ4"  !CDS_PN = "CJ4";
"DMI_TX_DN<2>":   PN = "CN4"  !CDS_PN = "CN4";
"DMI_TX_DN<3>":   PN = "CP5"  !CDS_PN = "CP5";
"DMI_TX_DP<0>":   PN = "CH5"  !CDS_PN = "CH5";
"DMI_TX_DP<1>":   PN = "CL4"  !CDS_PN = "CL4";
"DMI_TX_DP<2>":   PN = "CM3"  !CDS_PN = "CM3";
"DMI_TX_DP<3>":   PN = "CR4"  !CDS_PN = "CR4";
"RSVD<172>":   PN = "BA76"  !CDS_PN = "BA76";
"RSVD<173>":   PN = "BA66"  !CDS_PN = "BA66";
"RSVD<174>":   PN = "BA64"  !CDS_PN = "BA64";
"RSVD<175>":   PN = "BA22"  !CDS_PN = "BA22";
"RSVD<176>":   PN = "BA18"  !CDS_PN = "BA18";
"RSVD<177>":   PN = "BA16"  !CDS_PN = "BA16";
"RSVD<178>":   PN = "BA14"  !CDS_PN = "BA14";
"RSVD<179>":   PN = "AY77"  !CDS_PN = "AY77";
"RSVD<180>":   PN = "AY75"  !CDS_PN = "AY75";
"RSVD<181>":   PN = "AY67"  !CDS_PN = "AY67";
"RSVD<182>":   PN = "AY65"  !CDS_PN = "AY65";
"RSVD<183>":   PN = "AW76"  !CDS_PN = "AW76";
"RSVD<184>":   PN = "AW64"  !CDS_PN = "AW64";
"RSVD<186>":   PN = "AV77"  !CDS_PN = "AV77";
"RSVD<187>":   PN = "AT25"  !CDS_PN = "AT25";
"RSVD<188>":   PN = "AT23"  !CDS_PN = "AT23";
"RSVD<189>":   PN = "AT13"  !CDS_PN = "AT13";
"RSVD<190>":   PN = "AR62"  !CDS_PN = "AR62";
"RSVD<191>":   PN = "AR26"  !CDS_PN = "AR26";
"RSVD<192>":   PN = "AR22"  !CDS_PN = "AR22";
"RSVD<193>":   PN = "AR20"  !CDS_PN = "AR20";
DRAWING = "@baseboard_fab2_lib.baseboard_fab2(sch_1):page64";
BODY = "SKX_EXT_B","I68": #LOCATION = "U2D1" !CDS_LOCATION = "U2D1" #SEC = "10" !CDS_SEC = "10";
"PE1_RX_DN<0>":   PN = "CW8"  !CDS_PN = "CW8";
"PE1_RX_DN<1>":   PN = "DA8"  !CDS_PN = "DA8";
"PE1_RX_DN<2>":   PN = "DC8"  !CDS_PN = "DC8";
"PE1_RX_DN<3>":   PN = "DC10"  !CDS_PN = "DC10";
"PE1_RX_DN<4>":   PN = "DE10"  !CDS_PN = "DE10";
"PE1_RX_DN<5>":   PN = "DH9"  !CDS_PN = "DH9";
"PE1_RX_DN<6>":   PN = "DK9"  !CDS_PN = "DK9";
"PE1_RX_DN<7>":   PN = "DM9"  !CDS_PN = "DM9";
"PE1_RX_DN<8>":   PN = "DM11"  !CDS_PN = "DM11";
"PE1_RX_DN<9>":   PN = "DP11"  !CDS_PN = "DP11";
"PE1_RX_DN<10>":   PN = "DT11"  !CDS_PN = "DT11";
"PE1_RX_DN<11>":   PN = "DT13"  !CDS_PN = "DT13";
"PE1_RX_DN<12>":   PN = "DV13"  !CDS_PN = "DV13";
"PE1_RX_DN<13>":   PN = "DW14"  !CDS_PN = "DW14";
"PE1_RX_DN<14>":   PN = "DY15"  !CDS_PN = "DY15";
"PE1_RX_DN<15>":   PN = "DU16"  !CDS_PN = "DU16";
"PE1_RX_DP<0>":   PN = "CU8"  !CDS_PN = "CU8";
"PE1_RX_DP<1>":   PN = "CY7"  !CDS_PN = "CY7";
"PE1_RX_DP<2>":   PN = "DB9"  !CDS_PN = "DB9";
"PE1_RX_DP<3>":   PN = "DA10"  !CDS_PN = "DA10";
"PE1_RX_DP<4>":   PN = "DD9"  !CDS_PN = "DD9";
"PE1_RX_DP<5>":   PN = "DF9"  !CDS_PN = "DF9";
"PE1_RX_DP<6>":   PN = "DJ8"  !CDS_PN = "DJ8";
"PE1_RX_DP<7>":   PN = "DL10"  !CDS_PN = "DL10";
"PE1_RX_DP<8>":   PN = "DK11"  !CDS_PN = "DK11";
"PE1_RX_DP<9>":   PN = "DN10"  !CDS_PN = "DN10";
"PE1_RX_DP<10>":   PN = "DR12"  !CDS_PN = "DR12";
"PE1_RX_DP<11>":   PN = "DP13"  !CDS_PN = "DP13";
"PE1_RX_DP<12>":   PN = "DU12"  !CDS_PN = "DU12";
"PE1_RX_DP<13>":   PN = "DY13"  !CDS_PN = "DY13";
"PE1_RX_DP<14>":   PN = "DV15"  !CDS_PN = "DV15";
"PE1_RX_DP<15>":   PN = "DT15"  !CDS_PN = "DT15";
"PE1_TX_DN<0>":   PN = "DA2"  !CDS_PN = "DA2";
"PE1_TX_DN<1>":   PN = "DC2"  !CDS_PN = "DC2";
"PE1_TX_DN<2>":   PN = "DE2"  !CDS_PN = "DE2";
"PE1_TX_DN<3>":   PN = "DE4"  !CDS_PN = "DE4";
"PE1_TX_DN<4>":   PN = "DG4"  !CDS_PN = "DG4";
"PE1_TX_DN<5>":   PN = "DK3"  !CDS_PN = "DK3";
"PE1_TX_DN<6>":   PN = "DM3"  !CDS_PN = "DM3";
"PE1_TX_DN<7>":   PN = "DN4"  !CDS_PN = "DN4";
"PE1_TX_DN<8>":   PN = "DT5"  !CDS_PN = "DT5";
"PE1_TX_DN<9>":   PN = "DV3"  !CDS_PN = "DV3";
"PE1_TX_DN<10>":   PN = "DW4"  !CDS_PN = "DW4";
"PE1_TX_DN<11>":   PN = "DU6"  !CDS_PN = "DU6";
"PE1_TX_DN<12>":   PN = "DV7"  !CDS_PN = "DV7";
"PE1_TX_DN<13>":   PN = "DY7"  !CDS_PN = "DY7";
"PE1_TX_DN<14>":   PN = "EA8"  !CDS_PN = "EA8";
"PE1_TX_DN<15>":   PN = "ED9"  !CDS_PN = "ED9";
"PE1_TX_DP<0>":   PN = "CW2"  !CDS_PN = "CW2";
"PE1_TX_DP<1>":   PN = "DB1"  !CDS_PN = "DB1";
"PE1_TX_DP<2>":   PN = "DD3"  !CDS_PN = "DD3";
"PE1_TX_DP<3>":   PN = "DC4"  !CDS_PN = "DC4";
"PE1_TX_DP<4>":   PN = "DF3"  !CDS_PN = "DF3";
"PE1_TX_DP<5>":   PN = "DH3"  !CDS_PN = "DH3";
"PE1_TX_DP<6>":   PN = "DL2"  !CDS_PN = "DL2";
"PE1_TX_DP<7>":   PN = "DP3"  !CDS_PN = "DP3";
"PE1_TX_DP<8>":   PN = "DR4"  !CDS_PN = "DR4";
"PE1_TX_DP<9>":   PN = "DU2"  !CDS_PN = "DU2";
"PE1_TX_DP<10>":   PN = "DU4"  !CDS_PN = "DU4";
"PE1_TX_DP<11>":   PN = "DV5"  !CDS_PN = "DV5";
"PE1_TX_DP<12>":   PN = "DT7"  !CDS_PN = "DT7";
"PE1_TX_DP<13>":   PN = "DW6"  !CDS_PN = "DW6";
"PE1_TX_DP<14>":   PN = "EB7"  !CDS_PN = "EB7";
"PE1_TX_DP<15>":   PN = "EC8"  !CDS_PN = "EC8";
DRAWING = "@baseboard_fab2_lib.baseboard_fab2(sch_1):page65";
BODY = "SKX_EXT_B","I68": #LOCATION = "U2D1" !CDS_LOCATION = "U2D1" #SEC = "11" !CDS_SEC = "11";
"PE2_RX_DN<0>":   PN = "CT9"  !CDS_PN = "CT9";
"PE2_RX_DN<1>":   PN = "CP9"  !CDS_PN = "CP9";
"PE2_RX_DN<2>":   PN = "CP7"  !CDS_PN = "CP7";
"PE2_RX_DN<3>":   PN = "CM7"  !CDS_PN = "CM7";
"PE2_RX_DN<4>":   PN = "CK7"  !CDS_PN = "CK7";
"PE2_RX_DN<5>":   PN = "CG8"  !CDS_PN = "CG8";
"PE2_RX_DN<6>":   PN = "CE6"  !CDS_PN = "CE6";
"PE2_RX_DN<7>":   PN = "CE8"  !CDS_PN = "CE8";
"PE2_RX_DN<8>":   PN = "BY9"  !CDS_PN = "BY9";
"PE2_RX_DN<9>":   PN = "BY7"  !CDS_PN = "BY7";
"PE2_RX_DN<10>":   PN = "BV7"  !CDS_PN = "BV7";
"PE2_RX_DN<11>":   PN = "BT7"  !CDS_PN = "BT7";
"PE2_RX_DN<12>":   PN = "BR8"  !CDS_PN = "BR8";
"PE2_RX_DN<13>":   PN = "BN8"  !CDS_PN = "BN8";
"PE2_RX_DN<14>":   PN = "BL8"  !CDS_PN = "BL8";
"PE2_RX_DN<15>":   PN = "BK9"  !CDS_PN = "BK9";
"PE2_RX_DP<0>":   PN = "CR8"  !CDS_PN = "CR8";
"PE2_RX_DP<1>":   PN = "CM9"  !CDS_PN = "CM9";
"PE2_RX_DP<2>":   PN = "CN8"  !CDS_PN = "CN8";
"PE2_RX_DP<3>":   PN = "CL6"  !CDS_PN = "CL6";
"PE2_RX_DP<4>":   PN = "CH7"  !CDS_PN = "CH7";
"PE2_RX_DP<5>":   PN = "CF7"  !CDS_PN = "CF7";
"PE2_RX_DP<6>":   PN = "CD7"  !CDS_PN = "CD7";
"PE2_RX_DP<7>":   PN = "CC8"  !CDS_PN = "CC8";
"PE2_RX_DP<8>":   PN = "BV9"  !CDS_PN = "BV9";
"PE2_RX_DP<9>":   PN = "BW8"  !CDS_PN = "BW8";
"PE2_RX_DP<10>":   PN = "BU6"  !CDS_PN = "BU6";
"PE2_RX_DP<11>":   PN = "BP7"  !CDS_PN = "BP7";
"PE2_RX_DP<12>":   PN = "BP9"  !CDS_PN = "BP9";
"PE2_RX_DP<13>":   PN = "BM7"  !CDS_PN = "BM7";
"PE2_RX_DP<14>":   PN = "BJ8"  !CDS_PN = "BJ8";
"PE2_RX_DP<15>":   PN = "BJ10"  !CDS_PN = "BJ10";
"PE2_TX_DN<0>":   PN = "CY3"  !CDS_PN = "CY3";
"PE2_TX_DN<1>":   PN = "CV3"  !CDS_PN = "CV3";
"PE2_TX_DN<2>":   PN = "CT1"  !CDS_PN = "CT1";
"PE2_TX_DN<3>":   PN = "CT3"  !CDS_PN = "CT3";
"PE2_TX_DN<4>":   PN = "CM1"  !CDS_PN = "CM1";
"PE2_TX_DN<5>":   PN = "CL2"  !CDS_PN = "CL2";
"PE2_TX_DN<6>":   PN = "CG2"  !CDS_PN = "CG2";
"PE2_TX_DN<7>":   PN = "CF3"  !CDS_PN = "CF3";
"PE2_TX_DN<8>":   PN = "CC2"  !CDS_PN = "CC2";
"PE2_TX_DN<9>":   PN = "CB3"  !CDS_PN = "CB3";
"PE2_TX_DN<10>":   PN = "CA4"  !CDS_PN = "CA4";
"PE2_TX_DN<11>":   PN = "BW4"  !CDS_PN = "BW4";
"PE2_TX_DN<12>":   PN = "BU4"  !CDS_PN = "BU4";
"PE2_TX_DN<13>":   PN = "BP5"  !CDS_PN = "BP5";
"PE2_TX_DN<14>":   PN = "BL4"  !CDS_PN = "BL4";
"PE2_TX_DN<15>":   PN = "BM5"  !CDS_PN = "BM5";
"PE2_TX_DP<0>":   PN = "CW4"  !CDS_PN = "CW4";
"PE2_TX_DP<1>":   PN = "CU2"  !CDS_PN = "CU2";
"PE2_TX_DP<2>":   PN = "CR2"  !CDS_PN = "CR2";
"PE2_TX_DP<3>":   PN = "CP3"  !CDS_PN = "CP3";
"PE2_TX_DP<4>":   PN = "CK1"  !CDS_PN = "CK1";
"PE2_TX_DP<5>":   PN = "CK3"  !CDS_PN = "CK3";
"PE2_TX_DP<6>":   PN = "CE2"  !CDS_PN = "CE2";
"PE2_TX_DP<7>":   PN = "CE4"  !CDS_PN = "CE4";
"PE2_TX_DP<8>":   PN = "CD3"  !CDS_PN = "CD3";
"PE2_TX_DP<9>":   PN = "BY3"  !CDS_PN = "BY3";
"PE2_TX_DP<10>":   PN = "BY5"  !CDS_PN = "BY5";
"PE2_TX_DP<11>":   PN = "BV3"  !CDS_PN = "BV3";
"PE2_TX_DP<12>":   PN = "BR4"  !CDS_PN = "BR4";
"PE2_TX_DP<13>":   PN = "BN4"  !CDS_PN = "BN4";
"PE2_TX_DP<14>":   PN = "BM3"  !CDS_PN = "BM3";
"PE2_TX_DP<15>":   PN = "BK5"  !CDS_PN = "BK5";
DRAWING = "@baseboard_fab2_lib.baseboard_fab2(sch_1):page66";
BODY = "SKX_EXT_B","I84": #LOCATION = "U2D1" !CDS_LOCATION = "U2D1" #SEC = "12" !CDS_SEC = "12";
"PE3_RX_DN<0>":   PN = "EA18"  !CDS_PN = "EA18";
"PE3_RX_DN<1>":   PN = "DW18"  !CDS_PN = "DW18";
"PE3_RX_DN<2>":   PN = "DW16"  !CDS_PN = "DW16";
"PE3_RX_DN<3>":   PN = "DT19"  !CDS_PN = "DT19";
"PE3_RX_DN<4>":   PN = "DR16"  !CDS_PN = "DR16";
"PE3_RX_DN<5>":   PN = "DR14"  !CDS_PN = "DR14";
"PE3_RX_DN<6>":   PN = "DN14"  !CDS_PN = "DN14";
"PE3_RX_DN<7>":   PN = "DL14"  !CDS_PN = "DL14";
"PE3_RX_DN<8>":   PN = "DL12"  !CDS_PN = "DL12";
"PE3_RX_DN<9>":   PN = "DJ12"  !CDS_PN = "DJ12";
"PE3_RX_DN<10>":   PN = "DG12"  !CDS_PN = "DG12";
"PE3_RX_DN<11>":   PN = "DG10"  !CDS_PN = "DG10";
"PE3_RX_DN<12>":   PN = "DD13"  !CDS_PN = "DD13";
"PE3_RX_DN<13>":   PN = "DB11"  !CDS_PN = "DB11";
"PE3_RX_DN<14>":   PN = "CY11"  !CDS_PN = "CY11";
"PE3_RX_DN<15>":   PN = "CV9"  !CDS_PN = "CV9";
"PE3_RX_DP<0>":   PN = "DY17"  !CDS_PN = "DY17";
"PE3_RX_DP<1>":   PN = "DU18"  !CDS_PN = "DU18";
"PE3_RX_DP<2>":   PN = "DV17"  !CDS_PN = "DV17";
"PE3_RX_DP<3>":   PN = "DR18"  !CDS_PN = "DR18";
"PE3_RX_DP<4>":   PN = "DN16"  !CDS_PN = "DN16";
"PE3_RX_DP<5>":   PN = "DP15"  !CDS_PN = "DP15";
"PE3_RX_DP<6>":   PN = "DM13"  !CDS_PN = "DM13";
"PE3_RX_DP<7>":   PN = "DJ14"  !CDS_PN = "DJ14";
"PE3_RX_DP<8>":   PN = "DK13"  !CDS_PN = "DK13";
"PE3_RX_DP<9>":   PN = "DH11"  !CDS_PN = "DH11";
"PE3_RX_DP<10>":   PN = "DE12"  !CDS_PN = "DE12";
"PE3_RX_DP<11>":   PN = "DF11"  !CDS_PN = "DF11";
"PE3_RX_DP<12>":   PN = "DC12"  !CDS_PN = "DC12";
"PE3_RX_DP<13>":   PN = "DA12"  !CDS_PN = "DA12";
"PE3_RX_DP<14>":   PN = "CW10"  !CDS_PN = "CW10";
"PE3_RX_DP<15>":   PN = "CU10"  !CDS_PN = "CU10";
"PE3_TX_DN<0>":   PN = "EE14"  !CDS_PN = "EE14";
"PE3_TX_DN<1>":   PN = "EE12"  !CDS_PN = "EE12";
"PE3_TX_DN<2>":   PN = "EC12"  !CDS_PN = "EC12";
"PE3_TX_DN<3>":   PN = "DY11"  !CDS_PN = "DY11";
"PE3_TX_DN<4>":   PN = "EB9"  !CDS_PN = "EB9";
"PE3_TX_DN<5>":   PN = "DW10"  !CDS_PN = "DW10";
"PE3_TX_DN<6>":   PN = "DU8"  !CDS_PN = "DU8";
"PE3_TX_DN<7>":   PN = "DR8"  !CDS_PN = "DR8";
"PE3_TX_DN<8>":   PN = "DM7"  !CDS_PN = "DM7";
"PE3_TX_DN<9>":   PN = "DP5"  !CDS_PN = "DP5";
"PE3_TX_DN<10>":   PN = "DL6"  !CDS_PN = "DL6";
"PE3_TX_DN<11>":   PN = "DJ4"  !CDS_PN = "DJ4";
"PE3_TX_DN<12>":   PN = "DJ6"  !CDS_PN = "DJ6";
"PE3_TX_DN<13>":   PN = "DD5"  !CDS_PN = "DD5";
"PE3_TX_DN<14>":   PN = "DB5"  !CDS_PN = "DB5";
"PE3_TX_DN<15>":   PN = "CY5"  !CDS_PN = "CY5";
"PE3_TX_DP<0>":   PN = "EC14"  !CDS_PN = "EC14";
"PE3_TX_DP<1>":   PN = "ED13"  !CDS_PN = "ED13";
"PE3_TX_DP<2>":   PN = "EB11"  !CDS_PN = "EB11";
"PE3_TX_DP<3>":   PN = "EA10"  !CDS_PN = "EA10";
"PE3_TX_DP<4>":   PN = "DY9"  !CDS_PN = "DY9";
"PE3_TX_DP<5>":   PN = "DV9"  !CDS_PN = "DV9";
"PE3_TX_DP<6>":   PN = "DT9"  !CDS_PN = "DT9";
"PE3_TX_DP<7>":   PN = "DP7"  !CDS_PN = "DP7";
"PE3_TX_DP<8>":   PN = "DN6"  !CDS_PN = "DN6";
"PE3_TX_DP<9>":   PN = "DM5"  !CDS_PN = "DM5";
"PE3_TX_DP<10>":   PN = "DK5"  !CDS_PN = "DK5";
"PE3_TX_DP<11>":   PN = "DH5"  !CDS_PN = "DH5";
"PE3_TX_DP<12>":   PN = "DG6"  !CDS_PN = "DG6";
"PE3_TX_DP<13>":   PN = "DC6"  !CDS_PN = "DC6";
"PE3_TX_DP<14>":   PN = "DA4"  !CDS_PN = "DA4";
"PE3_TX_DP<15>":   PN = "CV5"  !CDS_PN = "CV5";
DRAWING = "@baseboard_fab2_lib.baseboard_fab2(sch_1):page67";
BODY = "SKX_EXT_B","I132": #LOCATION = "U2D1" !CDS_LOCATION = "U2D1" #SEC = "13" !CDS_SEC = "13";
"UPI0_RX_DN<0>":   PN = "AC10"  !CDS_PN = "AC10";
"UPI0_RX_DN<1>":   PN = "AA8"  !CDS_PN = "AA8";
"UPI0_RX_DN<2>":   PN = "AB7"  !CDS_PN = "AB7";
"UPI0_RX_DN<3>":   PN = "AD5"  !CDS_PN = "AD5";
"UPI0_RX_DN<4>":   PN = "AE6"  !CDS_PN = "AE6";
"UPI0_RX_DN<5>":   PN = "AG8"  !CDS_PN = "AG8";
"UPI0_RX_DN<6>":   PN = "AJ6"  !CDS_PN = "AJ6";
"UPI0_RX_DN<7>":   PN = "AL6"  !CDS_PN = "AL6";
"UPI0_RX_DN<8>":   PN = "AK7"  !CDS_PN = "AK7";
"UPI0_RX_DN<9>":   PN = "AM9"  !CDS_PN = "AM9";
"UPI0_RX_DN<10>":   PN = "AP7"  !CDS_PN = "AP7";
"UPI0_RX_DN<11>":   PN = "AR8"  !CDS_PN = "AR8";
"UPI0_RX_DN<12>":   PN = "AU10"  !CDS_PN = "AU10";
"UPI0_RX_DN<13>":   PN = "BA8"  !CDS_PN = "BA8";
"UPI0_RX_DN<14>":   PN = "BC6"  !CDS_PN = "BC6";
"UPI0_RX_DN<15>":   PN = "BD7"  !CDS_PN = "BD7";
"UPI0_RX_DN<16>":   PN = "AW8"  !CDS_PN = "AW8";
"UPI0_RX_DN<17>":   PN = "AY9"  !CDS_PN = "AY9";
"UPI0_RX_DN<18>":   PN = "BD9"  !CDS_PN = "BD9";
"UPI0_RX_DN<19>":   PN = "BB11"  !CDS_PN = "BB11";
"UPI0_RX_DP<0>":   PN = "AB9"  !CDS_PN = "AB9";
"UPI0_RX_DP<1>":   PN = "AC8"  !CDS_PN = "AC8";
"UPI0_RX_DP<2>":   PN = "AA6"  !CDS_PN = "AA6";
"UPI0_RX_DP<3>":   PN = "AC6"  !CDS_PN = "AC6";
"UPI0_RX_DP<4>":   PN = "AG6"  !CDS_PN = "AG6";
"UPI0_RX_DP<5>":   PN = "AF7"  !CDS_PN = "AF7";
"UPI0_RX_DP<6>":   PN = "AH7"  !CDS_PN = "AH7";
"UPI0_RX_DP<7>":   PN = "AK5"  !CDS_PN = "AK5";
"UPI0_RX_DP<8>":   PN = "AM7"  !CDS_PN = "AM7";
"UPI0_RX_DP<9>":   PN = "AL8"  !CDS_PN = "AL8";
"UPI0_RX_DP<10>":   PN = "AN8"  !CDS_PN = "AN8";
"UPI0_RX_DP<11>":   PN = "AU8"  !CDS_PN = "AU8";
"UPI0_RX_DP<12>":   PN = "AT9"  !CDS_PN = "AT9";
"UPI0_RX_DP<13>":   PN = "AY7"  !CDS_PN = "AY7";
"UPI0_RX_DP<14>":   PN = "BB7"  !CDS_PN = "BB7";
"UPI0_RX_DP<15>":   PN = "BF7"  !CDS_PN = "BF7";
"UPI0_RX_DP<16>":   PN = "AV9"  !CDS_PN = "AV9";
"UPI0_RX_DP<17>":   PN = "BB9"  !CDS_PN = "BB9";
"UPI0_RX_DP<18>":   PN = "BC10"  !CDS_PN = "BC10";
"UPI0_RX_DP<19>":   PN = "BA10"  !CDS_PN = "BA10";
"UPI0_TX_DN<0>":   PN = "N2"  !CDS_PN = "N2";
"UPI0_TX_DN<1>":   PN = "P1"  !CDS_PN = "P1";
"UPI0_TX_DN<2>":   PN = "V3"  !CDS_PN = "V3";
"UPI0_TX_DN<3>":   PN = "Y1"  !CDS_PN = "Y1";
"UPI0_TX_DN<4>":   PN = "AB3"  !CDS_PN = "AB3";
"UPI0_TX_DN<5>":   PN = "AC2"  !CDS_PN = "AC2";
"UPI0_TX_DN<6>":   PN = "AG4"  !CDS_PN = "AG4";
"UPI0_TX_DN<7>":   PN = "AE2"  !CDS_PN = "AE2";
"UPI0_TX_DN<8>":   PN = "AH3"  !CDS_PN = "AH3";
"UPI0_TX_DN<9>":   PN = "AL2"  !CDS_PN = "AL2";
"UPI0_TX_DN<10>":   PN = "AM3"  !CDS_PN = "AM3";
"UPI0_TX_DN<11>":   PN = "AN4"  !CDS_PN = "AN4";
"UPI0_TX_DN<12>":   PN = "AT1"  !CDS_PN = "AT1";
"UPI0_TX_DN<13>":   PN = "AT3"  !CDS_PN = "AT3";
"UPI0_TX_DN<14>":   PN = "AU4"  !CDS_PN = "AU4";
"UPI0_TX_DN<15>":   PN = "AV5"  !CDS_PN = "AV5";
"UPI0_TX_DN<16>":   PN = "BA4"  !CDS_PN = "BA4";
"UPI0_TX_DN<17>":   PN = "BB3"  !CDS_PN = "BB3";
"UPI0_TX_DN<18>":   PN = "BF3"  !CDS_PN = "BF3";
"UPI0_TX_DN<19>":   PN = "BG4"  !CDS_PN = "BG4";
"UPI0_TX_DP<0>":   PN = "M1"  !CDS_PN = "M1";
"UPI0_TX_DP<1>":   PN = "T1"  !CDS_PN = "T1";
"UPI0_TX_DP<2>":   PN = "Y3"  !CDS_PN = "Y3";
"UPI0_TX_DP<3>":   PN = "W2"  !CDS_PN = "W2";
"UPI0_TX_DP<4>":   PN = "AA2"  !CDS_PN = "AA2";
"UPI0_TX_DP<5>":   PN = "AD1"  !CDS_PN = "AD1";
"UPI0_TX_DP<6>":   PN = "AF3"  !CDS_PN = "AF3";
"UPI0_TX_DP<7>":   PN = "AG2"  !CDS_PN = "AG2";
"UPI0_TX_DP<8>":   PN = "AJ2"  !CDS_PN = "AJ2";
"UPI0_TX_DP<9>":   PN = "AK1"  !CDS_PN = "AK1";
"UPI0_TX_DP<10>":   PN = "AK3"  !CDS_PN = "AK3";
"UPI0_TX_DP<11>":   PN = "AP3"  !CDS_PN = "AP3";
"UPI0_TX_DP<12>":   PN = "AP1"  !CDS_PN = "AP1";
"UPI0_TX_DP<13>":   PN = "AR2"  !CDS_PN = "AR2";
"UPI0_TX_DP<14>":   PN = "AR4"  !CDS_PN = "AR4";
"UPI0_TX_DP<15>":   PN = "AW4"  !CDS_PN = "AW4";
"UPI0_TX_DP<16>":   PN = "AY3"  !CDS_PN = "AY3";
"UPI0_TX_DP<17>":   PN = "BC2"  !CDS_PN = "BC2";
"UPI0_TX_DP<18>":   PN = "BD3"  !CDS_PN = "BD3";
"UPI0_TX_DP<19>":   PN = "BH3"  !CDS_PN = "BH3";
DRAWING = "@baseboard_fab2_lib.baseboard_fab2(sch_1):page68";
BODY = "SKX_EXT_B","I125": #LOCATION = "U2D1" !CDS_LOCATION = "U2D1" #SEC = "14" !CDS_SEC = "14";
"UPI1_RX_DN<0>":   PN = "T5"  !CDS_PN = "T5";
"UPI1_RX_DN<1>":   PN = "P7"  !CDS_PN = "P7";
"UPI1_RX_DN<2>":   PN = "V7"  !CDS_PN = "V7";
"UPI1_RX_DN<3>":   PN = "T9"  !CDS_PN = "T9";
"UPI1_RX_DN<4>":   PN = "P9"  !CDS_PN = "P9";
"UPI1_RX_DN<5>":   PN = "R10"  !CDS_PN = "R10";
"UPI1_RX_DN<6>":   PN = "U12"  !CDS_PN = "U12";
"UPI1_RX_DN<7>":   PN = "L12"  !CDS_PN = "L12";
"UPI1_RX_DN<8>":   PN = "N14"  !CDS_PN = "N14";
"UPI1_RX_DN<9>":   PN = "R12"  !CDS_PN = "R12";
"UPI1_RX_DN<10>":   PN = "R16"  !CDS_PN = "R16";
"UPI1_RX_DN<11>":   PN = "P17"  !CDS_PN = "P17";
"UPI1_RX_DN<12>":   PN = "U16"  !CDS_PN = "U16";
"UPI1_RX_DN<13>":   PN = "W18"  !CDS_PN = "W18";
"UPI1_RX_DN<14>":   PN = "R20"  !CDS_PN = "R20";
"UPI1_RX_DN<15>":   PN = "U18"  !CDS_PN = "U18";
"UPI1_RX_DN<16>":   PN = "P21"  !CDS_PN = "P21";
"UPI1_RX_DN<17>":   PN = "V19"  !CDS_PN = "V19";
"UPI1_RX_DN<18>":   PN = "Y21"  !CDS_PN = "Y21";
"UPI1_RX_DN<19>":   PN = "AB19"  !CDS_PN = "AB19";
"UPI1_RX_DP<0>":   PN = "R6"  !CDS_PN = "R6";
"UPI1_RX_DP<1>":   PN = "T7"  !CDS_PN = "T7";
"UPI1_RX_DP<2>":   PN = "U8"  !CDS_PN = "U8";
"UPI1_RX_DP<3>":   PN = "R8"  !CDS_PN = "R8";
"UPI1_RX_DP<4>":   PN = "N10"  !CDS_PN = "N10";
"UPI1_RX_DP<5>":   PN = "U10"  !CDS_PN = "U10";
"UPI1_RX_DP<6>":   PN = "T11"  !CDS_PN = "T11";
"UPI1_RX_DP<7>":   PN = "N12"  !CDS_PN = "N12";
"UPI1_RX_DP<8>":   PN = "M13"  !CDS_PN = "M13";
"UPI1_RX_DP<9>":   PN = "P13"  !CDS_PN = "P13";
"UPI1_RX_DP<10>":   PN = "T15"  !CDS_PN = "T15";
"UPI1_RX_DP<11>":   PN = "N16"  !CDS_PN = "N16";
"UPI1_RX_DP<12>":   PN = "W16"  !CDS_PN = "W16";
"UPI1_RX_DP<13>":   PN = "V17"  !CDS_PN = "V17";
"UPI1_RX_DP<14>":   PN = "P19"  !CDS_PN = "P19";
"UPI1_RX_DP<15>":   PN = "T19"  !CDS_PN = "T19";
"UPI1_RX_DP<16>":   PN = "T21"  !CDS_PN = "T21";
"UPI1_RX_DP<17>":   PN = "Y19"  !CDS_PN = "Y19";
"UPI1_RX_DP<18>":   PN = "W20"  !CDS_PN = "W20";
"UPI1_RX_DP<19>":   PN = "AA20"  !CDS_PN = "AA20";
"UPI1_TX_DN<0>":   PN = "M3"  !CDS_PN = "M3";
"UPI1_TX_DN<1>":   PN = "L4"  !CDS_PN = "L4";
"UPI1_TX_DN<2>":   PN = "K5"  !CDS_PN = "K5";
"UPI1_TX_DN<3>":   PN = "J6"  !CDS_PN = "J6";
"UPI1_TX_DN<4>":   PN = "G6"  !CDS_PN = "G6";
"UPI1_TX_DN<5>":   PN = "H7"  !CDS_PN = "H7";
"UPI1_TX_DN<6>":   PN = "K9"  !CDS_PN = "K9";
"UPI1_TX_DN<7>":   PN = "D9"  !CDS_PN = "D9";
"UPI1_TX_DN<8>":   PN = "F11"  !CDS_PN = "F11";
"UPI1_TX_DN<9>":   PN = "G10"  !CDS_PN = "G10";
"UPI1_TX_DN<10>":   PN = "E12"  !CDS_PN = "E12";
"UPI1_TX_DN<11>":   PN = "G14"  !CDS_PN = "G14";
"UPI1_TX_DN<12>":   PN = "D15"  !CDS_PN = "D15";
"UPI1_TX_DN<13>":   PN = "F15"  !CDS_PN = "F15";
"UPI1_TX_DN<14>":   PN = "H17"  !CDS_PN = "H17";
"UPI1_TX_DN<15>":   PN = "K19"  !CDS_PN = "K19";
"UPI1_TX_DN<16>":   PN = "G18"  !CDS_PN = "G18";
"UPI1_TX_DN<17>":   PN = "J20"  !CDS_PN = "J20";
"UPI1_TX_DN<18>":   PN = "F21"  !CDS_PN = "F21";
"UPI1_TX_DN<19>":   PN = "H21"  !CDS_PN = "H21";
"UPI1_TX_DP<0>":   PN = "P3"  !CDS_PN = "P3";
"UPI1_TX_DP<1>":   PN = "K3"  !CDS_PN = "K3";
"UPI1_TX_DP<2>":   PN = "M5"  !CDS_PN = "M5";
"UPI1_TX_DP<3>":   PN = "H5"  !CDS_PN = "H5";
"UPI1_TX_DP<4>":   PN = "F7"  !CDS_PN = "F7";
"UPI1_TX_DP<5>":   PN = "K7"  !CDS_PN = "K7";
"UPI1_TX_DP<6>":   PN = "J8"  !CDS_PN = "J8";
"UPI1_TX_DP<7>":   PN = "F9"  !CDS_PN = "F9";
"UPI1_TX_DP<8>":   PN = "E10"  !CDS_PN = "E10";
"UPI1_TX_DP<9>":   PN = "H9"  !CDS_PN = "H9";
"UPI1_TX_DP<10>":   PN = "G12"  !CDS_PN = "G12";
"UPI1_TX_DP<11>":   PN = "F13"  !CDS_PN = "F13";
"UPI1_TX_DP<12>":   PN = "E14"  !CDS_PN = "E14";
"UPI1_TX_DP<13>":   PN = "H15"  !CDS_PN = "H15";
"UPI1_TX_DP<14>":   PN = "G16"  !CDS_PN = "G16";
"UPI1_TX_DP<15>":   PN = "L18"  !CDS_PN = "L18";
"UPI1_TX_DP<16>":   PN = "J18"  !CDS_PN = "J18";
"UPI1_TX_DP<17>":   PN = "H19"  !CDS_PN = "H19";
"UPI1_TX_DP<18>":   PN = "G20"  !CDS_PN = "G20";
"UPI1_TX_DP<19>":   PN = "K21"  !CDS_PN = "K21";
DRAWING = "@baseboard_fab2_lib.baseboard_fab2(sch_1):page69";
BODY = "SKX_EXT_B","I1": #LOCATION = "U2D1" !CDS_LOCATION = "U2D1" #SEC = "15" !CDS_SEC = "15";
"UPI2_RX_DN<0>":   PN = "DF23"  !CDS_PN = "DF23";
"UPI2_RX_DN<1>":   PN = "DE22"  !CDS_PN = "DE22";
"UPI2_RX_DN<2>":   PN = "DC22"  !CDS_PN = "DC22";
"UPI2_RX_DN<3>":   PN = "DB21"  !CDS_PN = "DB21";
"UPI2_RX_DN<4>":   PN = "DD19"  !CDS_PN = "DD19";
"UPI2_RX_DN<5>":   PN = "DA20"  !CDS_PN = "DA20";
"UPI2_RX_DN<6>":   PN = "CW20"  !CDS_PN = "CW20";
"UPI2_RX_DN<7>":   PN = "CV19"  !CDS_PN = "CV19";
"UPI2_RX_DN<8>":   PN = "CT21"  !CDS_PN = "CT21";
"UPI2_RX_DN<9>":   PN = "CR18"  !CDS_PN = "CR18";
"UPI2_RX_DN<10>":   PN = "CN20"  !CDS_PN = "CN20";
"UPI2_RX_DN<11>":   PN = "CP21"  !CDS_PN = "CP21";
"UPI2_RX_DN<12>":   PN = "CL16"  !CDS_PN = "CL16";
"UPI2_RX_DN<13>":   PN = "CJ18"  !CDS_PN = "CJ18";
"UPI2_RX_DN<14>":   PN = "CH17"  !CDS_PN = "CH17";
"UPI2_RX_DN<15>":   PN = "CE16"  !CDS_PN = "CE16";
"UPI2_RX_DN<16>":   PN = "CD15"  !CDS_PN = "CD15";
"UPI2_RX_DN<17>":   PN = "CF17"  !CDS_PN = "CF17";
"UPI2_RX_DN<18>":   PN = "CB15"  !CDS_PN = "CB15";
"UPI2_RX_DN<19>":   PN = "BY17"  !CDS_PN = "BY17";
"UPI2_RX_DP<0>":   PN = "DG22"  !CDS_PN = "DG22";
"UPI2_RX_DP<1>":   PN = "DD21"  !CDS_PN = "DD21";
"UPI2_RX_DP<2>":   PN = "DA22"  !CDS_PN = "DA22";
"UPI2_RX_DP<3>":   PN = "DC20"  !CDS_PN = "DC20";
"UPI2_RX_DP<4>":   PN = "DB19"  !CDS_PN = "DB19";
"UPI2_RX_DP<5>":   PN = "CY19"  !CDS_PN = "CY19";
"UPI2_RX_DP<6>":   PN = "CU20"  !CDS_PN = "CU20";
"UPI2_RX_DP<7>":   PN = "CW18"  !CDS_PN = "CW18";
"UPI2_RX_DP<8>":   PN = "CR20"  !CDS_PN = "CR20";
"UPI2_RX_DP<9>":   PN = "CN18"  !CDS_PN = "CN18";
"UPI2_RX_DP<10>":   PN = "CP19"  !CDS_PN = "CP19";
"UPI2_RX_DP<11>":   PN = "CM21"  !CDS_PN = "CM21";
"UPI2_RX_DP<12>":   PN = "CJ16"  !CDS_PN = "CJ16";
"UPI2_RX_DP<13>":   PN = "CK17"  !CDS_PN = "CK17";
"UPI2_RX_DP<14>":   PN = "CG16"  !CDS_PN = "CG16";
"UPI2_RX_DP<15>":   PN = "CF15"  !CDS_PN = "CF15";
"UPI2_RX_DP<16>":   PN = "CC14"  !CDS_PN = "CC14";
"UPI2_RX_DP<17>":   PN = "CD17"  !CDS_PN = "CD17";
"UPI2_RX_DP<18>":   PN = "BY15"  !CDS_PN = "BY15";
"UPI2_RX_DP<19>":   PN = "CA16"  !CDS_PN = "CA16";
"UPI2_TX_DN<0>":   PN = "DT21"  !CDS_PN = "DT21";
"UPI2_TX_DN<1>":   PN = "DM21"  !CDS_PN = "DM21";
"UPI2_TX_DN<2>":   PN = "DL20"  !CDS_PN = "DL20";
"UPI2_TX_DN<3>":   PN = "DG20"  !CDS_PN = "DG20";
"UPI2_TX_DN<4>":   PN = "DH19"  !CDS_PN = "DH19";
"UPI2_TX_DN<5>":   PN = "DK17"  !CDS_PN = "DK17";
"UPI2_TX_DN<6>":   PN = "DG18"  !CDS_PN = "DG18";
"UPI2_TX_DN<7>":   PN = "DD17"  !CDS_PN = "DD17";
"UPI2_TX_DN<8>":   PN = "DF15"  !CDS_PN = "DF15";
"UPI2_TX_DN<9>":   PN = "DC16"  !CDS_PN = "DC16";
"UPI2_TX_DN<10>":   PN = "DA16"  !CDS_PN = "DA16";
"UPI2_TX_DN<11>":   PN = "CW14"  !CDS_PN = "CW14";
"UPI2_TX_DN<12>":   PN = "CU14"  !CDS_PN = "CU14";
"UPI2_TX_DN<13>":   PN = "CM13"  !CDS_PN = "CM13";
"UPI2_TX_DN<14>":   PN = "CJ14"  !CDS_PN = "CJ14";
"UPI2_TX_DN<15>":   PN = "CF13"  !CDS_PN = "CF13";
"UPI2_TX_DN<16>":   PN = "CH11"  !CDS_PN = "CH11";
"UPI2_TX_DN<17>":   PN = "CE12"  !CDS_PN = "CE12";
"UPI2_TX_DN<18>":   PN = "CC10"  !CDS_PN = "CC10";
"UPI2_TX_DN<19>":   PN = "CC12"  !CDS_PN = "CC12";
"UPI2_TX_DP<0>":   PN = "DP21"  !CDS_PN = "DP21";
"UPI2_TX_DP<1>":   PN = "DN20"  !CDS_PN = "DN20";
"UPI2_TX_DP<2>":   PN = "DK19"  !CDS_PN = "DK19";
"UPI2_TX_DP<3>":   PN = "DJ20"  !CDS_PN = "DJ20";
"UPI2_TX_DP<4>":   PN = "DJ18"  !CDS_PN = "DJ18";
"UPI2_TX_DP<5>":   PN = "DH17"  !CDS_PN = "DH17";
"UPI2_TX_DP<6>":   PN = "DF17"  !CDS_PN = "DF17";
"UPI2_TX_DP<7>":   PN = "DE16"  !CDS_PN = "DE16";
"UPI2_TX_DP<8>":   PN = "DD15"  !CDS_PN = "DD15";
"UPI2_TX_DP<9>":   PN = "DB15"  !CDS_PN = "DB15";
"UPI2_TX_DP<10>":   PN = "CW16"  !CDS_PN = "CW16";
"UPI2_TX_DP<11>":   PN = "CV13"  !CDS_PN = "CV13";
"UPI2_TX_DP<12>":   PN = "CR14"  !CDS_PN = "CR14";
"UPI2_TX_DP<13>":   PN = "CK13"  !CDS_PN = "CK13";
"UPI2_TX_DP<14>":   PN = "CH13"  !CDS_PN = "CH13";
"UPI2_TX_DP<15>":   PN = "CG12"  !CDS_PN = "CG12";
"UPI2_TX_DP<16>":   PN = "CF11"  !CDS_PN = "CF11";
"UPI2_TX_DP<17>":   PN = "CD11"  !CDS_PN = "CD11";
"UPI2_TX_DP<18>":   PN = "CB11"  !CDS_PN = "CB11";
"UPI2_TX_DP<19>":   PN = "CA12"  !CDS_PN = "CA12";
DRAWING = "@baseboard_fab2_lib.baseboard_fab2(sch_1):page70";
BODY = "SKX_EXT_B","I9": #LOCATION = "U2D1" !CDS_LOCATION = "U2D1" #SEC = "16" !CDS_SEC = "16";
"RSVD<92>":   PN = "CH23"  !CDS_PN = "CH23";
"RSVD<93>":   PN = "CH21"  !CDS_PN = "CH21";
"RSVD<94>":   PN = "CG82"  !CDS_PN = "CG82";
"RSVD<95>":   PN = "CG78"  !CDS_PN = "CG78";
"RSVD<96>":   PN = "CG26"  !CDS_PN = "CG26";
"RSVD<97>":   PN = "CG24"  !CDS_PN = "CG24";
"RSVD<98>":   PN = "CG20"  !CDS_PN = "CG20";
"RSVD<99>":   PN = "CG10"  !CDS_PN = "CG10";
"RSVD<100>":   PN = "CF81"  !CDS_PN = "CF81";
"RSVD<101>":   PN = "CF79"  !CDS_PN = "CF79";
"RSVD<102>":   PN = "CF23"  !CDS_PN = "CF23";
"RSVD<103>":   PN = "CF21"  !CDS_PN = "CF21";
"RSVD<104>":   PN = "CF19"  !CDS_PN = "CF19";
"RSVD<105>":   PN = "CE80"  !CDS_PN = "CE80";
"RSVD<106>":   PN = "CE78"  !CDS_PN = "CE78";
"RSVD<107>":   PN = "CE22"  !CDS_PN = "CE22";
"RSVD<108>":   PN = "CD25"  !CDS_PN = "CD25";
"RSVD<109>":   PN = "CD21"  !CDS_PN = "CD21";
"RSVD<110>":   PN = "CD19"  !CDS_PN = "CD19";
"RSVD<111>":   PN = "CC6"  !CDS_PN = "CC6";
"RSVD<112>":   PN = "CC20"  !CDS_PN = "CC20";
"RSVD<113>":   PN = "CB5"  !CDS_PN = "CB5";
"RSVD<114>":   PN = "CB25"  !CDS_PN = "CB25";
"RSVD<115>":   PN = "CB21"  !CDS_PN = "CB21";
"RSVD<116>":   PN = "CB19"  !CDS_PN = "CB19";
"RSVD<117>":   PN = "CA24"  !CDS_PN = "CA24";
"RSVD<118>":   PN = "CA22"  !CDS_PN = "CA22";
"RSVD<119>":   PN = "BY25"  !CDS_PN = "BY25";
"RSVD<120>":   PN = "BY19"  !CDS_PN = "BY19";
"RSVD<121>":   PN = "BW22"  !CDS_PN = "BW22";
"RSVD<122>":   PN = "BW20"  !CDS_PN = "BW20";
"RSVD<123>":   PN = "BW10"  !CDS_PN = "BW10";
"RSVD<124>":   PN = "BV23"  !CDS_PN = "BV23";
"RSVD<125>":   PN = "BV21"  !CDS_PN = "BV21";
"RSVD<126>":   PN = "BV19"  !CDS_PN = "BV19";
"RSVD<127>":   PN = "BU22"  !CDS_PN = "BU22";
"RSVD<128>":   PN = "BU20"  !CDS_PN = "BU20";
"RSVD<129>":   PN = "BU18"  !CDS_PN = "BU18";
"RSVD<130>":   PN = "BR24"  !CDS_PN = "BR24";
"RSVD<131>":   PN = "BR22"  !CDS_PN = "BR22";
"RSVD<132>":   PN = "BP21"  !CDS_PN = "BP21";
"RSVD<133>":   PN = "BP17"  !CDS_PN = "BP17";
"RSVD<134>":   PN = "BN18"  !CDS_PN = "BN18";
"RSVD<135>":   PN = "BM19"  !CDS_PN = "BM19";
"RSVD<136>":   PN = "BM17"  !CDS_PN = "BM17";
"RSVD<137>":   PN = "BL20"  !CDS_PN = "BL20";
"RSVD<138>":   PN = "BL18"  !CDS_PN = "BL18";
"RSVD<139>":   PN = "BK17"  !CDS_PN = "BK17";
"RSVD<140>":   PN = "BJ20"  !CDS_PN = "BJ20";
"RSVD<141>":   PN = "BJ18"  !CDS_PN = "BJ18";
"RSVD<142>":   PN = "BJ16"  !CDS_PN = "BJ16";
"RSVD<143>":   PN = "BH19"  !CDS_PN = "BH19";
"RSVD<144>":   PN = "BG20"  !CDS_PN = "BG20";
"RSVD<145>":   PN = "BG18"  !CDS_PN = "BG18";
"RSVD<146>":   PN = "BF21"  !CDS_PN = "BF21";
"RSVD<147>":   PN = "BE22"  !CDS_PN = "BE22";
"RSVD<148>":   PN = "BE20"  !CDS_PN = "BE20";
"RSVD<149>":   PN = "BE18"  !CDS_PN = "BE18";
"RSVD<150>":   PN = "BD69"  !CDS_PN = "BD69";
"RSVD<151>":   PN = "BD67"  !CDS_PN = "BD67";
"RSVD<152>":   PN = "BD65"  !CDS_PN = "BD65";
"RSVD<153>":   PN = "BD25"  !CDS_PN = "BD25";
"RSVD<154>":   PN = "BD19"  !CDS_PN = "BD19";
"RSVD<155>":   PN = "BD17"  !CDS_PN = "BD17";
"RSVD<156>":   PN = "BC68"  !CDS_PN = "BC68";
"RSVD<157>":   PN = "BC66"  !CDS_PN = "BC66";
"RSVD<158>":   PN = "BC64"  !CDS_PN = "BC64";
"RSVD<159>":   PN = "BC22"  !CDS_PN = "BC22";
"RSVD<160>":   PN = "BC20"  !CDS_PN = "BC20";
"RSVD<161>":   PN = "BC18"  !CDS_PN = "BC18";
"RSVD<162>":   PN = "BC14"  !CDS_PN = "BC14";
"RSVD<163>":   PN = "BB67"  !CDS_PN = "BB67";
"RSVD<164>":   PN = "BB65"  !CDS_PN = "BB65";
"RSVD<165>":   PN = "BB25"  !CDS_PN = "BB25";
"RSVD<166>":   PN = "BB21"  !CDS_PN = "BB21";
"RSVD<167>":   PN = "BB17"  !CDS_PN = "BB17";
"RSVD<168>":   PN = "BB15"  !CDS_PN = "BB15";
"RSVD<169>":   PN = "BB13"  !CDS_PN = "BB13";
"RSVD<170>":   PN = "BA82"  !CDS_PN = "BA82";
"RSVD<171>":   PN = "BA78"  !CDS_PN = "BA78";
"RSVD<255>":   PN = "AY83"  !CDS_PN = "AY83";
BODY = "SKX_EXT_B","I10": #LOCATION = "U2D1" !CDS_LOCATION = "U2D1" #SEC = "17" !CDS_SEC = "17";
"RSVD<81>":   PN = "CL24"  !CDS_PN = "CL24";
"RSVD<82>":   PN = "CK77"  !CDS_PN = "CK77";
"RSVD<83>":   PN = "CK25"  !CDS_PN = "CK25";
"RSVD<84>":   PN = "CK23"  !CDS_PN = "CK23";
"RSVD<85>":   PN = "CK19"  !CDS_PN = "CK19";
"RSVD<86>":   PN = "CJ26"  !CDS_PN = "CJ26";
"RSVD<87>":   PN = "CJ24"  !CDS_PN = "CJ24";
"RSVD<88>":   PN = "CJ22"  !CDS_PN = "CJ22";
"RSVD<89>":   PN = "CJ20"  !CDS_PN = "CJ20";
"RSVD<90>":   PN = "CH77"  !CDS_PN = "CH77";
"RSVD<91>":   PN = "CH25"  !CDS_PN = "CH25";
"TEST_6":   PN = "AR16"  !CDS_PN = "AR16";
"TEST_7":   PN = "AU18"  !CDS_PN = "AU18";
"TEST_8":   PN = "AW16"  !CDS_PN = "AW16";
"TEST_9":   PN = "AW20"  !CDS_PN = "AW20";
"TEST_10":   PN = "AW22"  !CDS_PN = "AW22";
DRAWING = "@baseboard_fab2_lib.baseboard_fab2(sch_1):page71";
BODY = "RES","I43": #LOCATION = "R3D27" !CDS_LOCATION = "R3D27" #SEC = "1" !CDS_SEC = "1";
"A":   PN = "1"  !CDS_PN = "1";
"B":   PN = "2"  !CDS_PN = "2";
BODY = "RES","I49": #LOCATION = "RT8P1" !CDS_LOCATION = "RT8P1" #SEC = "1" !CDS_SEC = "1";
"A":   PN = "1"  !CDS_PN = "1";
"B":   PN = "2"  !CDS_PN = "2";
BODY = "SKX_EXT_B","I50": #LOCATION = "U2D1" !CDS_LOCATION = "U2D1" #SEC = "18" !CDS_SEC = "18";
"VCCIN<130>":   PN = "BN78"  !CDS_PN = "BN78";
"VCCIN<131>":   PN = "BN76"  !CDS_PN = "BN76";
"VCCIN<132>":   PN = "BN74"  !CDS_PN = "BN74";
"VCCIN<133>":   PN = "BN72"  !CDS_PN = "BN72";
"VCCIN<134>":   PN = "BN70"  !CDS_PN = "BN70";
"VCCIN<135>":   PN = "BN68"  !CDS_PN = "BN68";
"VCCIN<136>":   PN = "BN66"  !CDS_PN = "BN66";
"VCCIN<137>":   PN = "BN64"  !CDS_PN = "BN64";
"VCCIN<138>":   PN = "BN62"  !CDS_PN = "BN62";
"VCCIN<139>":   PN = "BN60"  !CDS_PN = "BN60";
"VCCIN<140>":   PN = "BM83"  !CDS_PN = "BM83";
"VCCIN<141>":   PN = "BM81"  !CDS_PN = "BM81";
"VCCIN<142>":   PN = "BM79"  !CDS_PN = "BM79";
"VCCIN<143>":   PN = "BM77"  !CDS_PN = "BM77";
"VCCIN<144>":   PN = "BM75"  !CDS_PN = "BM75";
"VCCIN<145>":   PN = "BM73"  !CDS_PN = "BM73";
"VCCIN<146>":   PN = "BM71"  !CDS_PN = "BM71";
"VCCIN<147>":   PN = "BM69"  !CDS_PN = "BM69";
"VCCIN<148>":   PN = "BM67"  !CDS_PN = "BM67";
"VCCIN<149>":   PN = "BM65"  !CDS_PN = "BM65";
"VCCIN<150>":   PN = "BM63"  !CDS_PN = "BM63";
"VCCIN<151>":   PN = "BM61"  !CDS_PN = "BM61";
"VCCIN<152>":   PN = "BL84"  !CDS_PN = "BL84";
"VCCIN<153>":   PN = "BL62"  !CDS_PN = "BL62";
"VCCIN<154>":   PN = "BL60"  !CDS_PN = "BL60";
"VCCIN<155>":   PN = "BK83"  !CDS_PN = "BK83";
"VCCIN<156>":   PN = "BK81"  !CDS_PN = "BK81";
"VCCIN<157>":   PN = "BK79"  !CDS_PN = "BK79";
"VCCIN<158>":   PN = "BK77"  !CDS_PN = "BK77";
"VCCIN<159>":   PN = "BK75"  !CDS_PN = "BK75";
"VCCIN<160>":   PN = "BK73"  !CDS_PN = "BK73";
"VCCIN<161>":   PN = "BK71"  !CDS_PN = "BK71";
"VCCIN<162>":   PN = "BK69"  !CDS_PN = "BK69";
"VCCIN<163>":   PN = "BK67"  !CDS_PN = "BK67";
"VCCIN<164>":   PN = "BK65"  !CDS_PN = "BK65";
"VCCIN<165>":   PN = "BK63"  !CDS_PN = "BK63";
"VCCIN<166>":   PN = "BK61"  !CDS_PN = "BK61";
"VCCIN<167>":   PN = "BJ84"  !CDS_PN = "BJ84";
"VCCIN<168>":   PN = "BJ82"  !CDS_PN = "BJ82";
"VCCIN<169>":   PN = "BJ80"  !CDS_PN = "BJ80";
"VCCIN<170>":   PN = "BJ78"  !CDS_PN = "BJ78";
"VCCIN<171>":   PN = "BJ76"  !CDS_PN = "BJ76";
"VCCIN<172>":   PN = "BJ74"  !CDS_PN = "BJ74";
"VCCIN<173>":   PN = "BJ72"  !CDS_PN = "BJ72";
"VCCIN<174>":   PN = "BJ70"  !CDS_PN = "BJ70";
"VCCIN<175>":   PN = "BJ68"  !CDS_PN = "BJ68";
"VCCIN<176>":   PN = "BJ66"  !CDS_PN = "BJ66";
"VCCIN<177>":   PN = "BJ64"  !CDS_PN = "BJ64";
"VCCIN<178>":   PN = "BJ62"  !CDS_PN = "BJ62";
"VCCIN<179>":   PN = "BJ60"  !CDS_PN = "BJ60";
"VCCIN<180>":   PN = "BH83"  !CDS_PN = "BH83";
"VCCIN<181>":   PN = "BH81"  !CDS_PN = "BH81";
"VCCIN<182>":   PN = "BH79"  !CDS_PN = "BH79";
"VCCIN<183>":   PN = "BH77"  !CDS_PN = "BH77";
"VCCIN<184>":   PN = "BH75"  !CDS_PN = "BH75";
"VCCIN<185>":   PN = "BH73"  !CDS_PN = "BH73";
"VCCIN<186>":   PN = "BH71"  !CDS_PN = "BH71";
"VCCIN<187>":   PN = "BH69"  !CDS_PN = "BH69";
"VCCIN<188>":   PN = "BH67"  !CDS_PN = "BH67";
"VCCIN<189>":   PN = "BH65"  !CDS_PN = "BH65";
"VCCIN<190>":   PN = "BH63"  !CDS_PN = "BH63";
"VCCIN<191>":   PN = "BH61"  !CDS_PN = "BH61";
"VCCIN<192>":   PN = "BG84"  !CDS_PN = "BG84";
"VCCIN<193>":   PN = "BG70"  !CDS_PN = "BG70";
"VCCIN<194>":   PN = "BG68"  !CDS_PN = "BG68";
"VCCIN<195>":   PN = "BG66"  !CDS_PN = "BG66";
"VCCIN<196>":   PN = "BG64"  !CDS_PN = "BG64";
"VCCIN<197>":   PN = "BG62"  !CDS_PN = "BG62";
"VCCIN<198>":   PN = "BG60"  !CDS_PN = "BG60";
"VCCIN<199>":   PN = "BF85"  !CDS_PN = "BF85";
"VCCIN<200>":   PN = "BF83"  !CDS_PN = "BF83";
"VCCIN<201>":   PN = "BF81"  !CDS_PN = "BF81";
"VCCIN<202>":   PN = "BF79"  !CDS_PN = "BF79";
"VCCIN<203>":   PN = "BF77"  !CDS_PN = "BF77";
"VCCIN<204>":   PN = "BF75"  !CDS_PN = "BF75";
"VCCIN<205>":   PN = "BF73"  !CDS_PN = "BF73";
"VCCIN<206>":   PN = "BF61"  !CDS_PN = "BF61";
"VCCIN<207>":   PN = "BE84"  !CDS_PN = "BE84";
"VCCIN<208>":   PN = "BE82"  !CDS_PN = "BE82";
"VCCIN<209>":   PN = "BE80"  !CDS_PN = "BE80";
"VCCIN<210>":   PN = "BE78"  !CDS_PN = "BE78";
"VCCIN<211>":   PN = "BE76"  !CDS_PN = "BE76";
"VCCIN<212>":   PN = "BE74"  !CDS_PN = "BE74";
"VCCIN<213>":   PN = "BE72"  !CDS_PN = "BE72";
"VCCIN<214>":   PN = "BE62"  !CDS_PN = "BE62";
"VCCIN<215>":   PN = "BE60"  !CDS_PN = "BE60";
"VCCIN<216>":   PN = "BD85"  !CDS_PN = "BD85";
"VCCIN<217>":   PN = "BD83"  !CDS_PN = "BD83";
"VCCIN<218>":   PN = "BD81"  !CDS_PN = "BD81";
"VCCIN<219>":   PN = "BD79"  !CDS_PN = "BD79";
"VCCIN<220>":   PN = "BD77"  !CDS_PN = "BD77";
"VCCIN<221>":   PN = "BD75"  !CDS_PN = "BD75";
"VCCIN<222>":   PN = "BD73"  !CDS_PN = "BD73";
"VCCIN<223>":   PN = "BD61"  !CDS_PN = "BD61";
"VCCIN<224>":   PN = "BC84"  !CDS_PN = "BC84";
"VCCIN<225>":   PN = "BC62"  !CDS_PN = "BC62";
"VCCIN<226>":   PN = "BC60"  !CDS_PN = "BC60";
"VCCIN<227>":   PN = "BB85"  !CDS_PN = "BB85";
"VCCIN<228>":   PN = "BB61"  !CDS_PN = "BB61";
"VCCIN<229>":   PN = "BA60"  !CDS_PN = "BA60";
"VCCIN<230>":   PN = "AY61"  !CDS_PN = "AY61";
"VCCIN<231>":   PN = "AW60"  !CDS_PN = "AW60";
"VCCIN<232>":   PN = "AV61"  !CDS_PN = "AV61";
"VCCIN<233>":   PN = "AV59"  !CDS_PN = "AV59";
"VCCIN<234>":   PN = "AU60"  !CDS_PN = "AU60";
"VCCIN<235>":   PN = "AU58"  !CDS_PN = "AU58";
"VCCIN<236>":   PN = "AT59"  !CDS_PN = "AT59";
"VCCIN<237>":   PN = "AT57"  !CDS_PN = "AT57";
"VCCIN<238>":   PN = "AR58"  !CDS_PN = "AR58";
"VCCIN<239>":   PN = "AR56"  !CDS_PN = "AR56";
"VCCIN<240>":   PN = "AP57"  !CDS_PN = "AP57";
"VCCIN<241>":   PN = "AP55"  !CDS_PN = "AP55";
"VCCIN<242>":   PN = "AN56"  !CDS_PN = "AN56";
"VCCIN<243>":   PN = "AN54"  !CDS_PN = "AN54";
"VCCIN<244>":   PN = "AN32"  !CDS_PN = "AN32";
"VCCIN<245>":   PN = "AM55"  !CDS_PN = "AM55";
"VCCIN<246>":   PN = "AM53"  !CDS_PN = "AM53";
"VCCIN<247>":   PN = "AM33"  !CDS_PN = "AM33";
"VCCIN<248>":   PN = "AL54"  !CDS_PN = "AL54";
"VCCIN<249>":   PN = "AL52"  !CDS_PN = "AL52";
"VCCIN<250>":   PN = "AL50"  !CDS_PN = "AL50";
"VCCIN<251>":   PN = "AL48"  !CDS_PN = "AL48";
"VCCIN<252>":   PN = "AL46"  !CDS_PN = "AL46";
"VCCIN<253>":   PN = "AL34"  !CDS_PN = "AL34";
"VCCIN<254>":   PN = "AK53"  !CDS_PN = "AK53";
"VCCIN<255>":   PN = "AK51"  !CDS_PN = "AK51";
"VCCIN<256>":   PN = "AK49"  !CDS_PN = "AK49";
"VCCIN<257>":   PN = "AK47"  !CDS_PN = "AK47";
"VCCIN<258>":   PN = "AK45"  !CDS_PN = "AK45";
"VCCIN<259>":   PN = "AK35"  !CDS_PN = "AK35";
"VCCIN<260>":   PN = "AJ36"  !CDS_PN = "AJ36";
"VCCIN<261>":   PN = "AH41"  !CDS_PN = "AH41";
"VCCIN<262>":   PN = "AH39"  !CDS_PN = "AH39";
"VCCIN<263>":   PN = "AH37"  !CDS_PN = "AH37";
"VCCIN<264>":   PN = "AG42"  !CDS_PN = "AG42";
"VCCIN<265>":   PN = "AG40"  !CDS_PN = "AG40";
"VCCIN<266>":   PN = "AG38"  !CDS_PN = "AG38";
"VCCIN<267>":   PN = "AF43"  !CDS_PN = "AF43";
BODY = "SKX_EXT_B","I51": #LOCATION = "U2D1" !CDS_LOCATION = "U2D1" #SEC = "19" !CDS_SEC = "19";
"VCCIN<0>":   PN = "CY49"  !CDS_PN = "CY49";
"VCCIN<1>":   PN = "CY47"  !CDS_PN = "CY47";
"VCCIN<2>":   PN = "CW50"  !CDS_PN = "CW50";
"VCCIN<3>":   PN = "CW48"  !CDS_PN = "CW48";
"VCCIN<4>":   PN = "CW46"  !CDS_PN = "CW46";
"VCCIN<5>":   PN = "CV51"  !CDS_PN = "CV51";
"VCCIN<6>":   PN = "CU54"  !CDS_PN = "CU54";
"VCCIN<7>":   PN = "CU52"  !CDS_PN = "CU52";
"VCCIN<8>":   PN = "CU42"  !CDS_PN = "CU42";
"VCCIN<9>":   PN = "CU40"  !CDS_PN = "CU40";
"VCCIN<10>":   PN = "CU38"  !CDS_PN = "CU38";
"VCCIN<11>":   PN = "CT55"  !CDS_PN = "CT55";
"VCCIN<12>":   PN = "CT53"  !CDS_PN = "CT53";
"VCCIN<13>":   PN = "CT41"  !CDS_PN = "CT41";
"VCCIN<14>":   PN = "CT39"  !CDS_PN = "CT39";
"VCCIN<15>":   PN = "CT37"  !CDS_PN = "CT37";
"VCCIN<16>":   PN = "CR56"  !CDS_PN = "CR56";
"VCCIN<17>":   PN = "CR54"  !CDS_PN = "CR54";
"VCCIN<18>":   PN = "CR34"  !CDS_PN = "CR34";
"VCCIN<19>":   PN = "CP57"  !CDS_PN = "CP57";
"VCCIN<20>":   PN = "CP55"  !CDS_PN = "CP55";
"VCCIN<21>":   PN = "CP33"  !CDS_PN = "CP33";
"VCCIN<22>":   PN = "CN58"  !CDS_PN = "CN58";
"VCCIN<23>":   PN = "CN56"  !CDS_PN = "CN56";
"VCCIN<24>":   PN = "CM59"  !CDS_PN = "CM59";
"VCCIN<25>":   PN = "CM57"  !CDS_PN = "CM57";
"VCCIN<26>":   PN = "CL60"  !CDS_PN = "CL60";
"VCCIN<27>":   PN = "CL58"  !CDS_PN = "CL58";
"VCCIN<28>":   PN = "CK61"  !CDS_PN = "CK61";
"VCCIN<29>":   PN = "CK59"  !CDS_PN = "CK59";
"VCCIN<30>":   PN = "CJ60"  !CDS_PN = "CJ60";
"VCCIN<31>":   PN = "CH85"  !CDS_PN = "CH85";
"VCCIN<32>":   PN = "CH61"  !CDS_PN = "CH61";
"VCCIN<33>":   PN = "CG84"  !CDS_PN = "CG84";
"VCCIN<34>":   PN = "CG60"  !CDS_PN = "CG60";
"VCCIN<35>":   PN = "CF85"  !CDS_PN = "CF85";
"VCCIN<36>":   PN = "CF61"  !CDS_PN = "CF61";
"VCCIN<37>":   PN = "CE84"  !CDS_PN = "CE84";
"VCCIN<38>":   PN = "CE60"  !CDS_PN = "CE60";
"VCCIN<39>":   PN = "CD85"  !CDS_PN = "CD85";
"VCCIN<40>":   PN = "CD83"  !CDS_PN = "CD83";
"VCCIN<41>":   PN = "CD61"  !CDS_PN = "CD61";
"VCCIN<42>":   PN = "CC84"  !CDS_PN = "CC84";
"VCCIN<43>":   PN = "CC62"  !CDS_PN = "CC62";
"VCCIN<44>":   PN = "CC60"  !CDS_PN = "CC60";
"VCCIN<45>":   PN = "CB83"  !CDS_PN = "CB83";
"VCCIN<46>":   PN = "CB81"  !CDS_PN = "CB81";
"VCCIN<47>":   PN = "CB79"  !CDS_PN = "CB79";
"VCCIN<48>":   PN = "CB77"  !CDS_PN = "CB77";
"VCCIN<49>":   PN = "CB75"  !CDS_PN = "CB75";
"VCCIN<50>":   PN = "CB73"  !CDS_PN = "CB73";
"VCCIN<51>":   PN = "CB61"  !CDS_PN = "CB61";
"VCCIN<52>":   PN = "CA84"  !CDS_PN = "CA84";
"VCCIN<53>":   PN = "CA82"  !CDS_PN = "CA82";
"VCCIN<54>":   PN = "CA80"  !CDS_PN = "CA80";
"VCCIN<55>":   PN = "CA78"  !CDS_PN = "CA78";
"VCCIN<56>":   PN = "CA76"  !CDS_PN = "CA76";
"VCCIN<57>":   PN = "CA74"  !CDS_PN = "CA74";
"VCCIN<58>":   PN = "CA72"  !CDS_PN = "CA72";
"VCCIN<59>":   PN = "CA62"  !CDS_PN = "CA62";
"VCCIN<60>":   PN = "CA60"  !CDS_PN = "CA60";
"VCCIN<61>":   PN = "BY83"  !CDS_PN = "BY83";
"VCCIN<62>":   PN = "BY81"  !CDS_PN = "BY81";
"VCCIN<63>":   PN = "BY79"  !CDS_PN = "BY79";
"VCCIN<64>":   PN = "BY77"  !CDS_PN = "BY77";
"VCCIN<65>":   PN = "BY75"  !CDS_PN = "BY75";
"VCCIN<66>":   PN = "BY73"  !CDS_PN = "BY73";
"VCCIN<67>":   PN = "BY61"  !CDS_PN = "BY61";
"VCCIN<68>":   PN = "BW84"  !CDS_PN = "BW84";
"VCCIN<69>":   PN = "BW70"  !CDS_PN = "BW70";
"VCCIN<70>":   PN = "BW68"  !CDS_PN = "BW68";
"VCCIN<71>":   PN = "BW66"  !CDS_PN = "BW66";
"VCCIN<72>":   PN = "BW64"  !CDS_PN = "BW64";
"VCCIN<73>":   PN = "BW62"  !CDS_PN = "BW62";
"VCCIN<74>":   PN = "BW60"  !CDS_PN = "BW60";
"VCCIN<75>":   PN = "BV83"  !CDS_PN = "BV83";
"VCCIN<76>":   PN = "BV81"  !CDS_PN = "BV81";
"VCCIN<77>":   PN = "BV79"  !CDS_PN = "BV79";
"VCCIN<78>":   PN = "BV77"  !CDS_PN = "BV77";
"VCCIN<79>":   PN = "BV75"  !CDS_PN = "BV75";
"VCCIN<80>":   PN = "BV73"  !CDS_PN = "BV73";
"VCCIN<81>":   PN = "BV71"  !CDS_PN = "BV71";
"VCCIN<82>":   PN = "BV69"  !CDS_PN = "BV69";
"VCCIN<83>":   PN = "BV67"  !CDS_PN = "BV67";
"VCCIN<84>":   PN = "BV65"  !CDS_PN = "BV65";
"VCCIN<85>":   PN = "BV63"  !CDS_PN = "BV63";
"VCCIN<86>":   PN = "BV61"  !CDS_PN = "BV61";
"VCCIN<87>":   PN = "BU84"  !CDS_PN = "BU84";
"VCCIN<88>":   PN = "BU82"  !CDS_PN = "BU82";
"VCCIN<89>":   PN = "BU80"  !CDS_PN = "BU80";
"VCCIN<90>":   PN = "BU78"  !CDS_PN = "BU78";
"VCCIN<91>":   PN = "BU76"  !CDS_PN = "BU76";
"VCCIN<92>":   PN = "BU74"  !CDS_PN = "BU74";
"VCCIN<93>":   PN = "BU72"  !CDS_PN = "BU72";
"VCCIN<94>":   PN = "BU70"  !CDS_PN = "BU70";
"VCCIN<95>":   PN = "BU68"  !CDS_PN = "BU68";
"VCCIN<96>":   PN = "BU66"  !CDS_PN = "BU66";
"VCCIN<97>":   PN = "BU64"  !CDS_PN = "BU64";
"VCCIN<98>":   PN = "BU62"  !CDS_PN = "BU62";
"VCCIN<99>":   PN = "BU60"  !CDS_PN = "BU60";
"VCCIN<100>":   PN = "BT83"  !CDS_PN = "BT83";
"VCCIN<101>":   PN = "BT81"  !CDS_PN = "BT81";
"VCCIN<102>":   PN = "BT79"  !CDS_PN = "BT79";
"VCCIN<103>":   PN = "BT77"  !CDS_PN = "BT77";
"VCCIN<104>":   PN = "BT75"  !CDS_PN = "BT75";
"VCCIN<105>":   PN = "BT73"  !CDS_PN = "BT73";
"VCCIN<106>":   PN = "BT71"  !CDS_PN = "BT71";
"VCCIN<107>":   PN = "BT69"  !CDS_PN = "BT69";
"VCCIN<108>":   PN = "BT67"  !CDS_PN = "BT67";
"VCCIN<109>":   PN = "BT65"  !CDS_PN = "BT65";
"VCCIN<110>":   PN = "BT63"  !CDS_PN = "BT63";
"VCCIN<111>":   PN = "BT61"  !CDS_PN = "BT61";
"VCCIN<112>":   PN = "BR84"  !CDS_PN = "BR84";
"VCCIN<113>":   PN = "BR62"  !CDS_PN = "BR62";
"VCCIN<114>":   PN = "BR60"  !CDS_PN = "BR60";
"VCCIN<115>":   PN = "BP83"  !CDS_PN = "BP83";
"VCCIN<116>":   PN = "BP81"  !CDS_PN = "BP81";
"VCCIN<117>":   PN = "BP79"  !CDS_PN = "BP79";
"VCCIN<118>":   PN = "BP77"  !CDS_PN = "BP77";
"VCCIN<119>":   PN = "BP75"  !CDS_PN = "BP75";
"VCCIN<120>":   PN = "BP73"  !CDS_PN = "BP73";
"VCCIN<121>":   PN = "BP71"  !CDS_PN = "BP71";
"VCCIN<122>":   PN = "BP69"  !CDS_PN = "BP69";
"VCCIN<123>":   PN = "BP67"  !CDS_PN = "BP67";
"VCCIN<124>":   PN = "BP65"  !CDS_PN = "BP65";
"VCCIN<125>":   PN = "BP63"  !CDS_PN = "BP63";
"VCCIN<126>":   PN = "BP61"  !CDS_PN = "BP61";
"VCCIN<127>":   PN = "BN84"  !CDS_PN = "BN84";
"VCCIN<128>":   PN = "BN82"  !CDS_PN = "BN82";
"VCCIN<129>":   PN = "BN80"  !CDS_PN = "BN80";
"VCCIN_SENSE":   PN = "BA86"  !CDS_PN = "BA86";
"VCCINPMAX<0>":   PN = "AW86"  !CDS_PN = "AW86";
"VCCINPMAX<1>":   PN = "AV85"  !CDS_PN = "AV85";
"VSENSEPMAX":   PN = "AD41"  !CDS_PN = "AD41";
"VSS_VCCIN_SENSE":   PN = "AY85"  !CDS_PN = "AY85";
BODY = "RES","I53": #LOCATION = "R3D32" !CDS_LOCATION = "R3D32" #SEC = "1" !CDS_SEC = "1";
"A":   PN = "1"  !CDS_PN = "1";
"B":   PN = "2"  !CDS_PN = "2";
DRAWING = "@baseboard_fab2_lib.baseboard_fab2(sch_1):page72";
BODY = "CAP","I25": #LOCATION = "C3D3" !CDS_LOCATION = "C3D3" &SEC = "1" #&CDS_SEC = "1";
"A":   PN = "1"  !CDS_PN = "1";
"B":   PN = "2"  !CDS_PN = "2";
BODY = "SKX_EXT_B","I32": #LOCATION = "U2D1" !CDS_LOCATION = "U2D1" #SEC = "20" !CDS_SEC = "20";
"VCCD012<0>":   PN = "B49"  !CDS_PN = "B49";
"VCCD012<1>":   PN = "B53"  !CDS_PN = "B53";
"VCCD012<2>":   PN = "B59"  !CDS_PN = "B59";
"VCCD012<3>":   PN = "E46"  !CDS_PN = "E46";
"VCCD012<4>":   PN = "E48"  !CDS_PN = "E48";
"VCCD012<5>":   PN = "E50"  !CDS_PN = "E50";
"VCCD012<6>":   PN = "E52"  !CDS_PN = "E52";
"VCCD012<7>":   PN = "E54"  !CDS_PN = "E54";
"VCCD012<8>":   PN = "E56"  !CDS_PN = "E56";
"VCCD012<9>":   PN = "E58"  !CDS_PN = "E58";
"VCCD012<10>":   PN = "E60"  !CDS_PN = "E60";
"VCCD012<11>":   PN = "E62"  !CDS_PN = "E62";
"VCCD012<12>":   PN = "E64"  !CDS_PN = "E64";
"VCCD012<13>":   PN = "L46"  !CDS_PN = "L46";
"VCCD012<14>":   PN = "L48"  !CDS_PN = "L48";
"VCCD012<15>":   PN = "L50"  !CDS_PN = "L50";
"VCCD012<16>":   PN = "L52"  !CDS_PN = "L52";
"VCCD012<17>":   PN = "L54"  !CDS_PN = "L54";
"VCCD012<18>":   PN = "L56"  !CDS_PN = "L56";
"VCCD012<19>":   PN = "L58"  !CDS_PN = "L58";
"VCCD012<20>":   PN = "L60"  !CDS_PN = "L60";
"VCCD012<21>":   PN = "L62"  !CDS_PN = "L62";
"VCCD012<22>":   PN = "N64"  !CDS_PN = "N64";
"VCCD012<23>":   PN = "U46"  !CDS_PN = "U46";
"VCCD012<24>":   PN = "U48"  !CDS_PN = "U48";
"VCCD012<25>":   PN = "U50"  !CDS_PN = "U50";
"VCCD012<26>":   PN = "U52"  !CDS_PN = "U52";
"VCCD012<27>":   PN = "U54"  !CDS_PN = "U54";
"VCCD012<28>":   PN = "U56"  !CDS_PN = "U56";
"VCCD012<29>":   PN = "U58"  !CDS_PN = "U58";
"VCCD012<30>":   PN = "U60"  !CDS_PN = "U60";
"VCCD012<31>":   PN = "U62"  !CDS_PN = "U62";
"VCCD012<32>":   PN = "W64"  !CDS_PN = "W64";
"VCCD012<33>":   PN = "Y45"  !CDS_PN = "Y45";
"VCCD012<34>":   PN = "Y47"  !CDS_PN = "Y47";
"VCCD012<35>":   PN = "Y49"  !CDS_PN = "Y49";
"VCCD012<36>":   PN = "Y51"  !CDS_PN = "Y51";
"VCCD012<37>":   PN = "Y53"  !CDS_PN = "Y53";
"VCCD012<38>":   PN = "Y55"  !CDS_PN = "Y55";
"VCCD012<39>":   PN = "Y57"  !CDS_PN = "Y57";
"VCCD012<40>":   PN = "Y59"  !CDS_PN = "Y59";
"VCCD012<41>":   PN = "Y61"  !CDS_PN = "Y61";
"VCCD012<42>":   PN = "Y63"  !CDS_PN = "Y63";
"VCCD012<43>":   PN = "AD45"  !CDS_PN = "AD45";
"VCCD012<44>":   PN = "AF55"  !CDS_PN = "AF55";
"VCCD012<45>":   PN = "AF57"  !CDS_PN = "AF57";
"VCCD012<46>":   PN = "AF59"  !CDS_PN = "AF59";
"VCCD012<47>":   PN = "AF61"  !CDS_PN = "AF61";
"VCCD012<48>":   PN = "AF63"  !CDS_PN = "AF63";
"VCCD012<49>":   PN = "D45"  !CDS_PN = "D45";
"VCCD012<50>":   PN = "C46"  !CDS_PN = "C46";
"VCCD012<51>":   PN = "B47"  !CDS_PN = "B47";
"VCCD345<0>":   PN = "EF59"  !CDS_PN = "EF59";
"VCCD345<1>":   PN = "EF53"  !CDS_PN = "EF53";
"VCCD345<2>":   PN = "EF49"  !CDS_PN = "EF49";
"VCCD345<3>":   PN = "EC62"  !CDS_PN = "EC62";
"VCCD345<4>":   PN = "EC60"  !CDS_PN = "EC60";
"VCCD345<5>":   PN = "EC58"  !CDS_PN = "EC58";
"VCCD345<6>":   PN = "EC56"  !CDS_PN = "EC56";
"VCCD345<7>":   PN = "EC54"  !CDS_PN = "EC54";
"VCCD345<8>":   PN = "EC52"  !CDS_PN = "EC52";
"VCCD345<9>":   PN = "EC50"  !CDS_PN = "EC50";
"VCCD345<10>":   PN = "EC48"  !CDS_PN = "EC48";
"VCCD345<11>":   PN = "EC46"  !CDS_PN = "EC46";
"VCCD345<12>":   PN = "DU64"  !CDS_PN = "DU64";
"VCCD345<13>":   PN = "DU62"  !CDS_PN = "DU62";
"VCCD345<14>":   PN = "DU60"  !CDS_PN = "DU60";
"VCCD345<15>":   PN = "DU58"  !CDS_PN = "DU58";
"VCCD345<16>":   PN = "DU56"  !CDS_PN = "DU56";
"VCCD345<17>":   PN = "DU54"  !CDS_PN = "DU54";
"VCCD345<18>":   PN = "DU52"  !CDS_PN = "DU52";
"VCCD345<19>":   PN = "DU50"  !CDS_PN = "DU50";
"VCCD345<20>":   PN = "DU48"  !CDS_PN = "DU48";
"VCCD345<21>":   PN = "DU46"  !CDS_PN = "DU46";
"VCCD345<22>":   PN = "DL62"  !CDS_PN = "DL62";
"VCCD345<23>":   PN = "DL60"  !CDS_PN = "DL60";
"VCCD345<24>":   PN = "DL58"  !CDS_PN = "DL58";
"VCCD345<25>":   PN = "DL56"  !CDS_PN = "DL56";
"VCCD345<26>":   PN = "DL54"  !CDS_PN = "DL54";
"VCCD345<27>":   PN = "DL52"  !CDS_PN = "DL52";
"VCCD345<28>":   PN = "DL50"  !CDS_PN = "DL50";
"VCCD345<29>":   PN = "DL48"  !CDS_PN = "DL48";
"VCCD345<30>":   PN = "DL46"  !CDS_PN = "DL46";
"VCCD345<31>":   PN = "DJ64"  !CDS_PN = "DJ64";
"VCCD345<32>":   PN = "DH63"  !CDS_PN = "DH63";
"VCCD345<33>":   PN = "DH61"  !CDS_PN = "DH61";
"VCCD345<34>":   PN = "DH59"  !CDS_PN = "DH59";
"VCCD345<35>":   PN = "DH57"  !CDS_PN = "DH57";
"VCCD345<36>":   PN = "DH55"  !CDS_PN = "DH55";
"VCCD345<37>":   PN = "DH53"  !CDS_PN = "DH53";
"VCCD345<38>":   PN = "DH51"  !CDS_PN = "DH51";
"VCCD345<39>":   PN = "DH49"  !CDS_PN = "DH49";
"VCCD345<40>":   PN = "DH47"  !CDS_PN = "DH47";
"VCCD345<41>":   PN = "DH45"  !CDS_PN = "DH45";
"VCCD345<42>":   PN = "DD45"  !CDS_PN = "DD45";
"VCCD345<43>":   PN = "DB63"  !CDS_PN = "DB63";
"VCCD345<44>":   PN = "DB61"  !CDS_PN = "DB61";
"VCCD345<45>":   PN = "DB59"  !CDS_PN = "DB59";
"VCCD345<46>":   PN = "DB57"  !CDS_PN = "DB57";
"VCCD345<47>":   PN = "DB55"  !CDS_PN = "DB55";
"VCCD345<48>":   PN = "DB53"  !CDS_PN = "DB53";
"VCCD345<49>":   PN = "EF45"  !CDS_PN = "EF45";
"VCCD345<50>":   PN = "EE44"  !CDS_PN = "EE44";
BODY = "SKX_EXT_B","I33": #LOCATION = "U2D1" !CDS_LOCATION = "U2D1" #SEC = "21" !CDS_SEC = "21";
"CD_VCC_CORE<0>":   PN = "BL14"  !CDS_PN = "BL14";
"CD_VCC_CORE<1>":   PN = "BK15"  !CDS_PN = "BK15";
"CD_VCC_CORE<2>":   PN = "BK13"  !CDS_PN = "BK13";
"CD_VCC_CORE<3>":   PN = "BJ14"  !CDS_PN = "BJ14";
"CD_VCC_CORE<4>":   PN = "BJ12"  !CDS_PN = "BJ12";
"CD_VCC_CORE<5>":   PN = "BH13"  !CDS_PN = "BH13";
"CD_VCC_CORE<6>":   PN = "BG14"  !CDS_PN = "BG14";
"CD_VCC_CORE<7>":   PN = "BG12"  !CDS_PN = "BG12";
"CD_VCC_CORE<8>":   PN = "BF13"  !CDS_PN = "BF13";
"CD_VCC_CORE<9>":   PN = "BF11"  !CDS_PN = "BF11";
"CD_VCC_CORE<10>":   PN = "BE14"  !CDS_PN = "BE14";
"CD_VCC_CORE<11>":   PN = "BE12"  !CDS_PN = "BE12";
"CD_VCC_CORE<12>":   PN = "BD13"  !CDS_PN = "BD13";
"CD_VCCIN<0>":   PN = "BT27"  !CDS_PN = "BT27";
"CD_VCCIN<1>":   PN = "BU26"  !CDS_PN = "BU26";
"CD_VCCIN<2>":   PN = "BV27"  !CDS_PN = "BV27";
"CD_VCCIN<3>":   PN = "BY27"  !CDS_PN = "BY27";
"CD_VCCP<0>":   PN = "BV15"  !CDS_PN = "BV15";
"CD_VCCP<1>":   PN = "BV13"  !CDS_PN = "BV13";
"CD_VCCP<2>":   PN = "BV11"  !CDS_PN = "BV11";
"CD_VCCP<3>":   PN = "BU14"  !CDS_PN = "BU14";
"CD_VCCP<4>":   PN = "BU12"  !CDS_PN = "BU12";
"CD_VCCP<5>":   PN = "BT15"  !CDS_PN = "BT15";
"CD_VCCP<6>":   PN = "BT13"  !CDS_PN = "BT13";
"CD_VCCP<7>":   PN = "BT11"  !CDS_PN = "BT11";
"CD_VCCP<8>":   PN = "BR14"  !CDS_PN = "BR14";
"CD_VCCP<9>":   PN = "BR12"  !CDS_PN = "BR12";
"CD_VCCP<10>":   PN = "BP15"  !CDS_PN = "BP15";
"CD_VCCP<11>":   PN = "BP13"  !CDS_PN = "BP13";
"CD_VCCP<12>":   PN = "BP11"  !CDS_PN = "BP11";
"CD_VCCP<13>":   PN = "BN14"  !CDS_PN = "BN14";
"CD_VCCP<14>":   PN = "BN12"  !CDS_PN = "BN12";
"CD_VCCP<15>":   PN = "BM11"  !CDS_PN = "BM11";
"CD_VPP<0>":   PN = "B11"  !CDS_PN = "B11";
"CD_VPP<1>":   PN = "A12"  !CDS_PN = "A12";
"CD_VPP<2>":   PN = "A10"  !CDS_PN = "A10";
"CD_VPP<3>":   PN = "A8"  !CDS_PN = "A8";
"VCC33":   PN = "CY55"  !CDS_PN = "CY55";
"VCCIO<20>":   PN = "CM15"  !CDS_PN = "CM15";
"VCCIO<21>":   PN = "CL12"  !CDS_PN = "CL12";
"VCCIO<22>":   PN = "CK5"  !CDS_PN = "CK5";
"VCCIO<23>":   PN = "CV7"  !CDS_PN = "CV7";
"VCCIO<24>":   PN = "CH9"  !CDS_PN = "CH9";
"VCCIO<25>":   PN = "D7"  !CDS_PN = "D7";
"VCCIO<26>":   PN = "CE18"  !CDS_PN = "CE18";
"VCCIO<27>":   PN = "CD9"  !CDS_PN = "CD9";
"VCCIO<28>":   PN = "CB17"  !CDS_PN = "CB17";
"VCCIO<29>":   PN = "CB13"  !CDS_PN = "CB13";
"VCCIO<30>":   PN = "BP25"  !CDS_PN = "BP25";
"VCCIO<31>":   PN = "BJ24"  !CDS_PN = "BJ24";
"VCCIO<32>":   PN = "BF23"  !CDS_PN = "BF23";
"VCCIO<33>":   PN = "DA14"  !CDS_PN = "DA14";
"VCCIO<34>":   PN = "BB5"  !CDS_PN = "BB5";
"VCCIO<35>":   PN = "BA24"  !CDS_PN = "BA24";
"VCCIO<36>":   PN = "AY11"  !CDS_PN = "AY11";
"VCCIO<37>":   PN = "AW6"  !CDS_PN = "AW6";
"VCCIO<38>":   PN = "AT11"  !CDS_PN = "AT11";
"VCCIO<39>":   PN = "DD7"  !CDS_PN = "DD7";
"VCCIO<40>":   PN = "AN10"  !CDS_PN = "AN10";
"VCCIO<41>":   PN = "DF13"  !CDS_PN = "DF13";
"VCCIO<42>":   PN = "AH9"  !CDS_PN = "AH9";
"VCCIO<43>":   PN = "AC4"  !CDS_PN = "AC4";
"VCCIO<44>":   PN = "AC20"  !CDS_PN = "AC20";
"VCCIO<45>":   PN = "AA10"  !CDS_PN = "AA10";
"VCCIO<46>":   PN = "W6"  !CDS_PN = "W6";
"VCCIO<47>":   PN = "W4"  !CDS_PN = "W4";
"VCCIO<48>":   PN = "DF21"  !CDS_PN = "DF21";
"VCCIO<49>":   PN = "U14"  !CDS_PN = "U14";
"VCCIO<50>":   PN = "T3"  !CDS_PN = "T3";
"VCCIO<51>":   PN = "P5"  !CDS_PN = "P5";
"VCCIO<52>":   PN = "M21"  !CDS_PN = "M21";
"VCCIO<53>":   PN = "M11"  !CDS_PN = "M11";
"VCCIO<54>":   PN = "DG8"  !CDS_PN = "DG8";
"VCCIO<55>":   PN = "DH7"  !CDS_PN = "DH7";
"VCCIO<56>":   PN = "L16"  !CDS_PN = "L16";
"VCCIO<57>":   PN = "L14"  !CDS_PN = "L14";
"VCCIO<58>":   PN = "J10"  !CDS_PN = "J10";
"VCCIO<59>":   PN = "H13"  !CDS_PN = "H13";
"VCCIO<60>":   PN = "DJ16"  !CDS_PN = "DJ16";
"VCCIO<61>":   PN = "DM17"  !CDS_PN = "DM17";
"VCCIO<62>":   PN = "DN8"  !CDS_PN = "DN8";
"VCCIO<63>":   PN = "DP19"  !CDS_PN = "DP19";
"VCCIO<64>":   PN = "DR10"  !CDS_PN = "DR10";
"VCCIO<65>":   PN = "DR2"  !CDS_PN = "DR2";
"VCCIO<66>":   PN = "DU20"  !CDS_PN = "DU20";
"VCCIO<67>":   PN = "EA12"  !CDS_PN = "EA12";
"VCCIO<68>":   PN = "EB15"  !CDS_PN = "EB15";
"VCCIO<69>":   PN = "J2"  !CDS_PN = "J2";
"VCCIO<70>":   PN = "K15"  !CDS_PN = "K15";
"VCCIO<71>":   PN = "M7"  !CDS_PN = "M7";
"VCCIO<72>":   PN = "M9"  !CDS_PN = "M9";
"VCCIO<73>":   PN = "N18"  !CDS_PN = "N18";
"VCCIO<74>":   PN = "W10"  !CDS_PN = "W10";
"VCCIO<75>":   PN = "BC26"  !CDS_PN = "BC26";
"VCCIO<76>":   PN = "BB27"  !CDS_PN = "BB27";
"VCCIO<77>":   PN = "BA26"  !CDS_PN = "BA26";
"VCCIO<78>":   PN = "AY27"  !CDS_PN = "AY27";
"VCCIO<79>":   PN = "AW26"  !CDS_PN = "AW26";
"VCCIO<80>":   PN = "AV27"  !CDS_PN = "AV27";
"VCCIO<81>":   PN = "CF27"  !CDS_PN = "CF27";
"VCCIO<82>":   PN = "CD27"  !CDS_PN = "CD27";
"VCCIO<83>":   PN = "CC26"  !CDS_PN = "CC26";
"VCCIO<84>":   PN = "CJ28"  !CDS_PN = "CJ28";
"VCCIO<85>":   PN = "CH27"  !CDS_PN = "CH27";
"VCCIO<86>":   PN = "BM27"  !CDS_PN = "BM27";
"VCCIO<87>":   PN = "BL26"  !CDS_PN = "BL26";
"VCCIO<88>":   PN = "BK27"  !CDS_PN = "BK27";
"VCCIO<89>":   PN = "BK25"  !CDS_PN = "BK25";
"VCCIO<90>":   PN = "BJ26"  !CDS_PN = "BJ26";
"VCCIO<91>":   PN = "BH27"  !CDS_PN = "BH27";
"VCCIO<92>":   PN = "BH25"  !CDS_PN = "BH25";
"VCCIO<93>":   PN = "BG26"  !CDS_PN = "BG26";
"VCCIO<94>":   PN = "BF27"  !CDS_PN = "BF27";
"VCCIO<95>":   PN = "AE36"  !CDS_PN = "AE36";
"VCCIO<96>":   PN = "AD37"  !CDS_PN = "AD37";
"VCCIO<97>":   PN = "AC36"  !CDS_PN = "AC36";
"VCCIO<98>":   PN = "AF35"  !CDS_PN = "AF35";
"VCCIO<99>":   PN = "AD35"  !CDS_PN = "AD35";
"VCCIO<100>":   PN = "AE34"  !CDS_PN = "AE34";
"VCCIO<101>":   PN = "AG34"  !CDS_PN = "AG34";
"VCCIO<102>":   PN = "AM29"  !CDS_PN = "AM29";
"VCCIO<103>":   PN = "AL28"  !CDS_PN = "AL28";
"VCCIO<104>":   PN = "AR28"  !CDS_PN = "AR28";
"VCCSA<0>":   PN = "CJ66"  !CDS_PN = "CJ66";
"VCCSA<1>":   PN = "CJ64"  !CDS_PN = "CJ64";
"VCCSA<2>":   PN = "CH75"  !CDS_PN = "CH75";
"VCCSA<3>":   PN = "CH65"  !CDS_PN = "CH65";
"VCCSA<4>":   PN = "CG74"  !CDS_PN = "CG74";
"VCCSA<5>":   PN = "CG66"  !CDS_PN = "CG66";
"VCCSA<6>":   PN = "CG64"  !CDS_PN = "CG64";
"VCCSA<7>":   PN = "CF75"  !CDS_PN = "CF75";
"VCCSA<8>":   PN = "CF73"  !CDS_PN = "CF73";
"VCCSA<9>":   PN = "CF67"  !CDS_PN = "CF67";
"VCCSA<10>":   PN = "CF65"  !CDS_PN = "CF65";
"VCCSA<11>":   PN = "CE74"  !CDS_PN = "CE74";
"VCCSA<12>":   PN = "CE72"  !CDS_PN = "CE72";
"VCCSA<13>":   PN = "CE68"  !CDS_PN = "CE68";
"VCCSA<14>":   PN = "CE66"  !CDS_PN = "CE66";
"VCCSA<15>":   PN = "CE64"  !CDS_PN = "CE64";
"VCCSA<16>":   PN = "CD71"  !CDS_PN = "CD71";
"VCCSA<17>":   PN = "CD69"  !CDS_PN = "CD69";
"VCCSA<18>":   PN = "CD67"  !CDS_PN = "CD67";
"VCCSA<19>":   PN = "CD65"  !CDS_PN = "CD65";
"VCCSA<20>":   PN = "CC70"  !CDS_PN = "CC70";
"VCCSA<21>":   PN = "CC68"  !CDS_PN = "CC68";
"VCCSA<22>":   PN = "CC66"  !CDS_PN = "CC66";
"VCCSA<23>":   PN = "CB69"  !CDS_PN = "CB69";
"VCCSA<24>":   PN = "CB67"  !CDS_PN = "CB67";
"VCCSA<25>":   PN = "CB65"  !CDS_PN = "CB65";
DRAWING = "@baseboard_fab2_lib.baseboard_fab2(sch_1):page73";
BODY = "SKX_EXT_B","I107": #LOCATION = "U2D1" !CDS_LOCATION = "U2D1" #SEC = "22" !CDS_SEC = "22";
"CD_VCC_CORE_SENSE":   PN = "BN16"  !CDS_PN = "BN16";
"CD_VCCP_SENSE<0>":   PN = "BU16"  !CDS_PN = "BU16";
"CD_VCCP_SENSE<1>":   PN = "BT17"  !CDS_PN = "BT17";
"CD_VSS_VCC_CORE_SENSE":   PN = "BL16"  !CDS_PN = "BL16";
"RSVD<0>":   PN = "EF83"  !CDS_PN = "EF83";
"RSVD<1>":   PN = "EF81"  !CDS_PN = "EF81";
"RSVD<2>":   PN = "EF77"  !CDS_PN = "EF77";
"RSVD<3>":   PN = "EF47"  !CDS_PN = "EF47";
"RSVD<4>":   PN = "EE84"  !CDS_PN = "EE84";
"RSVD<5>":   PN = "EE82"  !CDS_PN = "EE82";
"RSVD<6>":   PN = "EE6"  !CDS_PN = "EE6";
"RSVD<7>":   PN = "EE46"  !CDS_PN = "EE46";
"RSVD<8>":   PN = "EE16"  !CDS_PN = "EE16";
"RSVD<9>":   PN = "ED83"  !CDS_PN = "ED83";
"RSVD<10>":   PN = "ED5"  !CDS_PN = "ED5";
"RSVD<11>":   PN = "ED45"  !CDS_PN = "ED45";
"RSVD<12>":   PN = "EC84"  !CDS_PN = "EC84";
"RSVD<13>":   PN = "EC44"  !CDS_PN = "EC44";
"RSVD<14>":   PN = "EC4"  !CDS_PN = "EC4";
"RSVD<15>":   PN = "EC16"  !CDS_PN = "EC16";
"RSVD<16>":   PN = "EB85"  !CDS_PN = "EB85";
"RSVD<17>":   PN = "EB5"  !CDS_PN = "EB5";
"RSVD<18>":   PN = "EB3"  !CDS_PN = "EB3";
"RSVD<19>":   PN = "EA44"  !CDS_PN = "EA44";
"RSVD<20>":   PN = "EA4"  !CDS_PN = "EA4";
"RSVD<21>":   PN = "DY3"  !CDS_PN = "DY3";
"RSVD<22>":   PN = "DW46"  !CDS_PN = "DW46";
"RSVD<23>":   PN = "DW44"  !CDS_PN = "DW44";
"RSVD<24>":   PN = "DV71"  !CDS_PN = "DV71";
"RSVD<25>":   PN = "DV61"  !CDS_PN = "DV61";
"RSVD<26>":   PN = "DU44"  !CDS_PN = "DU44";
"RSVD<27>":   PN = "DT71"  !CDS_PN = "DT71";
"RSVD<28>":   PN = "DR44"  !CDS_PN = "DR44";
"RSVD<29>":   PN = "DP65"  !CDS_PN = "DP65";
"RSVD<30>":   PN = "DP17"  !CDS_PN = "DP17";
"RSVD<31>":   PN = "DN66"  !CDS_PN = "DN66";
"RSVD<32>":   PN = "DN62"  !CDS_PN = "DN62";
"RSVD<33>":   PN = "DM67"  !CDS_PN = "DM67";
"RSVD<34>":   PN = "DL66"  !CDS_PN = "DL66";
"RSVD<35>":   PN = "DL38"  !CDS_PN = "DL38";
"RSVD<36>":   PN = "DK67"  !CDS_PN = "DK67";
"RSVD<37>":   PN = "DK65"  !CDS_PN = "DK65";
"RSVD<38>":   PN = "DK37"  !CDS_PN = "DK37";
"RSVD<39>":   PN = "DK15"  !CDS_PN = "DK15";
"RSVD<40>":   PN = "DJ66"  !CDS_PN = "DJ66";
"RSVD<41>":   PN = "DJ36"  !CDS_PN = "DJ36";
"RSVD<42>":   PN = "DH65"  !CDS_PN = "DH65";
"RSVD<43>":   PN = "DG64"  !CDS_PN = "DG64";
"RSVD<44>":   PN = "DG36"  !CDS_PN = "DG36";
"RSVD<45>":   PN = "DD51"  !CDS_PN = "DD51";
"RSVD<46>":   PN = "DC52"  !CDS_PN = "DC52";
"RSVD<47>":   PN = "DC46"  !CDS_PN = "DC46";
"RSVD<48>":   PN = "DA56"  !CDS_PN = "DA56";
"RSVD<49>":   PN = "DA54"  !CDS_PN = "DA54";
"RSVD<50>":   PN = "DA52"  !CDS_PN = "DA52";
"RSVD<51>":   PN = "DA40"  !CDS_PN = "DA40";
"RSVD<52>":   PN = "DA24"  !CDS_PN = "DA24";
"RSVD<53>":   PN = "CY73"  !CDS_PN = "CY73";
"RSVD<54>":   PN = "CY63"  !CDS_PN = "CY63";
"RSVD<55>":   PN = "CY57"  !CDS_PN = "CY57";
"RSVD<56>":   PN = "CY53"  !CDS_PN = "CY53";
"RSVD<57>":   PN = "CY39"  !CDS_PN = "CY39";
"RSVD<58>":   PN = "CY25"  !CDS_PN = "CY25";
"RSVD<59>":   PN = "CY23"  !CDS_PN = "CY23";
"RSVD<60>":   PN = "CW62"  !CDS_PN = "CW62";
"RSVD<61>":   PN = "CW60"  !CDS_PN = "CW60";
"RSVD<62>":   PN = "CW24"  !CDS_PN = "CW24";
"RSVD<63>":   PN = "CW22"  !CDS_PN = "CW22";
"RSVD<64>":   PN = "CV69"  !CDS_PN = "CV69";
"RSVD<65>":   PN = "CV23"  !CDS_PN = "CV23";
"RSVD<66>":   PN = "CU60"  !CDS_PN = "CU60";
"RSVD<67>":   PN = "CU6"  !CDS_PN = "CU6";
"RSVD<68>":   PN = "CU24"  !CDS_PN = "CU24";
"RSVD<69>":   PN = "CT69"  !CDS_PN = "CT69";
"RSVD<70>":   PN = "CT5"  !CDS_PN = "CT5";
"RSVD<71>":   PN = "CT23"  !CDS_PN = "CT23";
"RSVD<72>":   PN = "CR60"  !CDS_PN = "CR60";
"RSVD<73>":   PN = "CP31"  !CDS_PN = "CP31";
"RSVD<74>":   PN = "CP23"  !CDS_PN = "CP23";
"RSVD<75>":   PN = "CN28"  !CDS_PN = "CN28";
"RSVD<76>":   PN = "CN24"  !CDS_PN = "CN24";
"RSVD<77>":   PN = "CN22"  !CDS_PN = "CN22";
"RSVD<78>":   PN = "CM25"  !CDS_PN = "CM25";
"RSVD<79>":   PN = "CM23"  !CDS_PN = "CM23";
"RSVD<80>":   PN = "CL26"  !CDS_PN = "CL26";
"VCCIO<0>":   PN = "EE10"  !CDS_PN = "EE10";
"VCCIO<1>":   PN = "AE10"  !CDS_PN = "AE10";
"VCCIO<2>":   PN = "AF5"  !CDS_PN = "AF5";
"VCCIO<3>":   PN = "DV11"  !CDS_PN = "DV11";
"VCCIO<4>":   PN = "AM5"  !CDS_PN = "AM5";
"VCCIO<5>":   PN = "AT5"  !CDS_PN = "AT5";
"VCCIO<6>":   PN = "AT7"  !CDS_PN = "AT7";
"VCCIO<7>":   PN = "BE24"  !CDS_PN = "BE24";
"VCCIO<8>":   PN = "DK21"  !CDS_PN = "DK21";
"VCCIO<9>":   PN = "CF5"  !CDS_PN = "CF5";
"VCCIO<10>":   PN = "CG14"  !CDS_PN = "CG14";
"VCCIO<11>":   PN = "CL20"  !CDS_PN = "CL20";
"VCCIO<12>":   PN = "CP13"  !CDS_PN = "CP13";
"VCCIO<13>":   PN = "DE14"  !CDS_PN = "DE14";
"VCCIO<14>":   PN = "DC18"  !CDS_PN = "DC18";
"VCCIO<15>":   PN = "CY17"  !CDS_PN = "CY17";
"VCCIO<16>":   PN = "CU18"  !CDS_PN = "CU18";
"VCCIO<17>":   PN = "CV21"  !CDS_PN = "CV21";
"VCCIO<18>":   PN = "CU12"  !CDS_PN = "CU12";
"VCCIO<19>":   PN = "CN6"  !CDS_PN = "CN6";
"VCCIO_SENSE":   PN = "BH5"  !CDS_PN = "BH5";
"VCCSA_SENSE":   PN = "CE76"  !CDS_PN = "CE76";
"VSS_VCCIO_SENSE":   PN = "BF5"  !CDS_PN = "BF5";
"VSS_VCCSA_SENSE":   PN = "CG76"  !CDS_PN = "CG76";
DRAWING = "@baseboard_fab2_lib.baseboard_fab2(sch_1):page74";
BODY = "SKX_EXT_B","I20": #LOCATION = "U2D1" !CDS_LOCATION = "U2D1" #SEC = "23" !CDS_SEC = "23";
"VSS<1094>":   PN = "J74"  !CDS_PN = "J74";
"VSS<1095>":   PN = "J72"  !CDS_PN = "J72";
"VSS<1096>":   PN = "J40"  !CDS_PN = "J40";
"VSS<1097>":   PN = "J38"  !CDS_PN = "J38";
"VSS<1098>":   PN = "J34"  !CDS_PN = "J34";
"VSS<1099>":   PN = "J32"  !CDS_PN = "J32";
"VSS<1100>":   PN = "J28"  !CDS_PN = "J28";
"VSS<1101>":   PN = "J26"  !CDS_PN = "J26";
"VSS<1102>":   PN = "J22"  !CDS_PN = "J22";
"VSS<1103>":   PN = "J14"  !CDS_PN = "J14";
"VSS<1104>":   PN = "J12"  !CDS_PN = "J12";
"VSS<1105>":   PN = "J4"  !CDS_PN = "J4";
"VSS<1106>":   PN = "DN44"  !CDS_PN = "DN44";
"VSS<1107>":   PN = "H75"  !CDS_PN = "H75";
"VSS<1108>":   PN = "H71"  !CDS_PN = "H71";
"VSS<1109>":   PN = "H65"  !CDS_PN = "H65";
"VSS<1110>":   PN = "H41"  !CDS_PN = "H41";
"VSS<1111>":   PN = "H39"  !CDS_PN = "H39";
"VSS<1112>":   PN = "H37"  !CDS_PN = "H37";
"VSS<1113>":   PN = "H35"  !CDS_PN = "H35";
"VSS<1114>":   PN = "H33"  !CDS_PN = "H33";
"VSS<1115>":   PN = "H31"  !CDS_PN = "H31";
"VSS<1116>":   PN = "H29"  !CDS_PN = "H29";
"VSS<1117>":   PN = "H27"  !CDS_PN = "H27";
"VSS<1118>":   PN = "H25"  !CDS_PN = "H25";
"VSS<1119>":   PN = "H11"  !CDS_PN = "H11";
"VSS<1120>":   PN = "H3"  !CDS_PN = "H3";
"VSS<1121>":   PN = "G82"  !CDS_PN = "G82";
"VSS<1122>":   PN = "G80"  !CDS_PN = "G80";
"VSS<1123>":   PN = "G78"  !CDS_PN = "G78";
"VSS<1124>":   PN = "G76"  !CDS_PN = "G76";
"VSS<1125>":   PN = "G70"  !CDS_PN = "G70";
"VSS<1126>":   PN = "G66"  !CDS_PN = "G66";
"VSS<1127>":   PN = "G42"  !CDS_PN = "G42";
"VSS<1128>":   PN = "G38"  !CDS_PN = "G38";
"VSS<1129>":   PN = "G36"  !CDS_PN = "G36";
"VSS<1130>":   PN = "G32"  !CDS_PN = "G32";
"VSS<1131>":   PN = "G30"  !CDS_PN = "G30";
"VSS<1132>":   PN = "G26"  !CDS_PN = "G26";
"VSS<1133>":   PN = "G24"  !CDS_PN = "G24";
"VSS<1134>":   PN = "G22"  !CDS_PN = "G22";
"VSS<1135>":   PN = "G8"  !CDS_PN = "G8";
"VSS<1136>":   PN = "G4"  !CDS_PN = "G4";
"VSS<1137>":   PN = "F69"  !CDS_PN = "F69";
"VSS<1138>":   PN = "F67"  !CDS_PN = "F67";
"VSS<1139>":   PN = "F43"  !CDS_PN = "F43";
"VSS<1140>":   PN = "F37"  !CDS_PN = "F37";
"VSS<1141>":   PN = "F31"  !CDS_PN = "F31";
"VSS<1142>":   PN = "F25"  !CDS_PN = "F25";
"VSS<1143>":   PN = "F19"  !CDS_PN = "F19";
"VSS<1144>":   PN = "F17"  !CDS_PN = "F17";
"VSS<1145>":   PN = "F5"  !CDS_PN = "F5";
"VSS<1146>":   PN = "E76"  !CDS_PN = "E76";
"VSS<1147>":   PN = "E74"  !CDS_PN = "E74";
"VSS<1148>":   PN = "E72"  !CDS_PN = "E72";
"VSS<1149>":   PN = "E22"  !CDS_PN = "E22";
"VSS<1150>":   PN = "E20"  !CDS_PN = "E20";
"VSS<1151>":   PN = "E18"  !CDS_PN = "E18";
"VSS<1152>":   PN = "E16"  !CDS_PN = "E16";
"VSS<1153>":   PN = "E8"  !CDS_PN = "E8";
"VSS<1154>":   PN = "E6"  !CDS_PN = "E6";
"VSS<1155>":   PN = "D77"  !CDS_PN = "D77";
"VSS<1156>":   PN = "D43"  !CDS_PN = "D43";
"VSS<1157>":   PN = "D41"  !CDS_PN = "D41";
"VSS<1158>":   PN = "D39"  !CDS_PN = "D39";
"VSS<1159>":   PN = "D37"  !CDS_PN = "D37";
"VSS<1160>":   PN = "D35"  !CDS_PN = "D35";
"VSS<1161>":   PN = "D33"  !CDS_PN = "D33";
"VSS<1162>":   PN = "D31"  !CDS_PN = "D31";
"VSS<1163>":   PN = "D29"  !CDS_PN = "D29";
"VSS<1164>":   PN = "D27"  !CDS_PN = "D27";
"VSS<1165>":   PN = "D25"  !CDS_PN = "D25";
"VSS<1166>":   PN = "D13"  !CDS_PN = "D13";
"VSS<1167>":   PN = "D11"  !CDS_PN = "D11";
"VSS<1168>":   PN = "CM27"  !CDS_PN = "CM27";
"VSS<1169>":   PN = "C78"  !CDS_PN = "C78";
"VSS<1170>":   PN = "C76"  !CDS_PN = "C76";
"VSS<1171>":   PN = "C16"  !CDS_PN = "C16";
"VSS<1172>":   PN = "C14"  !CDS_PN = "C14";
"VSS<1173>":   PN = "C12"  !CDS_PN = "C12";
"VSS<1174>":   PN = "C10"  !CDS_PN = "C10";
"VSS<1175>":   PN = "C8"  !CDS_PN = "C8";
"VSS<1176>":   PN = "B75"  !CDS_PN = "B75";
"VSS<1177>":   PN = "B71"  !CDS_PN = "B71";
"VSS<1178>":   PN = "B37"  !CDS_PN = "B37";
"VSS<1179>":   PN = "B31"  !CDS_PN = "B31";
"VSS<1180>":   PN = "B25"  !CDS_PN = "B25";
"VSS<1181>":   PN = "A38"  !CDS_PN = "A38";
"VSS<1182>":   PN = "A36"  !CDS_PN = "A36";
"VSS<1183>":   PN = "A32"  !CDS_PN = "A32";
"VSS<1184>":   PN = "A30"  !CDS_PN = "A30";
"VSS<1185>":   PN = "A26"  !CDS_PN = "A26";
"VSS<1186>":   PN = "AC58"  !CDS_PN = "AC58";
"VSS<1187>":   PN = "AC60"  !CDS_PN = "AC60";
"VSS<1188>":   PN = "AC62"  !CDS_PN = "AC62";
"VSS<1189>":   PN = "AJ4"  !CDS_PN = "AJ4";
"VSS<1190>":   PN = "AR6"  !CDS_PN = "AR6";
"VSS<1191>":   PN = "CG6"  !CDS_PN = "CG6";
"VSS<1192>":   PN = "CW6"  !CDS_PN = "CW6";
"VSS<1193>":   PN = "DE48"  !CDS_PN = "DE48";
"VSS<1194>":   PN = "DE50"  !CDS_PN = "DE50";
"VSS<1195>":   PN = "DE52"  !CDS_PN = "DE52";
"VSS<1196>":   PN = "DE54"  !CDS_PN = "DE54";
"VSS<1197>":   PN = "DE56"  !CDS_PN = "DE56";
"VSS<1198>":   PN = "DE58"  !CDS_PN = "DE58";
"VSS<1199>":   PN = "DE60"  !CDS_PN = "DE60";
"VSS<1200>":   PN = "DE62"  !CDS_PN = "DE62";
"VSS<1201>":   PN = "DL8"  !CDS_PN = "DL8";
"VSS<1202>":   PN = "DN18"  !CDS_PN = "DN18";
"VSS<1203>":   PN = "DP45"  !CDS_PN = "DP45";
"VSS<1204>":   PN = "DP47"  !CDS_PN = "DP47";
"VSS<1205>":   PN = "DP49"  !CDS_PN = "DP49";
"VSS<1206>":   PN = "DP51"  !CDS_PN = "DP51";
"VSS<1207>":   PN = "DP53"  !CDS_PN = "DP53";
"VSS<1208>":   PN = "DP55"  !CDS_PN = "DP55";
"VSS<1209>":   PN = "DP57"  !CDS_PN = "DP57";
"VSS<1210>":   PN = "DP59"  !CDS_PN = "DP59";
"VSS<1211>":   PN = "DP61"  !CDS_PN = "DP61";
"VSS<1212>":   PN = "DP63"  !CDS_PN = "DP63";
"VSS<1213>":   PN = "DP9"  !CDS_PN = "DP9";
"VSS<1214>":   PN = "DV19"  !CDS_PN = "DV19";
"VSS<1215>":   PN = "DY45"  !CDS_PN = "DY45";
"VSS<1216>":   PN = "DY47"  !CDS_PN = "DY47";
"VSS<1217>":   PN = "DY49"  !CDS_PN = "DY49";
"VSS<1218>":   PN = "DY51"  !CDS_PN = "DY51";
"VSS<1219>":   PN = "DY53"  !CDS_PN = "DY53";
"VSS<1220>":   PN = "DY55"  !CDS_PN = "DY55";
"VSS<1221>":   PN = "DY57"  !CDS_PN = "DY57";
"VSS<1222>":   PN = "DY59"  !CDS_PN = "DY59";
"VSS<1223>":   PN = "DY61"  !CDS_PN = "DY61";
"VSS<1224>":   PN = "DY63"  !CDS_PN = "DY63";
"VSS<1225>":   PN = "EA14"  !CDS_PN = "EA14";
"VSS<1226>":   PN = "L8"  !CDS_PN = "L8";
"VSS<1227>":   PN = "V11"  !CDS_PN = "V11";
"VSS<1228>":   PN = "E66"  !CDS_PN = "E66";
"VSS<1229>":   PN = "ED69"  !CDS_PN = "ED69";
"VSS<1230>":   PN = "EE80"  !CDS_PN = "EE80";
"VSS<1231>":   PN = "EE8"  !CDS_PN = "EE8";
"VSS<1232>":   PN = "EE40"  !CDS_PN = "EE40";
"VSS<1233>":   PN = "ED81"  !CDS_PN = "ED81";
"VSS<1234>":   PN = "ED7"  !CDS_PN = "ED7";
"VSS<1235>":   PN = "ED41"  !CDS_PN = "ED41";
"VSS<1236>":   PN = "EC82"  !CDS_PN = "EC82";
"VSS<1237>":   PN = "EC6"  !CDS_PN = "EC6";
"VSS<1238>":   PN = "EC42"  !CDS_PN = "EC42";
"VSS<1239>":   PN = "DW2"  !CDS_PN = "DW2";
"VSS<1240>":   PN = "EB83"  !CDS_PN = "EB83";
"VSS<1241>":   PN = "EA84"  !CDS_PN = "EA84";
"VSS<1242>":   PN = "DY85"  !CDS_PN = "DY85";
"VSS<1243>":   PN = "J86"  !CDS_PN = "J86";
"VSS<1244>":   PN = "E82"  !CDS_PN = "E82";
"VSS<1245>":   PN = "D81"  !CDS_PN = "D81";
"VSS<1246>":   PN = "D3"  !CDS_PN = "D3";
"VSS<1247>":   PN = "C80"  !CDS_PN = "C80";
"VSS<1248>":   PN = "C4"  !CDS_PN = "C4";
"VSS<1249>":   PN = "B79"  !CDS_PN = "B79";
"VSS<1250>":   PN = "B5"  !CDS_PN = "B5";
"VSS<1251>":   PN = "B43"  !CDS_PN = "B43";
"VSS<1252>":   PN = "A42"  !CDS_PN = "A42";
"VSS<1253>":   PN = "B9"  !CDS_PN = "B9";
BODY = "SKX_EXT_B","I21": #LOCATION = "U2D1" !CDS_LOCATION = "U2D1" #SEC = "24" !CDS_SEC = "24";
"VSS<934>":   PN = "AA16"  !CDS_PN = "AA16";
"VSS<935>":   PN = "AA4"  !CDS_PN = "AA4";
"VSS<936>":   PN = "Y85"  !CDS_PN = "Y85";
"VSS<937>":   PN = "Y83"  !CDS_PN = "Y83";
"VSS<938>":   PN = "Y81"  !CDS_PN = "Y81";
"VSS<939>":   PN = "Y79"  !CDS_PN = "Y79";
"VSS<940>":   PN = "Y73"  !CDS_PN = "Y73";
"VSS<941>":   PN = "Y71"  !CDS_PN = "Y71";
"VSS<942>":   PN = "Y9"  !CDS_PN = "Y9";
"VSS<943>":   PN = "Y7"  !CDS_PN = "Y7";
"VSS<944>":   PN = "Y67"  !CDS_PN = "Y67";
"VSS<945>":   PN = "Y5"  !CDS_PN = "Y5";
"VSS<946>":   PN = "Y17"  !CDS_PN = "Y17";
"VSS<947>":   PN = "Y15"  !CDS_PN = "Y15";
"VSS<948>":   PN = "W82"  !CDS_PN = "W82";
"VSS<949>":   PN = "W78"  !CDS_PN = "W78";
"VSS<950>":   PN = "W74"  !CDS_PN = "W74";
"VSS<951>":   PN = "W68"  !CDS_PN = "W68";
"VSS<952>":   PN = "W42"  !CDS_PN = "W42";
"VSS<953>":   PN = "W40"  !CDS_PN = "W40";
"VSS<954>":   PN = "W38"  !CDS_PN = "W38";
"VSS<955>":   PN = "W36"  !CDS_PN = "W36";
"VSS<956>":   PN = "W34"  !CDS_PN = "W34";
"VSS<957>":   PN = "W32"  !CDS_PN = "W32";
"VSS<958>":   PN = "W30"  !CDS_PN = "W30";
"VSS<959>":   PN = "W28"  !CDS_PN = "W28";
"VSS<960>":   PN = "W26"  !CDS_PN = "W26";
"VSS<961>":   PN = "W24"  !CDS_PN = "W24";
"VSS<962>":   PN = "W22"  !CDS_PN = "W22";
"VSS<963>":   PN = "W12"  !CDS_PN = "W12";
"VSS<964>":   PN = "AC56"  !CDS_PN = "AC56";
"VSS<965>":   PN = "W8"  !CDS_PN = "W8";
"VSS<966>":   PN = "V83"  !CDS_PN = "V83";
"VSS<967>":   PN = "V77"  !CDS_PN = "V77";
"VSS<968>":   PN = "V75"  !CDS_PN = "V75";
"VSS<969>":   PN = "V73"  !CDS_PN = "V73";
"VSS<970>":   PN = "V43"  !CDS_PN = "V43";
"VSS<971>":   PN = "V23"  !CDS_PN = "V23";
"VSS<972>":   PN = "V21"  !CDS_PN = "V21";
"VSS<973>":   PN = "V15"  !CDS_PN = "V15";
"VSS<974>":   PN = "V13"  !CDS_PN = "V13";
"VSS<975>":   PN = "V9"  !CDS_PN = "V9";
"VSS<976>":   PN = "V5"  !CDS_PN = "V5";
"VSS<977>":   PN = "V1"  !CDS_PN = "V1";
"VSS<978>":   PN = "U86"  !CDS_PN = "U86";
"VSS<979>":   PN = "U80"  !CDS_PN = "U80";
"VSS<980>":   PN = "U78"  !CDS_PN = "U78";
"VSS<981>":   PN = "U76"  !CDS_PN = "U76";
"VSS<982>":   PN = "U74"  !CDS_PN = "U74";
"VSS<983>":   PN = "U70"  !CDS_PN = "U70";
"VSS<984>":   PN = "U68"  !CDS_PN = "U68";
"VSS<985>":   PN = "U42"  !CDS_PN = "U42";
"VSS<986>":   PN = "U36"  !CDS_PN = "U36";
"VSS<987>":   PN = "U30"  !CDS_PN = "U30";
"VSS<988>":   PN = "U24"  !CDS_PN = "U24";
"VSS<989>":   PN = "U22"  !CDS_PN = "U22";
"VSS<990>":   PN = "U20"  !CDS_PN = "U20";
"VSS<991>":   PN = "U6"  !CDS_PN = "U6";
"VSS<992>":   PN = "U4"  !CDS_PN = "U4";
"VSS<993>":   PN = "U2"  !CDS_PN = "U2";
"VSS<994>":   PN = "T85"  !CDS_PN = "T85";
"VSS<995>":   PN = "T83"  !CDS_PN = "T83";
"VSS<996>":   PN = "T77"  !CDS_PN = "T77";
"VSS<997>":   PN = "T73"  !CDS_PN = "T73";
"VSS<998>":   PN = "T65"  !CDS_PN = "T65";
"VSS<999>":   PN = "T41"  !CDS_PN = "T41";
"VSS<1000>":   PN = "T37"  !CDS_PN = "T37";
"VSS<1001>":   PN = "T35"  !CDS_PN = "T35";
"VSS<1002>":   PN = "T31"  !CDS_PN = "T31";
"VSS<1003>":   PN = "T29"  !CDS_PN = "T29";
"VSS<1004>":   PN = "T25"  !CDS_PN = "T25";
"VSS<1005>":   PN = "T17"  !CDS_PN = "T17";
"VSS<1006>":   PN = "T13"  !CDS_PN = "T13";
"VSS<1007>":   PN = "R86"  !CDS_PN = "R86";
"VSS<1008>":   PN = "R78"  !CDS_PN = "R78";
"VSS<1009>":   PN = "R72"  !CDS_PN = "R72";
"VSS<1010>":   PN = "R68"  !CDS_PN = "R68";
"VSS<1011>":   PN = "R40"  !CDS_PN = "R40";
"VSS<1012>":   PN = "R38"  !CDS_PN = "R38";
"VSS<1013>":   PN = "R34"  !CDS_PN = "R34";
"VSS<1014>":   PN = "R32"  !CDS_PN = "R32";
"VSS<1015>":   PN = "R28"  !CDS_PN = "R28";
"VSS<1016>":   PN = "R26"  !CDS_PN = "R26";
"VSS<1017>":   PN = "R22"  !CDS_PN = "R22";
"VSS<1018>":   PN = "R4"  !CDS_PN = "R4";
"VSS<1019>":   PN = "R2"  !CDS_PN = "R2";
"VSS<1020>":   PN = "R18"  !CDS_PN = "R18";
"VSS<1021>":   PN = "R14"  !CDS_PN = "R14";
"VSS<1022>":   PN = "P83"  !CDS_PN = "P83";
"VSS<1023>":   PN = "P81"  !CDS_PN = "P81";
"VSS<1024>":   PN = "P71"  !CDS_PN = "P71";
"VSS<1025>":   PN = "P69"  !CDS_PN = "P69";
"VSS<1026>":   PN = "P67"  !CDS_PN = "P67";
"VSS<1027>":   PN = "P39"  !CDS_PN = "P39";
"VSS<1028>":   PN = "P33"  !CDS_PN = "P33";
"VSS<1029>":   PN = "P27"  !CDS_PN = "P27";
"VSS<1030>":   PN = "P15"  !CDS_PN = "P15";
"VSS<1031>":   PN = "P11"  !CDS_PN = "P11";
"VSS<1032>":   PN = "N8"  !CDS_PN = "N8";
"VSS<1033>":   PN = "N4"  !CDS_PN = "N4";
"VSS<1034>":   PN = "N78"  !CDS_PN = "N78";
"VSS<1035>":   PN = "N76"  !CDS_PN = "N76";
"VSS<1036>":   PN = "N74"  !CDS_PN = "N74";
"VSS<1037>":   PN = "N72"  !CDS_PN = "N72";
"VSS<1038>":   PN = "N70"  !CDS_PN = "N70";
"VSS<1039>":   PN = "N66"  !CDS_PN = "N66";
"VSS<1040>":   PN = "N6"  !CDS_PN = "N6";
"VSS<1041>":   PN = "N22"  !CDS_PN = "N22";
"VSS<1042>":   PN = "N20"  !CDS_PN = "N20";
"VSS<1043>":   PN = "DM19"  !CDS_PN = "DM19";
"VSS<1044>":   PN = "M85"  !CDS_PN = "M85";
"VSS<1045>":   PN = "M83"  !CDS_PN = "M83";
"VSS<1046>":   PN = "M79"  !CDS_PN = "M79";
"VSS<1047>":   PN = "M71"  !CDS_PN = "M71";
"VSS<1048>":   PN = "M65"  !CDS_PN = "M65";
"VSS<1049>":   PN = "M43"  !CDS_PN = "M43";
"VSS<1050>":   PN = "M41"  !CDS_PN = "M41";
"VSS<1051>":   PN = "M39"  !CDS_PN = "M39";
"VSS<1052>":   PN = "M37"  !CDS_PN = "M37";
"VSS<1053>":   PN = "M35"  !CDS_PN = "M35";
"VSS<1054>":   PN = "M33"  !CDS_PN = "M33";
"VSS<1055>":   PN = "M31"  !CDS_PN = "M31";
"VSS<1056>":   PN = "M29"  !CDS_PN = "M29";
"VSS<1057>":   PN = "M27"  !CDS_PN = "M27";
"VSS<1058>":   PN = "M25"  !CDS_PN = "M25";
"VSS<1059>":   PN = "M23"  !CDS_PN = "M23";
"VSS<1060>":   PN = "M19"  !CDS_PN = "M19";
"VSS<1061>":   PN = "M17"  !CDS_PN = "M17";
"VSS<1062>":   PN = "M15"  !CDS_PN = "M15";
"VSS<1063>":   PN = "CT7"  !CDS_PN = "CT7";
"VSS<1064>":   PN = "BT9"  !CDS_PN = "BT9";
"VSS<1065>":   PN = "L82"  !CDS_PN = "L82";
"VSS<1066>":   PN = "L80"  !CDS_PN = "L80";
"VSS<1067>":   PN = "L78"  !CDS_PN = "L78";
"VSS<1068>":   PN = "L72"  !CDS_PN = "L72";
"VSS<1069>":   PN = "L22"  !CDS_PN = "L22";
"VSS<1070>":   PN = "L20"  !CDS_PN = "L20";
"VSS<1071>":   PN = "L6"  !CDS_PN = "L6";
"VSS<1072>":   PN = "L2"  !CDS_PN = "L2";
"VSS<1073>":   PN = "L10"  !CDS_PN = "L10";
"VSS<1074>":   PN = "K85"  !CDS_PN = "K85";
"VSS<1075>":   PN = "K83"  !CDS_PN = "K83";
"VSS<1076>":   PN = "K81"  !CDS_PN = "K81";
"VSS<1077>":   PN = "K77"  !CDS_PN = "K77";
"VSS<1078>":   PN = "K73"  !CDS_PN = "K73";
"VSS<1079>":   PN = "K71"  !CDS_PN = "K71";
"VSS<1080>":   PN = "K69"  !CDS_PN = "K69";
"VSS<1081>":   PN = "K67"  !CDS_PN = "K67";
"VSS<1082>":   PN = "K65"  !CDS_PN = "K65";
"VSS<1083>":   PN = "K39"  !CDS_PN = "K39";
"VSS<1084>":   PN = "K33"  !CDS_PN = "K33";
"VSS<1085>":   PN = "K27"  !CDS_PN = "K27";
"VSS<1086>":   PN = "DB7"  !CDS_PN = "DB7";
"VSS<1087>":   PN = "K17"  !CDS_PN = "K17";
"VSS<1088>":   PN = "K13"  !CDS_PN = "K13";
"VSS<1089>":   PN = "K11"  !CDS_PN = "K11";
"VSS<1090>":   PN = "K1"  !CDS_PN = "K1";
"VSS<1091>":   PN = "J84"  !CDS_PN = "J84";
"VSS<1092>":   PN = "J82"  !CDS_PN = "J82";
"VSS<1093>":   PN = "J76"  !CDS_PN = "J76";
BODY = "SKX_EXT_B","I22": #LOCATION = "U2D1" !CDS_LOCATION = "U2D1" #SEC = "25" !CDS_SEC = "25";
"VSS<774>":   PN = "AL68"  !CDS_PN = "AL68";
"VSS<775>":   PN = "AL64"  !CDS_PN = "AL64";
"VSS<776>":   PN = "AL56"  !CDS_PN = "AL56";
"VSS<777>":   PN = "AL32"  !CDS_PN = "AL32";
"VSS<778>":   PN = "AL30"  !CDS_PN = "AL30";
"VSS<779>":   PN = "AL24"  !CDS_PN = "AL24";
"VSS<780>":   PN = "AL10"  !CDS_PN = "AL10";
"VSS<781>":   PN = "AL4"  !CDS_PN = "AL4";
"VSS<782>":   PN = "AK85"  !CDS_PN = "AK85";
"VSS<783>":   PN = "AK83"  !CDS_PN = "AK83";
"VSS<784>":   PN = "AK81"  !CDS_PN = "AK81";
"VSS<785>":   PN = "AK79"  !CDS_PN = "AK79";
"VSS<786>":   PN = "AK73"  !CDS_PN = "AK73";
"VSS<787>":   PN = "AK67"  !CDS_PN = "AK67";
"VSS<788>":   PN = "AK65"  !CDS_PN = "AK65";
"VSS<789>":   PN = "AK55"  !CDS_PN = "AK55";
"VSS<790>":   PN = "AK33"  !CDS_PN = "AK33";
"VSS<791>":   PN = "AK31"  !CDS_PN = "AK31";
"VSS<792>":   PN = "AK29"  !CDS_PN = "AK29";
"VSS<793>":   PN = "AK25"  !CDS_PN = "AK25";
"VSS<794>":   PN = "AK23"  !CDS_PN = "AK23";
"VSS<795>":   PN = "AK19"  !CDS_PN = "AK19";
"VSS<796>":   PN = "AK13"  !CDS_PN = "AK13";
"VSS<797>":   PN = "AK9"  !CDS_PN = "AK9";
"VSS<798>":   PN = "AJ86"  !CDS_PN = "AJ86";
"VSS<799>":   PN = "AJ82"  !CDS_PN = "AJ82";
"VSS<800>":   PN = "AJ78"  !CDS_PN = "AJ78";
"VSS<801>":   PN = "AJ74"  !CDS_PN = "AJ74";
"VSS<802>":   PN = "AJ68"  !CDS_PN = "AJ68";
"VSS<803>":   PN = "AJ66"  !CDS_PN = "AJ66";
"VSS<804>":   PN = "AJ54"  !CDS_PN = "AJ54";
"VSS<805>":   PN = "AJ52"  !CDS_PN = "AJ52";
"VSS<806>":   PN = "AJ50"  !CDS_PN = "AJ50";
"VSS<807>":   PN = "AJ48"  !CDS_PN = "AJ48";
"VSS<808>":   PN = "AJ46"  !CDS_PN = "AJ46";
"VSS<809>":   PN = "AJ34"  !CDS_PN = "AJ34";
"VSS<810>":   PN = "AJ32"  !CDS_PN = "AJ32";
"VSS<811>":   PN = "AJ28"  !CDS_PN = "AJ28";
"VSS<812>":   PN = "AJ26"  !CDS_PN = "AJ26";
"VSS<813>":   PN = "AJ22"  !CDS_PN = "AJ22";
"VSS<814>":   PN = "AJ8"  !CDS_PN = "AJ8";
"VSS<815>":   PN = "AH83"  !CDS_PN = "AH83";
"VSS<816>":   PN = "AH77"  !CDS_PN = "AH77";
"VSS<817>":   PN = "AH75"  !CDS_PN = "AH75";
"VSS<818>":   PN = "AH69"  !CDS_PN = "AH69";
"VSS<819>":   PN = "AH65"  !CDS_PN = "AH65";
"VSS<820>":   PN = "AH61"  !CDS_PN = "AH61";
"VSS<821>":   PN = "AH59"  !CDS_PN = "AH59";
"VSS<822>":   PN = "AH53"  !CDS_PN = "AH53";
"VSS<823>":   PN = "AH51"  !CDS_PN = "AH51";
"VSS<824>":   PN = "AH49"  !CDS_PN = "AH49";
"VSS<825>":   PN = "AH47"  !CDS_PN = "AH47";
"VSS<826>":   PN = "AH45"  !CDS_PN = "AH45";
"VSS<827>":   PN = "AH35"  !CDS_PN = "AH35";
"VSS<828>":   PN = "AH33"  !CDS_PN = "AH33";
"VSS<829>":   PN = "AH27"  !CDS_PN = "AH27";
"VSS<830>":   PN = "AH21"  !CDS_PN = "AH21";
"VSS<831>":   PN = "AH5"  !CDS_PN = "AH5";
"VSS<832>":   PN = "AH1"  !CDS_PN = "AH1";
"VSS<833>":   PN = "AG80"  !CDS_PN = "AG80";
"VSS<834>":   PN = "AG78"  !CDS_PN = "AG78";
"VSS<835>":   PN = "AG76"  !CDS_PN = "AG76";
"VSS<836>":   PN = "AG74"  !CDS_PN = "AG74";
"VSS<837>":   PN = "AG70"  !CDS_PN = "AG70";
"VSS<838>":   PN = "AG64"  !CDS_PN = "AG64";
"VSS<839>":   PN = "AG36"  !CDS_PN = "AG36";
"VSS<840>":   PN = "AG18"  !CDS_PN = "AG18";
"VSS<841>":   PN = "AG14"  !CDS_PN = "AG14";
"VSS<842>":   PN = "AG12"  !CDS_PN = "AG12";
"VSS<843>":   PN = "AF85"  !CDS_PN = "AF85";
"VSS<844>":   PN = "AF83"  !CDS_PN = "AF83";
"VSS<845>":   PN = "AF77"  !CDS_PN = "AF77";
"VSS<846>":   PN = "AF73"  !CDS_PN = "AF73";
"VSS<847>":   PN = "AF41"  !CDS_PN = "AF41";
"VSS<848>":   PN = "AF39"  !CDS_PN = "AF39";
"VSS<849>":   PN = "AF37"  !CDS_PN = "AF37";
"VSS<850>":   PN = "AF33"  !CDS_PN = "AF33";
"VSS<851>":   PN = "AF31"  !CDS_PN = "AF31";
"VSS<852>":   PN = "AF29"  !CDS_PN = "AF29";
"VSS<853>":   PN = "AF27"  !CDS_PN = "AF27";
"VSS<854>":   PN = "AF25"  !CDS_PN = "AF25";
"VSS<855>":   PN = "AF23"  !CDS_PN = "AF23";
"VSS<856>":   PN = "AF21"  !CDS_PN = "AF21";
"VSS<857>":   PN = "AF9"  !CDS_PN = "AF9";
"VSS<858>":   PN = "AC52"  !CDS_PN = "AC52";
"VSS<859>":   PN = "AF1"  !CDS_PN = "AF1";
"VSS<860>":   PN = "AE78"  !CDS_PN = "AE78";
"VSS<861>":   PN = "AE70"  !CDS_PN = "AE70";
"VSS<862>":   PN = "AE68"  !CDS_PN = "AE68";
"VSS<863>":   PN = "AE66"  !CDS_PN = "AE66";
"VSS<864>":   PN = "AE64"  !CDS_PN = "AE64";
"VSS<865>":   PN = "AE42"  !CDS_PN = "AE42";
"VSS<866>":   PN = "AE40"  !CDS_PN = "AE40";
"VSS<867>":   PN = "AE38"  !CDS_PN = "AE38";
"VSS<868>":   PN = "AE16"  !CDS_PN = "AE16";
"VSS<869>":   PN = "AC54"  !CDS_PN = "AC54";
"VSS<870>":   PN = "AE8"  !CDS_PN = "AE8";
"VSS<871>":   PN = "AE4"  !CDS_PN = "AE4";
"VSS<872>":   PN = "AD85"  !CDS_PN = "AD85";
"VSS<873>":   PN = "AD83"  !CDS_PN = "AD83";
"VSS<874>":   PN = "AD81"  !CDS_PN = "AD81";
"VSS<875>":   PN = "AD75"  !CDS_PN = "AD75";
"VSS<876>":   PN = "AD73"  !CDS_PN = "AD73";
"VSS<877>":   PN = "AD71"  !CDS_PN = "AD71";
"VSS<878>":   PN = "AD43"  !CDS_PN = "AD43";
"VSS<879>":   PN = "AD39"  !CDS_PN = "AD39";
"VSS<880>":   PN = "AD33"  !CDS_PN = "AD33";
"VSS<881>":   PN = "AD27"  !CDS_PN = "AD27";
"VSS<882>":   PN = "AD21"  !CDS_PN = "AD21";
"VSS<883>":   PN = "AD19"  !CDS_PN = "AD19";
"VSS<884>":   PN = "AD15"  !CDS_PN = "AD15";
"VSS<885>":   PN = "AD13"  !CDS_PN = "AD13";
"VSS<886>":   PN = "AD11"  !CDS_PN = "AD11";
"VSS<887>":   PN = "AD9"  !CDS_PN = "AD9";
"VSS<888>":   PN = "AD7"  !CDS_PN = "AD7";
"VSS<889>":   PN = "AD3"  !CDS_PN = "AD3";
"VSS<890>":   PN = "AC86"  !CDS_PN = "AC86";
"VSS<891>":   PN = "AC84"  !CDS_PN = "AC84";
"VSS<892>":   PN = "AC78"  !CDS_PN = "AC78";
"VSS<893>":   PN = "AC72"  !CDS_PN = "AC72";
"VSS<894>":   PN = "AC70"  !CDS_PN = "AC70";
"VSS<895>":   PN = "AC64"  !CDS_PN = "AC64";
"VSS<896>":   PN = "AC40"  !CDS_PN = "AC40";
"VSS<897>":   PN = "AC38"  !CDS_PN = "AC38";
"VSS<898>":   PN = "AC34"  !CDS_PN = "AC34";
"VSS<899>":   PN = "AC32"  !CDS_PN = "AC32";
"VSS<900>":   PN = "AC28"  !CDS_PN = "AC28";
"VSS<901>":   PN = "AC26"  !CDS_PN = "AC26";
"VSS<902>":   PN = "AC22"  !CDS_PN = "AC22";
"VSS<903>":   PN = "AC18"  !CDS_PN = "AC18";
"VSS<904>":   PN = "AB85"  !CDS_PN = "AB85";
"VSS<905>":   PN = "AB83"  !CDS_PN = "AB83";
"VSS<906>":   PN = "AB79"  !CDS_PN = "AB79";
"VSS<907>":   PN = "AB73"  !CDS_PN = "AB73";
"VSS<908>":   PN = "AB69"  !CDS_PN = "AB69";
"VSS<909>":   PN = "AB65"  !CDS_PN = "AB65";
"VSS<910>":   PN = "AB41"  !CDS_PN = "AB41";
"VSS<911>":   PN = "AB37"  !CDS_PN = "AB37";
"VSS<912>":   PN = "AB35"  !CDS_PN = "AB35";
"VSS<913>":   PN = "AB31"  !CDS_PN = "AB31";
"VSS<914>":   PN = "AB29"  !CDS_PN = "AB29";
"VSS<915>":   PN = "AB25"  !CDS_PN = "AB25";
"VSS<916>":   PN = "AB23"  !CDS_PN = "AB23";
"VSS<917>":   PN = "AB21"  !CDS_PN = "AB21";
"VSS<918>":   PN = "AB11"  !CDS_PN = "AB11";
"VSS<919>":   PN = "AB5"  !CDS_PN = "AB5";
"VSS<920>":   PN = "AB1"  !CDS_PN = "AB1";
"VSS<921>":   PN = "AA82"  !CDS_PN = "AA82";
"VSS<922>":   PN = "AA80"  !CDS_PN = "AA80";
"VSS<923>":   PN = "AA78"  !CDS_PN = "AA78";
"VSS<924>":   PN = "AA76"  !CDS_PN = "AA76";
"VSS<925>":   PN = "AA68"  !CDS_PN = "AA68";
"VSS<926>":   PN = "AA66"  !CDS_PN = "AA66";
"VSS<927>":   PN = "AA64"  !CDS_PN = "AA64";
"VSS<928>":   PN = "AA42"  !CDS_PN = "AA42";
"VSS<929>":   PN = "AA36"  !CDS_PN = "AA36";
"VSS<930>":   PN = "AA30"  !CDS_PN = "AA30";
"VSS<931>":   PN = "AA24"  !CDS_PN = "AA24";
"VSS<932>":   PN = "AA22"  !CDS_PN = "AA22";
"VSS<933>":   PN = "AA18"  !CDS_PN = "AA18";
BODY = "SKX_EXT_B","I23": #LOCATION = "U2D1" !CDS_LOCATION = "U2D1" #SEC = "26" !CDS_SEC = "26";
"VSS<614>":   PN = "BG72"  !CDS_PN = "BG72";
"VSS<615>":   PN = "BG24"  !CDS_PN = "BG24";
"VSS<616>":   PN = "BG22"  !CDS_PN = "BG22";
"VSS<617>":   PN = "BG10"  !CDS_PN = "BG10";
"VSS<618>":   PN = "BG8"  !CDS_PN = "BG8";
"VSS<619>":   PN = "BG6"  !CDS_PN = "BG6";
"VSS<620>":   PN = "BF71"  !CDS_PN = "BF71";
"VSS<621>":   PN = "BF69"  !CDS_PN = "BF69";
"VSS<622>":   PN = "BF67"  !CDS_PN = "BF67";
"VSS<623>":   PN = "BF65"  !CDS_PN = "BF65";
"VSS<624>":   PN = "BF63"  !CDS_PN = "BF63";
"VSS<625>":   PN = "BF25"  !CDS_PN = "BF25";
"VSS<626>":   PN = "BF19"  !CDS_PN = "BF19";
"VSS<627>":   PN = "BF17"  !CDS_PN = "BF17";
"VSS<628>":   PN = "BF15"  !CDS_PN = "BF15";
"VSS<629>":   PN = "BF9"  !CDS_PN = "BF9";
"VSS<630>":   PN = "BE70"  !CDS_PN = "BE70";
"VSS<631>":   PN = "BE68"  !CDS_PN = "BE68";
"VSS<632>":   PN = "BE66"  !CDS_PN = "BE66";
"VSS<633>":   PN = "BE64"  !CDS_PN = "BE64";
"VSS<634>":   PN = "BE26"  !CDS_PN = "BE26";
"VSS<635>":   PN = "BE10"  !CDS_PN = "BE10";
"VSS<636>":   PN = "BE8"  !CDS_PN = "BE8";
"VSS<637>":   PN = "BE6"  !CDS_PN = "BE6";
"VSS<638>":   PN = "BE4"  !CDS_PN = "BE4";
"VSS<639>":   PN = "BD71"  !CDS_PN = "BD71";
"VSS<640>":   PN = "BD63"  !CDS_PN = "BD63";
"VSS<641>":   PN = "BD27"  !CDS_PN = "BD27";
"VSS<642>":   PN = "BD21"  !CDS_PN = "BD21";
"VSS<643>":   PN = "BD15"  !CDS_PN = "BD15";
"VSS<644>":   PN = "BD11"  !CDS_PN = "BD11";
"VSS<645>":   PN = "BD5"  !CDS_PN = "BD5";
"VSS<646>":   PN = "BC82"  !CDS_PN = "BC82";
"VSS<647>":   PN = "BC80"  !CDS_PN = "BC80";
"VSS<648>":   PN = "BC78"  !CDS_PN = "BC78";
"VSS<649>":   PN = "BC76"  !CDS_PN = "BC76";
"VSS<650>":   PN = "BC74"  !CDS_PN = "BC74";
"VSS<651>":   PN = "BC72"  !CDS_PN = "BC72";
"VSS<652>":   PN = "BC70"  !CDS_PN = "BC70";
"VSS<653>":   PN = "BC16"  !CDS_PN = "BC16";
"VSS<654>":   PN = "BC12"  !CDS_PN = "BC12";
"VSS<655>":   PN = "BC8"  !CDS_PN = "BC8";
"VSS<656>":   PN = "BC4"  !CDS_PN = "BC4";
"VSS<657>":   PN = "BB83"  !CDS_PN = "BB83";
"VSS<658>":   PN = "BB81"  !CDS_PN = "BB81";
"VSS<659>":   PN = "BB79"  !CDS_PN = "BB79";
"VSS<660>":   PN = "BB77"  !CDS_PN = "BB77";
"VSS<661>":   PN = "BB75"  !CDS_PN = "BB75";
"VSS<662>":   PN = "BB73"  !CDS_PN = "BB73";
"VSS<663>":   PN = "BB69"  !CDS_PN = "BB69";
"VSS<664>":   PN = "BB63"  !CDS_PN = "BB63";
"VSS<665>":   PN = "BB23"  !CDS_PN = "BB23";
"VSS<666>":   PN = "BB19"  !CDS_PN = "BB19";
"VSS<667>":   PN = "BA84"  !CDS_PN = "BA84";
"VSS<668>":   PN = "BA80"  !CDS_PN = "BA80";
"VSS<669>":   PN = "BA74"  !CDS_PN = "BA74";
"VSS<670>":   PN = "BA68"  !CDS_PN = "BA68";
"VSS<671>":   PN = "BA62"  !CDS_PN = "BA62";
"VSS<672>":   PN = "BA12"  !CDS_PN = "BA12";
"VSS<673>":   PN = "BA6"  !CDS_PN = "BA6";
"VSS<674>":   PN = "BA2"  !CDS_PN = "BA2";
"VSS<675>":   PN = "AY81"  !CDS_PN = "AY81";
"VSS<676>":   PN = "AY79"  !CDS_PN = "AY79";
"VSS<677>":   PN = "AY63"  !CDS_PN = "AY63";
"VSS<678>":   PN = "AY25"  !CDS_PN = "AY25";
"VSS<679>":   PN = "AY23"  !CDS_PN = "AY23";
"VSS<680>":   PN = "AY21"  !CDS_PN = "AY21";
"VSS<681>":   PN = "AY17"  !CDS_PN = "AY17";
"VSS<682>":   PN = "AY15"  !CDS_PN = "AY15";
"VSS<683>":   PN = "AY5"  !CDS_PN = "AY5";
"VSS<684>":   PN = "AW84"  !CDS_PN = "AW84";
"VSS<685>":   PN = "AW82"  !CDS_PN = "AW82";
"VSS<686>":   PN = "AW78"  !CDS_PN = "AW78";
"VSS<687>":   PN = "AW74"  !CDS_PN = "AW74";
"VSS<688>":   PN = "AW72"  !CDS_PN = "AW72";
"VSS<689>":   PN = "AW70"  !CDS_PN = "AW70";
"VSS<690>":   PN = "AW68"  !CDS_PN = "AW68";
"VSS<691>":   PN = "AW66"  !CDS_PN = "AW66";
"VSS<692>":   PN = "AW62"  !CDS_PN = "AW62";
"VSS<693>":   PN = "AW10"  !CDS_PN = "AW10";
"VSS<694>":   PN = "AW2"  !CDS_PN = "AW2";
"VSS<695>":   PN = "AV83"  !CDS_PN = "AV83";
"VSS<696>":   PN = "AV75"  !CDS_PN = "AV75";
"VSS<697>":   PN = "AV67"  !CDS_PN = "AV67";
"VSS<698>":   PN = "AV65"  !CDS_PN = "AV65";
"VSS<699>":   PN = "AV63"  !CDS_PN = "AV63";
"VSS<700>":   PN = "AV25"  !CDS_PN = "AV25";
"VSS<701>":   PN = "AV23"  !CDS_PN = "AV23";
"VSS<702>":   PN = "AV19"  !CDS_PN = "AV19";
"VSS<703>":   PN = "AV13"  !CDS_PN = "AV13";
"VSS<704>":   PN = "AV11"  !CDS_PN = "AV11";
"VSS<705>":   PN = "AV7"  !CDS_PN = "AV7";
"VSS<706>":   PN = "AV3"  !CDS_PN = "AV3";
"VSS<707>":   PN = "AV1"  !CDS_PN = "AV1";
"VSS<708>":   PN = "AU86"  !CDS_PN = "AU86";
"VSS<709>":   PN = "AU84"  !CDS_PN = "AU84";
"VSS<710>":   PN = "AU80"  !CDS_PN = "AU80";
"VSS<711>":   PN = "AU78"  !CDS_PN = "AU78";
"VSS<712>":   PN = "AU76"  !CDS_PN = "AU76";
"VSS<713>":   PN = "AU74"  !CDS_PN = "AU74";
"VSS<714>":   PN = "AU68"  !CDS_PN = "AU68";
"VSS<715>":   PN = "AU64"  !CDS_PN = "AU64";
"VSS<716>":   PN = "AU62"  !CDS_PN = "AU62";
"VSS<717>":   PN = "AU28"  !CDS_PN = "AU28";
"VSS<718>":   PN = "AU26"  !CDS_PN = "AU26";
"VSS<719>":   PN = "AU6"  !CDS_PN = "AU6";
"VSS<720>":   PN = "AU2"  !CDS_PN = "AU2";
"VSS<721>":   PN = "AT85"  !CDS_PN = "AT85";
"VSS<722>":   PN = "AT83"  !CDS_PN = "AT83";
"VSS<723>":   PN = "AT77"  !CDS_PN = "AT77";
"VSS<724>":   PN = "AT73"  !CDS_PN = "AT73";
"VSS<725>":   PN = "AT69"  !CDS_PN = "AT69";
"VSS<726>":   PN = "AT63"  !CDS_PN = "AT63";
"VSS<727>":   PN = "AT61"  !CDS_PN = "AT61";
"VSS<728>":   PN = "AT27"  !CDS_PN = "AT27";
"VSS<729>":   PN = "AT21"  !CDS_PN = "AT21";
"VSS<730>":   PN = "AT17"  !CDS_PN = "AT17";
"VSS<731>":   PN = "AT15"  !CDS_PN = "AT15";
"VSS<732>":   PN = "P63"  !CDS_PN = "P63";
"VSS<733>":   PN = "AC48"  !CDS_PN = "AC48";
"VSS<734>":   PN = "AR78"  !CDS_PN = "AR78";
"VSS<735>":   PN = "AR72"  !CDS_PN = "AR72";
"VSS<736>":   PN = "AR60"  !CDS_PN = "AR60";
"VSS<737>":   PN = "AR30"  !CDS_PN = "AR30";
"VSS<738>":   PN = "AR24"  !CDS_PN = "AR24";
"VSS<739>":   PN = "AR10"  !CDS_PN = "AR10";
"VSS<740>":   PN = "AP85"  !CDS_PN = "AP85";
"VSS<741>":   PN = "AP83"  !CDS_PN = "AP83";
"VSS<742>":   PN = "AP81"  !CDS_PN = "AP81";
"VSS<743>":   PN = "AP75"  !CDS_PN = "AP75";
"VSS<744>":   PN = "AP73"  !CDS_PN = "AP73";
"VSS<745>":   PN = "AP69"  !CDS_PN = "AP69";
"VSS<746>":   PN = "AP67"  !CDS_PN = "AP67";
"VSS<747>":   PN = "AP65"  !CDS_PN = "AP65";
"VSS<748>":   PN = "AP63"  !CDS_PN = "AP63";
"VSS<749>":   PN = "AP59"  !CDS_PN = "AP59";
"VSS<750>":   PN = "AP31"  !CDS_PN = "AP31";
"VSS<751>":   PN = "AP19"  !CDS_PN = "AP19";
"VSS<752>":   PN = "AP13"  !CDS_PN = "AP13";
"VSS<753>":   PN = "AP9"  !CDS_PN = "AP9";
"VSS<754>":   PN = "AP5"  !CDS_PN = "AP5";
"VSS<755>":   PN = "AN78"  !CDS_PN = "AN78";
"VSS<756>":   PN = "AN58"  !CDS_PN = "AN58";
"VSS<757>":   PN = "AN28"  !CDS_PN = "AN28";
"VSS<758>":   PN = "AN6"  !CDS_PN = "AN6";
"VSS<759>":   PN = "AN2"  !CDS_PN = "AN2";
"VSS<760>":   PN = "AM83"  !CDS_PN = "AM83";
"VSS<761>":   PN = "AM79"  !CDS_PN = "AM79";
"VSS<762>":   PN = "AM73"  !CDS_PN = "AM73";
"VSS<763>":   PN = "AM69"  !CDS_PN = "AM69";
"VSS<764>":   PN = "AM63"  !CDS_PN = "AM63";
"VSS<765>":   PN = "AM57"  !CDS_PN = "AM57";
"VSS<766>":   PN = "AM31"  !CDS_PN = "AM31";
"VSS<767>":   PN = "AC50"  !CDS_PN = "AC50";
"VSS<768>":   PN = "AM1"  !CDS_PN = "AM1";
"VSS<769>":   PN = "AL86"  !CDS_PN = "AL86";
"VSS<770>":   PN = "AL82"  !CDS_PN = "AL82";
"VSS<771>":   PN = "AL80"  !CDS_PN = "AL80";
"VSS<772>":   PN = "AL78"  !CDS_PN = "AL78";
"VSS<773>":   PN = "AL76"  !CDS_PN = "AL76";
DRAWING = "@baseboard_fab2_lib.baseboard_fab2(sch_1):page75";
BODY = "SKX_EXT_B","I17": #LOCATION = "U2D1" !CDS_LOCATION = "U2D1" #SEC = "27" !CDS_SEC = "27";
"VSS<454>":   PN = "P49"  !CDS_PN = "P49";
"VSS<455>":   PN = "CJ12"  !CDS_PN = "CJ12";
"VSS<456>":   PN = "CJ10"  !CDS_PN = "CJ10";
"VSS<457>":   PN = "CJ8"  !CDS_PN = "CJ8";
"VSS<458>":   PN = "CJ6"  !CDS_PN = "CJ6";
"VSS<459>":   PN = "CJ2"  !CDS_PN = "CJ2";
"VSS<460>":   PN = "CH83"  !CDS_PN = "CH83";
"VSS<461>":   PN = "CH81"  !CDS_PN = "CH81";
"VSS<462>":   PN = "CH79"  !CDS_PN = "CH79";
"VSS<463>":   PN = "CH73"  !CDS_PN = "CH73";
"VSS<464>":   PN = "CH67"  !CDS_PN = "CH67";
"VSS<465>":   PN = "CH63"  !CDS_PN = "CH63";
"VSS<466>":   PN = "CH19"  !CDS_PN = "CH19";
"VSS<467>":   PN = "CH15"  !CDS_PN = "CH15";
"VSS<468>":   PN = "CH3"  !CDS_PN = "CH3";
"VSS<469>":   PN = "CH1"  !CDS_PN = "CH1";
"VSS<470>":   PN = "CG80"  !CDS_PN = "CG80";
"VSS<471>":   PN = "CG72"  !CDS_PN = "CG72";
"VSS<472>":   PN = "CG68"  !CDS_PN = "CG68";
"VSS<473>":   PN = "CG62"  !CDS_PN = "CG62";
"VSS<474>":   PN = "CG22"  !CDS_PN = "CG22";
"VSS<475>":   PN = "CG18"  !CDS_PN = "CG18";
"VSS<476>":   PN = "P51"  !CDS_PN = "P51";
"VSS<477>":   PN = "CF83"  !CDS_PN = "CF83";
"VSS<478>":   PN = "CF77"  !CDS_PN = "CF77";
"VSS<479>":   PN = "CF71"  !CDS_PN = "CF71";
"VSS<480>":   PN = "CF69"  !CDS_PN = "CF69";
"VSS<481>":   PN = "CF63"  !CDS_PN = "CF63";
"VSS<482>":   PN = "CF9"  !CDS_PN = "CF9";
"VSS<483>":   PN = "P53"  !CDS_PN = "P53";
"VSS<484>":   PN = "CE82"  !CDS_PN = "CE82";
"VSS<485>":   PN = "CE70"  !CDS_PN = "CE70";
"VSS<486>":   PN = "CE62"  !CDS_PN = "CE62";
"VSS<487>":   PN = "CE26"  !CDS_PN = "CE26";
"VSS<488>":   PN = "CE20"  !CDS_PN = "CE20";
"VSS<489>":   PN = "CE14"  !CDS_PN = "CE14";
"VSS<490>":   PN = "CE10"  !CDS_PN = "CE10";
"VSS<491>":   PN = "CD81"  !CDS_PN = "CD81";
"VSS<492>":   PN = "CD79"  !CDS_PN = "CD79";
"VSS<493>":   PN = "CD77"  !CDS_PN = "CD77";
"VSS<494>":   PN = "CD75"  !CDS_PN = "CD75";
"VSS<495>":   PN = "CD73"  !CDS_PN = "CD73";
"VSS<496>":   PN = "CD63"  !CDS_PN = "CD63";
"VSS<497>":   PN = "CD13"  !CDS_PN = "CD13";
"VSS<498>":   PN = "CD5"  !CDS_PN = "CD5";
"VSS<499>":   PN = "CC82"  !CDS_PN = "CC82";
"VSS<500>":   PN = "CC80"  !CDS_PN = "CC80";
"VSS<501>":   PN = "CC78"  !CDS_PN = "CC78";
"VSS<502>":   PN = "CC76"  !CDS_PN = "CC76";
"VSS<503>":   PN = "CC74"  !CDS_PN = "CC74";
"VSS<504>":   PN = "CC72"  !CDS_PN = "CC72";
"VSS<505>":   PN = "CC64"  !CDS_PN = "CC64";
"VSS<506>":   PN = "CC24"  !CDS_PN = "CC24";
"VSS<507>":   PN = "CC18"  !CDS_PN = "CC18";
"VSS<508>":   PN = "CC16"  !CDS_PN = "CC16";
"VSS<509>":   PN = "CC4"  !CDS_PN = "CC4";
"VSS<510>":   PN = "CB71"  !CDS_PN = "CB71";
"VSS<511>":   PN = "CB63"  !CDS_PN = "CB63";
"VSS<512>":   PN = "CB27"  !CDS_PN = "CB27";
"VSS<513>":   PN = "CB9"  !CDS_PN = "CB9";
"VSS<514>":   PN = "CB7"  !CDS_PN = "CB7";
"VSS<515>":   PN = "CA70"  !CDS_PN = "CA70";
"VSS<516>":   PN = "CA68"  !CDS_PN = "CA68";
"VSS<517>":   PN = "CA66"  !CDS_PN = "CA66";
"VSS<518>":   PN = "CA64"  !CDS_PN = "CA64";
"VSS<519>":   PN = "CA26"  !CDS_PN = "CA26";
"VSS<520>":   PN = "CA18"  !CDS_PN = "CA18";
"VSS<521>":   PN = "CA14"  !CDS_PN = "CA14";
"VSS<522>":   PN = "CA10"  !CDS_PN = "CA10";
"VSS<523>":   PN = "CA8"  !CDS_PN = "CA8";
"VSS<524>":   PN = "CA6"  !CDS_PN = "CA6";
"VSS<525>":   PN = "CA2"  !CDS_PN = "CA2";
"VSS<526>":   PN = "BY71"  !CDS_PN = "BY71";
"VSS<527>":   PN = "BY69"  !CDS_PN = "BY69";
"VSS<528>":   PN = "BY67"  !CDS_PN = "BY67";
"VSS<529>":   PN = "BY65"  !CDS_PN = "BY65";
"VSS<530>":   PN = "BY63"  !CDS_PN = "BY63";
"VSS<531>":   PN = "BY23"  !CDS_PN = "BY23";
"VSS<532>":   PN = "BY13"  !CDS_PN = "BY13";
"VSS<533>":   PN = "BY11"  !CDS_PN = "BY11";
"VSS<534>":   PN = "BW82"  !CDS_PN = "BW82";
"VSS<535>":   PN = "BW80"  !CDS_PN = "BW80";
"VSS<536>":   PN = "BW78"  !CDS_PN = "BW78";
"VSS<537>":   PN = "BW76"  !CDS_PN = "BW76";
"VSS<538>":   PN = "BW74"  !CDS_PN = "BW74";
"VSS<539>":   PN = "BW72"  !CDS_PN = "BW72";
"VSS<540>":   PN = "BW26"  !CDS_PN = "BW26";
"VSS<541>":   PN = "BW18"  !CDS_PN = "BW18";
"VSS<542>":   PN = "BW16"  !CDS_PN = "BW16";
"VSS<543>":   PN = "BW14"  !CDS_PN = "BW14";
"VSS<544>":   PN = "BW12"  !CDS_PN = "BW12";
"VSS<545>":   PN = "P55"  !CDS_PN = "P55";
"VSS<546>":   PN = "BW6"  !CDS_PN = "BW6";
"VSS<547>":   PN = "BV25"  !CDS_PN = "BV25";
"VSS<548>":   PN = "BV17"  !CDS_PN = "BV17";
"VSS<549>":   PN = "BU10"  !CDS_PN = "BU10";
"VSS<550>":   PN = "BV5"  !CDS_PN = "BV5";
"VSS<551>":   PN = "BU8"  !CDS_PN = "BU8";
"VSS<552>":   PN = "BT25"  !CDS_PN = "BT25";
"VSS<553>":   PN = "BT23"  !CDS_PN = "BT23";
"VSS<554>":   PN = "BT21"  !CDS_PN = "BT21";
"VSS<555>":   PN = "BT5"  !CDS_PN = "BT5";
"VSS<556>":   PN = "BT3"  !CDS_PN = "BT3";
"VSS<557>":   PN = "BR82"  !CDS_PN = "BR82";
"VSS<558>":   PN = "BR80"  !CDS_PN = "BR80";
"VSS<559>":   PN = "BR78"  !CDS_PN = "BR78";
"VSS<560>":   PN = "BR76"  !CDS_PN = "BR76";
"VSS<561>":   PN = "BR74"  !CDS_PN = "BR74";
"VSS<562>":   PN = "BR72"  !CDS_PN = "BR72";
"VSS<563>":   PN = "BR70"  !CDS_PN = "BR70";
"VSS<564>":   PN = "BR68"  !CDS_PN = "BR68";
"VSS<565>":   PN = "BR66"  !CDS_PN = "BR66";
"VSS<566>":   PN = "BR64"  !CDS_PN = "BR64";
"VSS<567>":   PN = "P57"  !CDS_PN = "P57";
"VSS<568>":   PN = "BR16"  !CDS_PN = "BR16";
"VSS<569>":   PN = "BR10"  !CDS_PN = "BR10";
"VSS<570>":   PN = "BR6"  !CDS_PN = "BR6";
"VSS<571>":   PN = "BP27"  !CDS_PN = "BP27";
"VSS<572>":   PN = "BP3"  !CDS_PN = "BP3";
"VSS<573>":   PN = "BN26"  !CDS_PN = "BN26";
"VSS<574>":   PN = "BN20"  !CDS_PN = "BN20";
"VSS<575>":   PN = "BN10"  !CDS_PN = "BN10";
"VSS<576>":   PN = "BN6"  !CDS_PN = "BN6";
"VSS<577>":   PN = "BM25"  !CDS_PN = "BM25";
"VSS<578>":   PN = "P59"  !CDS_PN = "P59";
"VSS<579>":   PN = "BM15"  !CDS_PN = "BM15";
"VSS<580>":   PN = "BM13"  !CDS_PN = "BM13";
"VSS<581>":   PN = "BM9"  !CDS_PN = "BM9";
"VSS<582>":   PN = "BL82"  !CDS_PN = "BL82";
"VSS<583>":   PN = "BL80"  !CDS_PN = "BL80";
"VSS<584>":   PN = "BL78"  !CDS_PN = "BL78";
"VSS<585>":   PN = "BL76"  !CDS_PN = "BL76";
"VSS<586>":   PN = "BL74"  !CDS_PN = "BL74";
"VSS<587>":   PN = "BL72"  !CDS_PN = "BL72";
"VSS<588>":   PN = "BL70"  !CDS_PN = "BL70";
"VSS<589>":   PN = "BL68"  !CDS_PN = "BL68";
"VSS<590>":   PN = "BL66"  !CDS_PN = "BL66";
"VSS<591>":   PN = "BL64"  !CDS_PN = "BL64";
"VSS<592>":   PN = "BL24"  !CDS_PN = "BL24";
"VSS<593>":   PN = "BL22"  !CDS_PN = "BL22";
"VSS<594>":   PN = "P61"  !CDS_PN = "P61";
"VSS<595>":   PN = "BL12"  !CDS_PN = "BL12";
"VSS<596>":   PN = "BL10"  !CDS_PN = "BL10";
"VSS<597>":   PN = "BL6"  !CDS_PN = "BL6";
"VSS<598>":   PN = "BK19"  !CDS_PN = "BK19";
"VSS<599>":   PN = "BK11"  !CDS_PN = "BK11";
"VSS<600>":   PN = "BK7"  !CDS_PN = "BK7";
"VSS<601>":   PN = "BK3"  !CDS_PN = "BK3";
"VSS<602>":   PN = "BJ6"  !CDS_PN = "BJ6";
"VSS<603>":   PN = "BJ4"  !CDS_PN = "BJ4";
"VSS<604>":   PN = "BH21"  !CDS_PN = "BH21";
"VSS<605>":   PN = "BH15"  !CDS_PN = "BH15";
"VSS<606>":   PN = "BH11"  !CDS_PN = "BH11";
"VSS<607>":   PN = "BH9"  !CDS_PN = "BH9";
"VSS<608>":   PN = "BH7"  !CDS_PN = "BH7";
"VSS<609>":   PN = "BG82"  !CDS_PN = "BG82";
"VSS<610>":   PN = "BG80"  !CDS_PN = "BG80";
"VSS<611>":   PN = "BG78"  !CDS_PN = "BG78";
"VSS<612>":   PN = "BG76"  !CDS_PN = "BG76";
"VSS<613>":   PN = "BG74"  !CDS_PN = "BG74";
BODY = "SKX_EXT_B","I18": #LOCATION = "U2D1" !CDS_LOCATION = "U2D1" #SEC = "28" !CDS_SEC = "28";
"VSS<294>":   PN = "DA46"  !CDS_PN = "DA46";
"VSS<295>":   PN = "DA44"  !CDS_PN = "DA44";
"VSS<296>":   PN = "DA38"  !CDS_PN = "DA38";
"VSS<297>":   PN = "DA36"  !CDS_PN = "DA36";
"VSS<298>":   PN = "DA34"  !CDS_PN = "DA34";
"VSS<299>":   PN = "DA32"  !CDS_PN = "DA32";
"VSS<300>":   PN = "DA30"  !CDS_PN = "DA30";
"VSS<301>":   PN = "DA28"  !CDS_PN = "DA28";
"VSS<302>":   PN = "DA26"  !CDS_PN = "DA26";
"VSS<303>":   PN = "DA18"  !CDS_PN = "DA18";
"VSS<304>":   PN = "H53"  !CDS_PN = "H53";
"VSS<305>":   PN = "DA6"  !CDS_PN = "DA6";
"VSS<306>":   PN = "CY85"  !CDS_PN = "CY85";
"VSS<307>":   PN = "CY83"  !CDS_PN = "CY83";
"VSS<308>":   PN = "CY77"  !CDS_PN = "CY77";
"VSS<309>":   PN = "CY75"  !CDS_PN = "CY75";
"VSS<310>":   PN = "CY69"  !CDS_PN = "CY69";
"VSS<311>":   PN = "CY65"  !CDS_PN = "CY65";
"VSS<312>":   PN = "CY61"  !CDS_PN = "CY61";
"VSS<313>":   PN = "CY59"  !CDS_PN = "CY59";
"VSS<314>":   PN = "CY51"  !CDS_PN = "CY51";
"VSS<315>":   PN = "CY45"  !CDS_PN = "CY45";
"VSS<316>":   PN = "CY41"  !CDS_PN = "CY41";
"VSS<317>":   PN = "CY21"  !CDS_PN = "CY21";
"VSS<318>":   PN = "CY15"  !CDS_PN = "CY15";
"VSS<319>":   PN = "CY13"  !CDS_PN = "CY13";
"VSS<320>":   PN = "CY9"  !CDS_PN = "CY9";
"VSS<321>":   PN = "CY1"  !CDS_PN = "CY1";
"VSS<322>":   PN = "CW82"  !CDS_PN = "CW82";
"VSS<323>":   PN = "CW78"  !CDS_PN = "CW78";
"VSS<324>":   PN = "CW74"  !CDS_PN = "CW74";
"VSS<325>":   PN = "CW68"  !CDS_PN = "CW68";
"VSS<326>":   PN = "CW66"  !CDS_PN = "CW66";
"VSS<327>":   PN = "CW64"  !CDS_PN = "CW64";
"VSS<328>":   PN = "CW54"  !CDS_PN = "CW54";
"VSS<329>":   PN = "CW52"  !CDS_PN = "CW52";
"VSS<330>":   PN = "CW42"  !CDS_PN = "CW42";
"VSS<331>":   PN = "CW40"  !CDS_PN = "CW40";
"VSS<332>":   PN = "CW38"  !CDS_PN = "CW38";
"VSS<333>":   PN = "CW32"  !CDS_PN = "CW32";
"VSS<334>":   PN = "CW26"  !CDS_PN = "CW26";
"VSS<335>":   PN = "CW12"  !CDS_PN = "CW12";
"VSS<336>":   PN = "CV83"  !CDS_PN = "CV83";
"VSS<337>":   PN = "CV81"  !CDS_PN = "CV81";
"VSS<338>":   PN = "CV79"  !CDS_PN = "CV79";
"VSS<339>":   PN = "CV73"  !CDS_PN = "CV73";
"VSS<340>":   PN = "CV67"  !CDS_PN = "CV67";
"VSS<341>":   PN = "CV63"  !CDS_PN = "CV63";
"VSS<342>":   PN = "CV55"  !CDS_PN = "CV55";
"VSS<343>":   PN = "CV53"  !CDS_PN = "CV53";
"VSS<344>":   PN = "CV41"  !CDS_PN = "CV41";
"VSS<345>":   PN = "CV39"  !CDS_PN = "CV39";
"VSS<346>":   PN = "CV37"  !CDS_PN = "CV37";
"VSS<347>":   PN = "CV33"  !CDS_PN = "CV33";
"VSS<348>":   PN = "CV31"  !CDS_PN = "CV31";
"VSS<349>":   PN = "CV27"  !CDS_PN = "CV27";
"VSS<350>":   PN = "CV25"  !CDS_PN = "CV25";
"VSS<351>":   PN = "CV17"  !CDS_PN = "CV17";
"VSS<352>":   PN = "H55"  !CDS_PN = "H55";
"VSS<353>":   PN = "CV1"  !CDS_PN = "CV1";
"VSS<354>":   PN = "CU86"  !CDS_PN = "CU86";
"VSS<355>":   PN = "CU82"  !CDS_PN = "CU82";
"VSS<356>":   PN = "CU80"  !CDS_PN = "CU80";
"VSS<357>":   PN = "CU78"  !CDS_PN = "CU78";
"VSS<358>":   PN = "CU76"  !CDS_PN = "CU76";
"VSS<359>":   PN = "CU68"  !CDS_PN = "CU68";
"VSS<360>":   PN = "CU62"  !CDS_PN = "CU62";
"VSS<361>":   PN = "CU56"  !CDS_PN = "CU56";
"VSS<362>":   PN = "CU36"  !CDS_PN = "CU36";
"VSS<363>":   PN = "CU34"  !CDS_PN = "CU34";
"VSS<364>":   PN = "CU30"  !CDS_PN = "CU30";
"VSS<365>":   PN = "CU28"  !CDS_PN = "CU28";
"VSS<366>":   PN = "CU22"  !CDS_PN = "CU22";
"VSS<367>":   PN = "CU4"  !CDS_PN = "CU4";
"VSS<368>":   PN = "CT85"  !CDS_PN = "CT85";
"VSS<369>":   PN = "CT83"  !CDS_PN = "CT83";
"VSS<370>":   PN = "CT79"  !CDS_PN = "CT79";
"VSS<371>":   PN = "CT73"  !CDS_PN = "CT73";
"VSS<372>":   PN = "CT57"  !CDS_PN = "CT57";
"VSS<373>":   PN = "CT35"  !CDS_PN = "CT35";
"VSS<374>":   PN = "CT33"  !CDS_PN = "CT33";
"VSS<375>":   PN = "CT29"  !CDS_PN = "CT29";
"VSS<376>":   PN = "CT27"  !CDS_PN = "CT27";
"VSS<377>":   PN = "CT19"  !CDS_PN = "CT19";
"VSS<378>":   PN = "CT13"  !CDS_PN = "CT13";
"VSS<379>":   PN = "H57"  !CDS_PN = "H57";
"VSS<380>":   PN = "CR86"  !CDS_PN = "CR86";
"VSS<381>":   PN = "CR78"  !CDS_PN = "CR78";
"VSS<382>":   PN = "CR68"  !CDS_PN = "CR68";
"VSS<383>":   PN = "CR66"  !CDS_PN = "CR66";
"VSS<384>":   PN = "CR64"  !CDS_PN = "CR64";
"VSS<385>":   PN = "CR62"  !CDS_PN = "CR62";
"VSS<386>":   PN = "CR58"  !CDS_PN = "CR58";
"VSS<387>":   PN = "CR32"  !CDS_PN = "CR32";
"VSS<388>":   PN = "CR24"  !CDS_PN = "CR24";
"VSS<389>":   PN = "CR22"  !CDS_PN = "CR22";
"VSS<390>":   PN = "CR10"  !CDS_PN = "CR10";
"VSS<391>":   PN = "CR6"  !CDS_PN = "CR6";
"VSS<392>":   PN = "CP83"  !CDS_PN = "CP83";
"VSS<393>":   PN = "CP81"  !CDS_PN = "CP81";
"VSS<394>":   PN = "CP75"  !CDS_PN = "CP75";
"VSS<395>":   PN = "CP73"  !CDS_PN = "CP73";
"VSS<396>":   PN = "CP69"  !CDS_PN = "CP69";
"VSS<397>":   PN = "CP59"  !CDS_PN = "CP59";
"VSS<398>":   PN = "CP25"  !CDS_PN = "CP25";
"VSS<399>":   PN = "H59"  !CDS_PN = "H59";
"VSS<400>":   PN = "CP1"  !CDS_PN = "CP1";
"VSS<401>":   PN = "CN78"  !CDS_PN = "CN78";
"VSS<402>":   PN = "CN68"  !CDS_PN = "CN68";
"VSS<403>":   PN = "CN62"  !CDS_PN = "CN62";
"VSS<404>":   PN = "CN60"  !CDS_PN = "CN60";
"VSS<405>":   PN = "CN32"  !CDS_PN = "CN32";
"VSS<406>":   PN = "CN26"  !CDS_PN = "CN26";
"VSS<407>":   PN = "H61"  !CDS_PN = "H61";
"VSS<408>":   PN = "CN12"  !CDS_PN = "CN12";
"VSS<409>":   PN = "CN2"  !CDS_PN = "CN2";
"VSS<410>":   PN = "CM85"  !CDS_PN = "CM85";
"VSS<411>":   PN = "CM83"  !CDS_PN = "CM83";
"VSS<412>":   PN = "CM77"  !CDS_PN = "CM77";
"VSS<413>":   PN = "CM73"  !CDS_PN = "CM73";
"VSS<414>":   PN = "CM67"  !CDS_PN = "CM67";
"VSS<415>":   PN = "CM63"  !CDS_PN = "CM63";
"VSS<416>":   PN = "CM61"  !CDS_PN = "CM61";
"VSS<417>":   PN = "CM31"  !CDS_PN = "CM31";
"VSS<418>":   PN = "CM5"  !CDS_PN = "CM5";
"VSS<419>":   PN = "CM29"  !CDS_PN = "CM29";
"VSS<420>":   PN = "CM19"  !CDS_PN = "CM19";
"VSS<421>":   PN = "CL80"  !CDS_PN = "CL80";
"VSS<422>":   PN = "CL78"  !CDS_PN = "CL78";
"VSS<423>":   PN = "CL76"  !CDS_PN = "CL76";
"VSS<424>":   PN = "CL74"  !CDS_PN = "CL74";
"VSS<425>":   PN = "CL66"  !CDS_PN = "CL66";
"VSS<426>":   PN = "CL64"  !CDS_PN = "CL64";
"VSS<427>":   PN = "CL62"  !CDS_PN = "CL62";
"VSS<428>":   PN = "H63"  !CDS_PN = "H63";
"VSS<429>":   PN = "P45"  !CDS_PN = "P45";
"VSS<430>":   PN = "CL18"  !CDS_PN = "CL18";
"VSS<431>":   PN = "CL14"  !CDS_PN = "CL14";
"VSS<432>":   PN = "CL8"  !CDS_PN = "CL8";
"VSS<433>":   PN = "CK85"  !CDS_PN = "CK85";
"VSS<434>":   PN = "CK83"  !CDS_PN = "CK83";
"VSS<435>":   PN = "CK75"  !CDS_PN = "CK75";
"VSS<436>":   PN = "CK73"  !CDS_PN = "CK73";
"VSS<437>":   PN = "CK71"  !CDS_PN = "CK71";
"VSS<438>":   PN = "CK69"  !CDS_PN = "CK69";
"VSS<439>":   PN = "CK67"  !CDS_PN = "CK67";
"VSS<440>":   PN = "CK65"  !CDS_PN = "CK65";
"VSS<441>":   PN = "CK63"  !CDS_PN = "CK63";
"VSS<442>":   PN = "CK27"  !CDS_PN = "CK27";
"VSS<443>":   PN = "CK21"  !CDS_PN = "CK21";
"VSS<444>":   PN = "CK15"  !CDS_PN = "CK15";
"VSS<445>":   PN = "CK11"  !CDS_PN = "CK11";
"VSS<446>":   PN = "CJ86"  !CDS_PN = "CJ86";
"VSS<447>":   PN = "CJ84"  !CDS_PN = "CJ84";
"VSS<448>":   PN = "CJ82"  !CDS_PN = "CJ82";
"VSS<449>":   PN = "CJ78"  !CDS_PN = "CJ78";
"VSS<450>":   PN = "CJ76"  !CDS_PN = "CJ76";
"VSS<451>":   PN = "CJ74"  !CDS_PN = "CJ74";
"VSS<452>":   PN = "CJ62"  !CDS_PN = "CJ62";
"VSS<453>":   PN = "P47"  !CDS_PN = "P47";
BODY = "SKX_EXT_B","I19": #LOCATION = "U2D1" !CDS_LOCATION = "U2D1" #SEC = "29" !CDS_SEC = "29";
"VSS<134>":   PN = "DN72"  !CDS_PN = "DN72";
"VSS<135>":   PN = "DN68"  !CDS_PN = "DN68";
"VSS<136>":   PN = "DN38"  !CDS_PN = "DN38";
"VSS<137>":   PN = "DN32"  !CDS_PN = "DN32";
"VSS<138>":   PN = "DN26"  !CDS_PN = "DN26";
"VSS<139>":   PN = "DN22"  !CDS_PN = "DN22";
"VSS<140>":   PN = "DN12"  !CDS_PN = "DN12";
"VSS<141>":   PN = "BH17"  !CDS_PN = "BH17";
"VSS<142>":   PN = "DN2"  !CDS_PN = "DN2";
"VSS<143>":   PN = "DM83"  !CDS_PN = "DM83";
"VSS<144>":   PN = "DM77"  !CDS_PN = "DM77";
"VSS<145>":   PN = "DM73"  !CDS_PN = "DM73";
"VSS<146>":   PN = "DM65"  !CDS_PN = "DM65";
"VSS<147>":   PN = "DM39"  !CDS_PN = "DM39";
"VSS<148>":   PN = "DM37"  !CDS_PN = "DM37";
"VSS<149>":   PN = "DM33"  !CDS_PN = "DM33";
"VSS<150>":   PN = "DM31"  !CDS_PN = "DM31";
"VSS<151>":   PN = "DM27"  !CDS_PN = "DM27";
"VSS<152>":   PN = "DM25"  !CDS_PN = "DM25";
"VSS<153>":   PN = "H45"  !CDS_PN = "H45";
"VSS<154>":   PN = "DM15"  !CDS_PN = "DM15";
"VSS<155>":   PN = "DL80"  !CDS_PN = "DL80";
"VSS<156>":   PN = "DL78"  !CDS_PN = "DL78";
"VSS<157>":   PN = "DL76"  !CDS_PN = "DL76";
"VSS<158>":   PN = "DL74"  !CDS_PN = "DL74";
"VSS<159>":   PN = "DL70"  !CDS_PN = "DL70";
"VSS<160>":   PN = "DL68"  !CDS_PN = "DL68";
"VSS<161>":   PN = "DL40"  !CDS_PN = "DL40";
"VSS<162>":   PN = "DL36"  !CDS_PN = "DL36";
"VSS<163>":   PN = "DL34"  !CDS_PN = "DL34";
"VSS<164>":   PN = "DL30"  !CDS_PN = "DL30";
"VSS<165>":   PN = "DL28"  !CDS_PN = "DL28";
"VSS<166>":   PN = "DL24"  !CDS_PN = "DL24";
"VSS<167>":   PN = "DL22"  !CDS_PN = "DL22";
"VSS<168>":   PN = "DL4"  !CDS_PN = "DL4";
"VSS<169>":   PN = "DL18"  !CDS_PN = "DL18";
"VSS<170>":   PN = "DL16"  !CDS_PN = "DL16";
"VSS<171>":   PN = "DK85"  !CDS_PN = "DK85";
"VSS<172>":   PN = "DK83"  !CDS_PN = "DK83";
"VSS<173>":   PN = "DK77"  !CDS_PN = "DK77";
"VSS<174>":   PN = "DK75"  !CDS_PN = "DK75";
"VSS<175>":   PN = "DK73"  !CDS_PN = "DK73";
"VSS<176>":   PN = "DK41"  !CDS_PN = "DK41";
"VSS<177>":   PN = "DK39"  !CDS_PN = "DK39";
"VSS<178>":   PN = "DK35"  !CDS_PN = "DK35";
"VSS<179>":   PN = "DK29"  !CDS_PN = "DK29";
"VSS<180>":   PN = "DK23"  !CDS_PN = "DK23";
"VSS<181>":   PN = "DK7"  !CDS_PN = "DK7";
"VSS<182>":   PN = "DJ84"  !CDS_PN = "DJ84";
"VSS<183>":   PN = "DJ82"  !CDS_PN = "DJ82";
"VSS<184>":   PN = "DJ78"  !CDS_PN = "DJ78";
"VSS<185>":   PN = "DJ74"  !CDS_PN = "DJ74";
"VSS<186>":   PN = "DJ68"  !CDS_PN = "DJ68";
"VSS<187>":   PN = "DJ42"  !CDS_PN = "DJ42";
"VSS<188>":   PN = "DJ38"  !CDS_PN = "DJ38";
"VSS<189>":   PN = "DJ22"  !CDS_PN = "DJ22";
"VSS<190>":   PN = "H47"  !CDS_PN = "H47";
"VSS<191>":   PN = "DJ10"  !CDS_PN = "DJ10";
"VSS<192>":   PN = "DJ2"  !CDS_PN = "DJ2";
"VSS<193>":   PN = "DH83"  !CDS_PN = "DH83";
"VSS<194>":   PN = "DH81"  !CDS_PN = "DH81";
"VSS<195>":   PN = "DH79"  !CDS_PN = "DH79";
"VSS<196>":   PN = "DH73"  !CDS_PN = "DH73";
"VSS<197>":   PN = "DH71"  !CDS_PN = "DH71";
"VSS<198>":   PN = "DH67"  !CDS_PN = "DH67";
"VSS<199>":   PN = "DH41"  !CDS_PN = "DH41";
"VSS<200>":   PN = "DH37"  !CDS_PN = "DH37";
"VSS<201>":   PN = "DH35"  !CDS_PN = "DH35";
"VSS<202>":   PN = "DH33"  !CDS_PN = "DH33";
"VSS<203>":   PN = "DH31"  !CDS_PN = "DH31";
"VSS<204>":   PN = "DH29"  !CDS_PN = "DH29";
"VSS<205>":   PN = "DH27"  !CDS_PN = "DH27";
"VSS<206>":   PN = "DH25"  !CDS_PN = "DH25";
"VSS<207>":   PN = "DH23"  !CDS_PN = "DH23";
"VSS<208>":   PN = "DH15"  !CDS_PN = "DH15";
"VSS<209>":   PN = "DH13"  !CDS_PN = "DH13";
"VSS<210>":   PN = "DG82"  !CDS_PN = "DG82";
"VSS<211>":   PN = "DG80"  !CDS_PN = "DG80";
"VSS<212>":   PN = "DG78"  !CDS_PN = "DG78";
"VSS<213>":   PN = "DG76"  !CDS_PN = "DG76";
"VSS<214>":   PN = "DG68"  !CDS_PN = "DG68";
"VSS<215>":   PN = "DG66"  !CDS_PN = "DG66";
"VSS<216>":   PN = "DG24"  !CDS_PN = "DG24";
"VSS<217>":   PN = "DG16"  !CDS_PN = "DG16";
"VSS<218>":   PN = "DG14"  !CDS_PN = "DG14";
"VSS<219>":   PN = "H49"  !CDS_PN = "H49";
"VSS<220>":   PN = "DG2"  !CDS_PN = "DG2";
"VSS<221>":   PN = "DF85"  !CDS_PN = "DF85";
"VSS<222>":   PN = "DF83"  !CDS_PN = "DF83";
"VSS<223>":   PN = "DF79"  !CDS_PN = "DF79";
"VSS<224>":   PN = "DF73"  !CDS_PN = "DF73";
"VSS<225>":   PN = "DF69"  !CDS_PN = "DF69";
"VSS<226>":   PN = "DF65"  !CDS_PN = "DF65";
"VSS<227>":   PN = "DF41"  !CDS_PN = "DF41";
"VSS<228>":   PN = "DF39"  !CDS_PN = "DF39";
"VSS<229>":   PN = "DF37"  !CDS_PN = "DF37";
"VSS<230>":   PN = "DF35"  !CDS_PN = "DF35";
"VSS<231>":   PN = "DF29"  !CDS_PN = "DF29";
"VSS<232>":   PN = "DF19"  !CDS_PN = "DF19";
"VSS<233>":   PN = "H51"  !CDS_PN = "H51";
"VSS<234>":   PN = "DF7"  !CDS_PN = "DF7";
"VSS<235>":   PN = "DF5"  !CDS_PN = "DF5";
"VSS<236>":   PN = "DE78"  !CDS_PN = "DE78";
"VSS<237>":   PN = "DE72"  !CDS_PN = "DE72";
"VSS<238>":   PN = "DE70"  !CDS_PN = "DE70";
"VSS<239>":   PN = "DE64"  !CDS_PN = "DE64";
"VSS<240>":   PN = "DE36"  !CDS_PN = "DE36";
"VSS<241>":   PN = "DE34"  !CDS_PN = "DE34";
"VSS<242>":   PN = "DE30"  !CDS_PN = "DE30";
"VSS<243>":   PN = "DE28"  !CDS_PN = "DE28";
"VSS<244>":   PN = "DE24"  !CDS_PN = "DE24";
"VSS<245>":   PN = "DE20"  !CDS_PN = "DE20";
"VSS<246>":   PN = "DE18"  !CDS_PN = "DE18";
"VSS<247>":   PN = "DE8"  !CDS_PN = "DE8";
"VSS<248>":   PN = "DE6"  !CDS_PN = "DE6";
"VSS<249>":   PN = "DD83"  !CDS_PN = "DD83";
"VSS<250>":   PN = "DD81"  !CDS_PN = "DD81";
"VSS<251>":   PN = "DD75"  !CDS_PN = "DD75";
"VSS<252>":   PN = "DD73"  !CDS_PN = "DD73";
"VSS<253>":   PN = "DD71"  !CDS_PN = "DD71";
"VSS<254>":   PN = "DD37"  !CDS_PN = "DD37";
"VSS<255>":   PN = "DD33"  !CDS_PN = "DD33";
"VSS<256>":   PN = "DD31"  !CDS_PN = "DD31";
"VSS<257>":   PN = "DD27"  !CDS_PN = "DD27";
"VSS<258>":   PN = "DD23"  !CDS_PN = "DD23";
"VSS<259>":   PN = "DD11"  !CDS_PN = "DD11";
"VSS<260>":   PN = "DC86"  !CDS_PN = "DC86";
"VSS<261>":   PN = "DC84"  !CDS_PN = "DC84";
"VSS<262>":   PN = "DC78"  !CDS_PN = "DC78";
"VSS<263>":   PN = "DC70"  !CDS_PN = "DC70";
"VSS<264>":   PN = "DC68"  !CDS_PN = "DC68";
"VSS<265>":   PN = "DC66"  !CDS_PN = "DC66";
"VSS<266>":   PN = "DC64"  !CDS_PN = "DC64";
"VSS<267>":   PN = "DC42"  !CDS_PN = "DC42";
"VSS<268>":   PN = "DC38"  !CDS_PN = "DC38";
"VSS<269>":   PN = "DC32"  !CDS_PN = "DC32";
"VSS<270>":   PN = "DC26"  !CDS_PN = "DC26";
"VSS<271>":   PN = "DC24"  !CDS_PN = "DC24";
"VSS<272>":   PN = "DC14"  !CDS_PN = "DC14";
"VSS<273>":   PN = "DB85"  !CDS_PN = "DB85";
"VSS<274>":   PN = "DB83"  !CDS_PN = "DB83";
"VSS<275>":   PN = "DB77"  !CDS_PN = "DB77";
"VSS<276>":   PN = "DB73"  !CDS_PN = "DB73";
"VSS<277>":   PN = "DB49"  !CDS_PN = "DB49";
"VSS<278>":   PN = "DB47"  !CDS_PN = "DB47";
"VSS<279>":   PN = "DB41"  !CDS_PN = "DB41";
"VSS<280>":   PN = "DB39"  !CDS_PN = "DB39";
"VSS<281>":   PN = "DB25"  !CDS_PN = "DB25";
"VSS<282>":   PN = "DB23"  !CDS_PN = "DB23";
"VSS<283>":   PN = "DB17"  !CDS_PN = "DB17";
"VSS<284>":   PN = "DB13"  !CDS_PN = "DB13";
"VSS<285>":   PN = "DB3"  !CDS_PN = "DB3";
"VSS<286>":   PN = "DA80"  !CDS_PN = "DA80";
"VSS<287>":   PN = "DA78"  !CDS_PN = "DA78";
"VSS<288>":   PN = "DA76"  !CDS_PN = "DA76";
"VSS<289>":   PN = "DA74"  !CDS_PN = "DA74";
"VSS<290>":   PN = "DA70"  !CDS_PN = "DA70";
"VSS<291>":   PN = "DA64"  !CDS_PN = "DA64";
"VSS<292>":   PN = "DA50"  !CDS_PN = "DA50";
"VSS<293>":   PN = "DA48"  !CDS_PN = "DA48";
BODY = "SKX_EXT_B","I20": #LOCATION = "U2D1" !CDS_LOCATION = "U2D1" #SEC = "30" !CDS_SEC = "30";
"VSS<0>":   PN = "EF79"  !CDS_PN = "EF79";
"VSS<1>":   PN = "EF75"  !CDS_PN = "EF75";
"VSS<2>":   PN = "EF71"  !CDS_PN = "EF71";
"VSS<3>":   PN = "EE78"  !CDS_PN = "EE78";
"VSS<4>":   PN = "EE76"  !CDS_PN = "EE76";
"VSS<5>":   PN = "EE70"  !CDS_PN = "EE70";
"VSS<6>":   PN = "EE36"  !CDS_PN = "EE36";
"VSS<7>":   PN = "EE34"  !CDS_PN = "EE34";
"VSS<8>":   PN = "EE30"  !CDS_PN = "EE30";
"VSS<9>":   PN = "EE28"  !CDS_PN = "EE28";
"VSS<10>":   PN = "EE24"  !CDS_PN = "EE24";
"VSS<11>":   PN = "ED77"  !CDS_PN = "ED77";
"VSS<12>":   PN = "ED35"  !CDS_PN = "ED35";
"VSS<13>":   PN = "ED29"  !CDS_PN = "ED29";
"VSS<14>":   PN = "ED23"  !CDS_PN = "ED23";
"VSS<15>":   PN = "ED15"  !CDS_PN = "ED15";
"VSS<16>":   PN = "ED11"  !CDS_PN = "ED11";
"VSS<17>":   PN = "EC76"  !CDS_PN = "EC76";
"VSS<18>":   PN = "EC74"  !CDS_PN = "EC74";
"VSS<19>":   PN = "EC72"  !CDS_PN = "EC72";
"VSS<20>":   PN = "EC70"  !CDS_PN = "EC70";
"VSS<21>":   PN = "EC10"  !CDS_PN = "EC10";
"VSS<22>":   PN = "EB69"  !CDS_PN = "EB69";
"VSS<23>":   PN = "EB65"  !CDS_PN = "EB65";
"VSS<24>":   PN = "EB41"  !CDS_PN = "EB41";
"VSS<25>":   PN = "EB39"  !CDS_PN = "EB39";
"VSS<26>":   PN = "EB37"  !CDS_PN = "EB37";
"VSS<27>":   PN = "EB35"  !CDS_PN = "EB35";
"VSS<28>":   PN = "EB33"  !CDS_PN = "EB33";
"VSS<29>":   PN = "EB31"  !CDS_PN = "EB31";
"VSS<30>":   PN = "EB29"  !CDS_PN = "EB29";
"VSS<31>":   PN = "EB27"  !CDS_PN = "EB27";
"VSS<32>":   PN = "EB25"  !CDS_PN = "EB25";
"VSS<33>":   PN = "EB23"  !CDS_PN = "EB23";
"VSS<34>":   PN = "BR18"  !CDS_PN = "BR18";
"VSS<35>":   PN = "EB13"  !CDS_PN = "EB13";
"VSS<36>":   PN = "EA82"  !CDS_PN = "EA82";
"VSS<37>":   PN = "EA80"  !CDS_PN = "EA80";
"VSS<38>":   PN = "EA78"  !CDS_PN = "EA78";
"VSS<39>":   PN = "EA76"  !CDS_PN = "EA76";
"VSS<40>":   PN = "EA70"  !CDS_PN = "EA70";
"VSS<41>":   PN = "EA64"  !CDS_PN = "EA64";
"VSS<42>":   PN = "EA42"  !CDS_PN = "EA42";
"VSS<43>":   PN = "EA22"  !CDS_PN = "EA22";
"VSS<44>":   PN = "EA20"  !CDS_PN = "EA20";
"VSS<45>":   PN = "EA16"  !CDS_PN = "EA16";
"VSS<46>":   PN = "J16"  !CDS_PN = "J16";
"VSS<47>":   PN = "EA6"  !CDS_PN = "EA6";
"VSS<48>":   PN = "DY75"  !CDS_PN = "DY75";
"VSS<49>":   PN = "DY71"  !CDS_PN = "DY71";
"VSS<50>":   PN = "DY41"  !CDS_PN = "DY41";
"VSS<51>":   PN = "DY35"  !CDS_PN = "DY35";
"VSS<52>":   PN = "DY29"  !CDS_PN = "DY29";
"VSS<53>":   PN = "DY23"  !CDS_PN = "DY23";
"VSS<54>":   PN = "DY19"  !CDS_PN = "DY19";
"VSS<55>":   PN = "DY5"  !CDS_PN = "DY5";
"VSS<56>":   PN = "DW84"  !CDS_PN = "DW84";
"VSS<57>":   PN = "DW82"  !CDS_PN = "DW82";
"VSS<58>":   PN = "DW8"  !CDS_PN = "DW8";
"VSS<59>":   PN = "DW76"  !CDS_PN = "DW76";
"VSS<60>":   PN = "DW74"  !CDS_PN = "DW74";
"VSS<61>":   PN = "DW72"  !CDS_PN = "DW72";
"VSS<62>":   PN = "DW70"  !CDS_PN = "DW70";
"VSS<63>":   PN = "DW68"  !CDS_PN = "DW68";
"VSS<64>":   PN = "DW66"  !CDS_PN = "DW66";
"VSS<65>":   PN = "DW64"  !CDS_PN = "DW64";
"VSS<66>":   PN = "DW40"  !CDS_PN = "DW40";
"VSS<67>":   PN = "DW36"  !CDS_PN = "DW36";
"VSS<68>":   PN = "DW34"  !CDS_PN = "DW34";
"VSS<69>":   PN = "DW30"  !CDS_PN = "DW30";
"VSS<70>":   PN = "DW28"  !CDS_PN = "DW28";
"VSS<71>":   PN = "DW24"  !CDS_PN = "DW24";
"VSS<72>":   PN = "DW20"  !CDS_PN = "DW20";
"VSS<73>":   PN = "DW12"  !CDS_PN = "DW12";
"VSS<74>":   PN = "DV81"  !CDS_PN = "DV81";
"VSS<75>":   PN = "DV77"  !CDS_PN = "DV77";
"VSS<76>":   PN = "DV73"  !CDS_PN = "DV73";
"VSS<77>":   PN = "DV39"  !CDS_PN = "DV39";
"VSS<78>":   PN = "DV37"  !CDS_PN = "DV37";
"VSS<79>":   PN = "DV33"  !CDS_PN = "DV33";
"VSS<80>":   PN = "DV31"  !CDS_PN = "DV31";
"VSS<81>":   PN = "DV27"  !CDS_PN = "DV27";
"VSS<82>":   PN = "DV25"  !CDS_PN = "DV25";
"VSS<83>":   PN = "DV21"  !CDS_PN = "DV21";
"VSS<84>":   PN = "DU84"  !CDS_PN = "DU84";
"VSS<85>":   PN = "DU82"  !CDS_PN = "DU82";
"VSS<86>":   PN = "DU80"  !CDS_PN = "DU80";
"VSS<87>":   PN = "DU78"  !CDS_PN = "DU78";
"VSS<88>":   PN = "DU72"  !CDS_PN = "DU72";
"VSS<89>":   PN = "DU70"  !CDS_PN = "DU70";
"VSS<90>":   PN = "DU38"  !CDS_PN = "DU38";
"VSS<91>":   PN = "DU32"  !CDS_PN = "DU32";
"VSS<92>":   PN = "DU26"  !CDS_PN = "DU26";
"VSS<93>":   PN = "DU22"  !CDS_PN = "DU22";
"VSS<94>":   PN = "CN14"  !CDS_PN = "CN14";
"VSS<95>":   PN = "DU14"  !CDS_PN = "DU14";
"VSS<96>":   PN = "DU10"  !CDS_PN = "DU10";
"VSS<97>":   PN = "DT85"  !CDS_PN = "DT85";
"VSS<98>":   PN = "DT83"  !CDS_PN = "DT83";
"VSS<99>":   PN = "DT79"  !CDS_PN = "DT79";
"VSS<100>":   PN = "DT69"  !CDS_PN = "DT69";
"VSS<101>":   PN = "DT65"  !CDS_PN = "DT65";
"VSS<102>":   PN = "DH21"  !CDS_PN = "DH21";
"VSS<103>":   PN = "DT17"  !CDS_PN = "DT17";
"VSS<104>":   PN = "DT3"  !CDS_PN = "DT3";
"VSS<105>":   PN = "DR78"  !CDS_PN = "DR78";
"VSS<106>":   PN = "DR76"  !CDS_PN = "DR76";
"VSS<107>":   PN = "DR74"  !CDS_PN = "DR74";
"VSS<108>":   PN = "DR72"  !CDS_PN = "DR72";
"VSS<109>":   PN = "DR70"  !CDS_PN = "DR70";
"VSS<110>":   PN = "DR68"  !CDS_PN = "DR68";
"VSS<111>":   PN = "DR66"  !CDS_PN = "DR66";
"VSS<112>":   PN = "DR42"  !CDS_PN = "DR42";
"VSS<113>":   PN = "DR40"  !CDS_PN = "DR40";
"VSS<114>":   PN = "DR38"  !CDS_PN = "DR38";
"VSS<115>":   PN = "DR36"  !CDS_PN = "DR36";
"VSS<116>":   PN = "DR34"  !CDS_PN = "DR34";
"VSS<117>":   PN = "DR32"  !CDS_PN = "DR32";
"VSS<118>":   PN = "DR30"  !CDS_PN = "DR30";
"VSS<119>":   PN = "DR28"  !CDS_PN = "DR28";
"VSS<120>":   PN = "DR26"  !CDS_PN = "DR26";
"VSS<121>":   PN = "DR24"  !CDS_PN = "DR24";
"VSS<122>":   PN = "DR22"  !CDS_PN = "DR22";
"VSS<123>":   PN = "DR20"  !CDS_PN = "DR20";
"VSS<124>":   PN = "CL22"  !CDS_PN = "CL22";
"VSS<125>":   PN = "CA20"  !CDS_PN = "CA20";
"VSS<126>":   PN = "DR6"  !CDS_PN = "DR6";
"VSS<127>":   PN = "BR26"  !CDS_PN = "BR26";
"VSS<128>":   PN = "DP83"  !CDS_PN = "DP83";
"VSS<129>":   PN = "DP81"  !CDS_PN = "DP81";
"VSS<130>":   PN = "DP71"  !CDS_PN = "DP71";
"VSS<131>":   PN = "DP69"  !CDS_PN = "DP69";
"VSS<132>":   PN = "DP67"  !CDS_PN = "DP67";
"VSS<133>":   PN = "DN78"  !CDS_PN = "DN78";
DRAWING = "@baseboard_fab2_lib.baseboard_fab2(sch_1):page76";
BODY = "CAP_A","I1": #LOCATION = "C3D21" !CDS_LOCATION = "C3D21" &SEC = "1" #&CDS_SEC = "1";
"A":   PN = "1"  !CDS_PN = "1";
"B":   PN = "2"  !CDS_PN = "2";
BODY = "CAP_A","I3": #LOCATION = "C3D5" !CDS_LOCATION = "C3D5" &SEC = "1" #&CDS_SEC = "1";
"A":   PN = "1"  !CDS_PN = "1";
"B":   PN = "2"  !CDS_PN = "2";
BODY = "CAP_A","I4": #LOCATION = "C3D12" !CDS_LOCATION = "C3D12" &SEC = "1" #&CDS_SEC = "1";
"A":   PN = "1"  !CDS_PN = "1";
"B":   PN = "2"  !CDS_PN = "2";
BODY = "CAP_A","I5": #LOCATION = "C3D4" !CDS_LOCATION = "C3D4" &SEC = "1" #&CDS_SEC = "1";
"A":   PN = "1"  !CDS_PN = "1";
"B":   PN = "2"  !CDS_PN = "2";
BODY = "CAP_A","I7": #LOCATION = "C3D11" !CDS_LOCATION = "C3D11" &SEC = "1" #&CDS_SEC = "1";
"A":   PN = "1"  !CDS_PN = "1";
"B":   PN = "2"  !CDS_PN = "2";
BODY = "CAP_A","I8": #LOCATION = "C3D13" !CDS_LOCATION = "C3D13" &SEC = "1" #&CDS_SEC = "1";
"A":   PN = "1"  !CDS_PN = "1";
"B":   PN = "2"  !CDS_PN = "2";
BODY = "CAP_A","I10": #LOCATION = "C2D40" !CDS_LOCATION = "C2D40" &SEC = "1" #&CDS_SEC = "1";
"A":   PN = "1"  !CDS_PN = "1";
"B":   PN = "2"  !CDS_PN = "2";
BODY = "CAP_A","I15": #LOCATION = "C3D9" !CDS_LOCATION = "C3D9" &SEC = "1" #&CDS_SEC = "1";
"A":   PN = "1"  !CDS_PN = "1";
"B":   PN = "2"  !CDS_PN = "2";
BODY = "CAP_A","I18": #LOCATION = "C3D8" !CDS_LOCATION = "C3D8" &SEC = "1" #&CDS_SEC = "1";
"A":   PN = "1"  !CDS_PN = "1";
"B":   PN = "2"  !CDS_PN = "2";
BODY = "CAP","I29": #LOCATION = "C7P17" !CDS_LOCATION = "C7P17" &SEC = "1" #&CDS_SEC = "1";
"A":   PN = "1"  !CDS_PN = "1";
"B":   PN = "2"  !CDS_PN = "2";
BODY = "CAP","I33": #LOCATION = "C2D8" !CDS_LOCATION = "C2D8" &SEC = "1" #&CDS_SEC = "1";
"A":   PN = "1"  !CDS_PN = "1";
"B":   PN = "2"  !CDS_PN = "2";
BODY = "CAP","I37": #LOCATION = "C2D10" !CDS_LOCATION = "C2D10" &SEC = "1" #&CDS_SEC = "1";
"A":   PN = "1"  !CDS_PN = "1";
"B":   PN = "2"  !CDS_PN = "2";
BODY = "CAP","I42": #LOCATION = "C2D11" !CDS_LOCATION = "C2D11" &SEC = "1" #&CDS_SEC = "1";
"A":   PN = "1"  !CDS_PN = "1";
"B":   PN = "2"  !CDS_PN = "2";
BODY = "CAP","I43": #LOCATION = "C2D9" !CDS_LOCATION = "C2D9" &SEC = "1" #&CDS_SEC = "1";
"A":   PN = "1"  !CDS_PN = "1";
"B":   PN = "2"  !CDS_PN = "2";
BODY = "CAP","I51": #LOCATION = "C7P18" !CDS_LOCATION = "C7P18" &SEC = "1" #&CDS_SEC = "1";
"A":   PN = "1"  !CDS_PN = "1";
"B":   PN = "2"  !CDS_PN = "2";
BODY = "CAP","I52": #LOCATION = "C7P3" !CDS_LOCATION = "C7P3" &SEC = "1" #&CDS_SEC = "1";
"A":   PN = "1"  !CDS_PN = "1";
"B":   PN = "2"  !CDS_PN = "2";
BODY = "CAP_A","I59": #LOCATION = "C2D12" !CDS_LOCATION = "C2D12" &SEC = "1" #&CDS_SEC = "1";
"A":   PN = "1"  !CDS_PN = "1";
"B":   PN = "2"  !CDS_PN = "2";
BODY = "CAP_A","I61": #LOCATION = "C2D22" !CDS_LOCATION = "C2D22" &SEC = "1" #&CDS_SEC = "1";
"A":   PN = "1"  !CDS_PN = "1";
"B":   PN = "2"  !CDS_PN = "2";
BODY = "CAP_A","I63": #LOCATION = "C2D31" !CDS_LOCATION = "C2D31" &SEC = "1" #&CDS_SEC = "1";
"A":   PN = "1"  !CDS_PN = "1";
"B":   PN = "2"  !CDS_PN = "2";
BODY = "CAP_A","I65": #LOCATION = "C2D21" !CDS_LOCATION = "C2D21" &SEC = "1" #&CDS_SEC = "1";
"A":   PN = "1"  !CDS_PN = "1";
"B":   PN = "2"  !CDS_PN = "2";
BODY = "CAP_A","I66": #LOCATION = "C2D27" !CDS_LOCATION = "C2D27" &SEC = "1" #&CDS_SEC = "1";
"A":   PN = "1"  !CDS_PN = "1";
"B":   PN = "2"  !CDS_PN = "2";
BODY = "CAP_A","I69": #LOCATION = "C3D2" !CDS_LOCATION = "C3D2" &SEC = "1" #&CDS_SEC = "1";
"A":   PN = "1"  !CDS_PN = "1";
"B":   PN = "2"  !CDS_PN = "2";
BODY = "CAP_A","I70": #LOCATION = "C2D36" !CDS_LOCATION = "C2D36" &SEC = "1" #&CDS_SEC = "1";
"A":   PN = "1"  !CDS_PN = "1";
"B":   PN = "2"  !CDS_PN = "2";
BODY = "CAP_A","I73": #LOCATION = "C2D13" !CDS_LOCATION = "C2D13" &SEC = "1" #&CDS_SEC = "1";
"A":   PN = "1"  !CDS_PN = "1";
"B":   PN = "2"  !CDS_PN = "2";
BODY = "CAP_A","I75": #LOCATION = "C2D19" !CDS_LOCATION = "C2D19" &SEC = "1" #&CDS_SEC = "1";
"A":   PN = "1"  !CDS_PN = "1";
"B":   PN = "2"  !CDS_PN = "2";
BODY = "CAP_A","I76": #LOCATION = "C2D14" !CDS_LOCATION = "C2D14" &SEC = "1" #&CDS_SEC = "1";
"A":   PN = "1"  !CDS_PN = "1";
"B":   PN = "2"  !CDS_PN = "2";
BODY = "CAP_A","I79": #LOCATION = "C2D20" !CDS_LOCATION = "C2D20" &SEC = "1" #&CDS_SEC = "1";
"A":   PN = "1"  !CDS_PN = "1";
"B":   PN = "2"  !CDS_PN = "2";
BODY = "CAP_A","I80": #LOCATION = "C2D24" !CDS_LOCATION = "C2D24" &SEC = "1" #&CDS_SEC = "1";
"A":   PN = "1"  !CDS_PN = "1";
"B":   PN = "2"  !CDS_PN = "2";
BODY = "CAP_A","I82": #LOCATION = "C2D25" !CDS_LOCATION = "C2D25" &SEC = "1" #&CDS_SEC = "1";
"A":   PN = "1"  !CDS_PN = "1";
"B":   PN = "2"  !CDS_PN = "2";
BODY = "CAP_A","I83": #LOCATION = "C2D30" !CDS_LOCATION = "C2D30" &SEC = "1" #&CDS_SEC = "1";
"A":   PN = "1"  !CDS_PN = "1";
"B":   PN = "2"  !CDS_PN = "2";
BODY = "CAP_A","I85": #LOCATION = "C2D33" !CDS_LOCATION = "C2D33" &SEC = "1" #&CDS_SEC = "1";
"A":   PN = "1"  !CDS_PN = "1";
"B":   PN = "2"  !CDS_PN = "2";
BODY = "CAP","I89": #LOCATION = "C8P20" !CDS_LOCATION = "C8P20" &SEC = "1" #&CDS_SEC = "1";
"A":   PN = "1"  !CDS_PN = "1";
"B":   PN = "2"  !CDS_PN = "2";
BODY = "CAP_A","I90": #LOCATION = "C2D32" !CDS_LOCATION = "C2D32" &SEC = "1" #&CDS_SEC = "1";
"A":   PN = "1"  !CDS_PN = "1";
"B":   PN = "2"  !CDS_PN = "2";
BODY = "CAP","I92": #LOCATION = "C8P18" !CDS_LOCATION = "C8P18" &SEC = "1" #&CDS_SEC = "1";
"A":   PN = "1"  !CDS_PN = "1";
"B":   PN = "2"  !CDS_PN = "2";
BODY = "CAP","I103": #LOCATION = "C8P19" !CDS_LOCATION = "C8P19" &SEC = "1" #&CDS_SEC = "1";
"A":   PN = "1"  !CDS_PN = "1";
"B":   PN = "2"  !CDS_PN = "2";
BODY = "CAP","I107": #LOCATION = "C8P12" !CDS_LOCATION = "C8P12" &SEC = "1" #&CDS_SEC = "1";
"A":   PN = "1"  !CDS_PN = "1";
"B":   PN = "2"  !CDS_PN = "2";
BODY = "CAP_A","I108": #LOCATION = "C2D26" !CDS_LOCATION = "C2D26" &SEC = "1" #&CDS_SEC = "1";
"A":   PN = "1"  !CDS_PN = "1";
"B":   PN = "2"  !CDS_PN = "2";
BODY = "CAP_A","I112": #LOCATION = "C2D23" !CDS_LOCATION = "C2D23" &SEC = "1" #&CDS_SEC = "1";
"A":   PN = "1"  !CDS_PN = "1";
"B":   PN = "2"  !CDS_PN = "2";
BODY = "CAP_A","I114": #LOCATION = "C2D17" !CDS_LOCATION = "C2D17" &SEC = "1" #&CDS_SEC = "1";
"A":   PN = "1"  !CDS_PN = "1";
"B":   PN = "2"  !CDS_PN = "2";
BODY = "CAP","I118": #LOCATION = "C8P26" !CDS_LOCATION = "C8P26" &SEC = "1" #&CDS_SEC = "1";
"A":   PN = "1"  !CDS_PN = "1";
"B":   PN = "2"  !CDS_PN = "2";
BODY = "CAP_A","I119": #LOCATION = "C2D37" !CDS_LOCATION = "C2D37" &SEC = "1" #&CDS_SEC = "1";
"A":   PN = "1"  !CDS_PN = "1";
"B":   PN = "2"  !CDS_PN = "2";
BODY = "CAP_A","I122": #LOCATION = "C2D34" !CDS_LOCATION = "C2D34" &SEC = "1" #&CDS_SEC = "1";
"A":   PN = "1"  !CDS_PN = "1";
"B":   PN = "2"  !CDS_PN = "2";
BODY = "CAP_A","I124": #LOCATION = "C2D16" !CDS_LOCATION = "C2D16" &SEC = "1" #&CDS_SEC = "1";
"A":   PN = "1"  !CDS_PN = "1";
"B":   PN = "2"  !CDS_PN = "2";
BODY = "CAP","I125": #LOCATION = "C8P29" !CDS_LOCATION = "C8P29" &SEC = "1" #&CDS_SEC = "1";
"A":   PN = "1"  !CDS_PN = "1";
"B":   PN = "2"  !CDS_PN = "2";
BODY = "CAP","I127": #LOCATION = "C8P10" !CDS_LOCATION = "C8P10" &SEC = "1" #&CDS_SEC = "1";
"A":   PN = "1"  !CDS_PN = "1";
"B":   PN = "2"  !CDS_PN = "2";
BODY = "CAP","I129": #LOCATION = "C8P16" !CDS_LOCATION = "C8P16" &SEC = "1" #&CDS_SEC = "1";
"A":   PN = "1"  !CDS_PN = "1";
"B":   PN = "2"  !CDS_PN = "2";
BODY = "CAP","I132": #LOCATION = "C8P13" !CDS_LOCATION = "C8P13" &SEC = "1" #&CDS_SEC = "1";
"A":   PN = "1"  !CDS_PN = "1";
"B":   PN = "2"  !CDS_PN = "2";
BODY = "CAP","I137": #LOCATION = "C8P28" !CDS_LOCATION = "C8P28" &SEC = "1" #&CDS_SEC = "1";
"A":   PN = "1"  !CDS_PN = "1";
"B":   PN = "2"  !CDS_PN = "2";
BODY = "CAP","I139": #LOCATION = "C8P11" !CDS_LOCATION = "C8P11" &SEC = "1" #&CDS_SEC = "1";
"A":   PN = "1"  !CDS_PN = "1";
"B":   PN = "2"  !CDS_PN = "2";
BODY = "CAP_A","I159": #LOCATION = "C2D15" !CDS_LOCATION = "C2D15" &SEC = "1" #&CDS_SEC = "1";
"A":   PN = "1"  !CDS_PN = "1";
"B":   PN = "2"  !CDS_PN = "2";
BODY = "CAP_A","I160": #LOCATION = "C2D38" !CDS_LOCATION = "C2D38" &SEC = "1" #&CDS_SEC = "1";
"A":   PN = "1"  !CDS_PN = "1";
"B":   PN = "2"  !CDS_PN = "2";
BODY = "CAP_A","I161": #LOCATION = "C2D35" !CDS_LOCATION = "C2D35" &SEC = "1" #&CDS_SEC = "1";
"A":   PN = "1"  !CDS_PN = "1";
"B":   PN = "2"  !CDS_PN = "2";
BODY = "CAP_A","I164": #LOCATION = "C3D7" !CDS_LOCATION = "C3D7" &SEC = "1" #&CDS_SEC = "1";
"A":   PN = "1"  !CDS_PN = "1";
"B":   PN = "2"  !CDS_PN = "2";
BODY = "CAP_A","I165": #LOCATION = "C2D39" !CDS_LOCATION = "C2D39" &SEC = "1" #&CDS_SEC = "1";
"A":   PN = "1"  !CDS_PN = "1";
"B":   PN = "2"  !CDS_PN = "2";
BODY = "CAP_A","I166": #LOCATION = "C3D17" !CDS_LOCATION = "C3D17" &SEC = "1" #&CDS_SEC = "1";
"A":   PN = "1"  !CDS_PN = "1";
"B":   PN = "2"  !CDS_PN = "2";
BODY = "CAP_A","I169": #LOCATION = "C3D18" !CDS_LOCATION = "C3D18" &SEC = "1" #&CDS_SEC = "1";
"A":   PN = "1"  !CDS_PN = "1";
"B":   PN = "2"  !CDS_PN = "2";
BODY = "CAP_A","I170": #LOCATION = "C3D6" !CDS_LOCATION = "C3D6" &SEC = "1" #&CDS_SEC = "1";
"A":   PN = "1"  !CDS_PN = "1";
"B":   PN = "2"  !CDS_PN = "2";
BODY = "CAP_A","I171": #LOCATION = "C3D14" !CDS_LOCATION = "C3D14" &SEC = "1" #&CDS_SEC = "1";
"A":   PN = "1"  !CDS_PN = "1";
"B":   PN = "2"  !CDS_PN = "2";
BODY = "CAP_A","I172": #LOCATION = "C3D23" !CDS_LOCATION = "C3D23" &SEC = "1" #&CDS_SEC = "1";
"A":   PN = "1"  !CDS_PN = "1";
"B":   PN = "2"  !CDS_PN = "2";
BODY = "CAP_A","I174": #LOCATION = "C3D15" !CDS_LOCATION = "C3D15" &SEC = "1" #&CDS_SEC = "1";
"A":   PN = "1"  !CDS_PN = "1";
"B":   PN = "2"  !CDS_PN = "2";
BODY = "CAP_A","I175": #LOCATION = "C3D24" !CDS_LOCATION = "C3D24" &SEC = "1" #&CDS_SEC = "1";
"A":   PN = "1"  !CDS_PN = "1";
"B":   PN = "2"  !CDS_PN = "2";
BODY = "CAP_A","I176": #LOCATION = "C3D16" !CDS_LOCATION = "C3D16" &SEC = "1" #&CDS_SEC = "1";
"A":   PN = "1"  !CDS_PN = "1";
"B":   PN = "2"  !CDS_PN = "2";
BODY = "CAP_A","I179": #LOCATION = "C7P12" !CDS_LOCATION = "C7P12" &SEC = "1" #&CDS_SEC = "1";
"A":   PN = "1"  !CDS_PN = "1";
"B":   PN = "2"  !CDS_PN = "2";
BODY = "CAP_A","I196": #LOCATION = "C3D10" !CDS_LOCATION = "C3D10" &SEC = "1" #&CDS_SEC = "1";
"A":   PN = "1"  !CDS_PN = "1";
"B":   PN = "2"  !CDS_PN = "2";
BODY = "CAP_A","I197": #LOCATION = "C2D18" !CDS_LOCATION = "C2D18" &SEC = "1" #&CDS_SEC = "1";
"A":   PN = "1"  !CDS_PN = "1";
"B":   PN = "2"  !CDS_PN = "2";
BODY = "CAP_A","I198": #LOCATION = "C2D28" !CDS_LOCATION = "C2D28" &SEC = "1" #&CDS_SEC = "1";
"A":   PN = "1"  !CDS_PN = "1";
"B":   PN = "2"  !CDS_PN = "2";
BODY = "CAP_A","I199": #LOCATION = "C2D29" !CDS_LOCATION = "C2D29" &SEC = "1" #&CDS_SEC = "1";
"A":   PN = "1"  !CDS_PN = "1";
"B":   PN = "2"  !CDS_PN = "2";
BODY = "CAP_A","I206": #LOCATION = "C7P16" !CDS_LOCATION = "C7P16" &SEC = "1" #&CDS_SEC = "1";
"A":   PN = "1"  !CDS_PN = "1";
"B":   PN = "2"  !CDS_PN = "2";
BODY = "CAP_A","I207": #LOCATION = "C3D20" !CDS_LOCATION = "C3D20" &SEC = "1" #&CDS_SEC = "1";
"A":   PN = "1"  !CDS_PN = "1";
"B":   PN = "2"  !CDS_PN = "2";
BODY = "CAP_A","I208": #LOCATION = "C3D19" !CDS_LOCATION = "C3D19" &SEC = "1" #&CDS_SEC = "1";
"A":   PN = "1"  !CDS_PN = "1";
"B":   PN = "2"  !CDS_PN = "2";
BODY = "CAP","I215": #LOCATION = "C7P19" !CDS_LOCATION = "C7P19" #SEC = "1" !CDS_SEC = "1";
"A":   PN = "1"  !CDS_PN = "1";
"B":   PN = "2"  !CDS_PN = "2";
BODY = "CAP","I217": #LOCATION = "C8P24" !CDS_LOCATION = "C8P24" #SEC = "1" !CDS_SEC = "1";
"A":   PN = "1"  !CDS_PN = "1";
"B":   PN = "2"  !CDS_PN = "2";
BODY = "CAP","I245": #LOCATION = "C8W4" !CDS_LOCATION = "C8W4" #SEC = "1" !CDS_SEC = "1";
"A":   PN = "1"  !CDS_PN = "1";
"B":   PN = "2"  !CDS_PN = "2";
BODY = "CAP","I246": #LOCATION = "C8P5" !CDS_LOCATION = "C8P5" &SEC = "1" #&CDS_SEC = "1";
"A":   PN = "1"  !CDS_PN = "1";
"B":   PN = "2"  !CDS_PN = "2";
BODY = "CAP","I247": #LOCATION = "C8P6" !CDS_LOCATION = "C8P6" &SEC = "1" #&CDS_SEC = "1";
"A":   PN = "1"  !CDS_PN = "1";
"B":   PN = "2"  !CDS_PN = "2";
BODY = "CAP","I248": #LOCATION = "C8P7" !CDS_LOCATION = "C8P7" &SEC = "1" #&CDS_SEC = "1";
"A":   PN = "1"  !CDS_PN = "1";
"B":   PN = "2"  !CDS_PN = "2";
BODY = "CAP","I249": #LOCATION = "C8P21" !CDS_LOCATION = "C8P21" #SEC = "1" !CDS_SEC = "1";
"A":   PN = "1"  !CDS_PN = "1";
"B":   PN = "2"  !CDS_PN = "2";
BODY = "CAP","I250": #LOCATION = "C8P27" !CDS_LOCATION = "C8P27" #SEC = "1" !CDS_SEC = "1";
"A":   PN = "1"  !CDS_PN = "1";
"B":   PN = "2"  !CDS_PN = "2";
BODY = "CAP","I251": #LOCATION = "C8P25" !CDS_LOCATION = "C8P25" #SEC = "1" !CDS_SEC = "1";
"A":   PN = "1"  !CDS_PN = "1";
"B":   PN = "2"  !CDS_PN = "2";
BODY = "CAP","I252": #LOCATION = "C8P17" !CDS_LOCATION = "C8P17" #SEC = "1" !CDS_SEC = "1";
"A":   PN = "1"  !CDS_PN = "1";
"B":   PN = "2"  !CDS_PN = "2";
BODY = "CAP_A","I254": #LOCATION = "C3W4" !CDS_LOCATION = "C3W4" #SEC = "1" !CDS_SEC = "1";
"A":   PN = "1"  !CDS_PN = "1";
"B":   PN = "2"  !CDS_PN = "2";
BODY = "CAP_A","I256": #LOCATION = "C3W3" !CDS_LOCATION = "C3W3" #SEC = "1" !CDS_SEC = "1";
"A":   PN = "1"  !CDS_PN = "1";
"B":   PN = "2"  !CDS_PN = "2";
BODY = "CAP","I258": #LOCATION = "C7P9" !CDS_LOCATION = "C7P9" #SEC = "1" !CDS_SEC = "1";
"A":   PN = "1"  !CDS_PN = "1";
"B":   PN = "2"  !CDS_PN = "2";
BODY = "CAP","I259": #LOCATION = "C7P5" !CDS_LOCATION = "C7P5" #SEC = "1" !CDS_SEC = "1";
"A":   PN = "1"  !CDS_PN = "1";
"B":   PN = "2"  !CDS_PN = "2";
BODY = "CAP","I260": #LOCATION = "C8P23" !CDS_LOCATION = "C8P23" #SEC = "1" !CDS_SEC = "1";
"A":   PN = "1"  !CDS_PN = "1";
"B":   PN = "2"  !CDS_PN = "2";
BODY = "CAP","I261": #LOCATION = "C7P14" !CDS_LOCATION = "C7P14" #SEC = "1" !CDS_SEC = "1";
"A":   PN = "1"  !CDS_PN = "1";
"B":   PN = "2"  !CDS_PN = "2";
BODY = "CAP","I262": #LOCATION = "C7P11" !CDS_LOCATION = "C7P11" #SEC = "1" !CDS_SEC = "1";
"A":   PN = "1"  !CDS_PN = "1";
"B":   PN = "2"  !CDS_PN = "2";
BODY = "CAP","I263": #LOCATION = "C7P15" !CDS_LOCATION = "C7P15" #SEC = "1" !CDS_SEC = "1";
"A":   PN = "1"  !CDS_PN = "1";
"B":   PN = "2"  !CDS_PN = "2";
BODY = "CAP","I264": #LOCATION = "C8P22" !CDS_LOCATION = "C8P22" #SEC = "1" !CDS_SEC = "1";
"A":   PN = "1"  !CDS_PN = "1";
"B":   PN = "2"  !CDS_PN = "2";
BODY = "CAP","I265": #LOCATION = "C7P8" !CDS_LOCATION = "C7P8" #SEC = "1" !CDS_SEC = "1";
"A":   PN = "1"  !CDS_PN = "1";
"B":   PN = "2"  !CDS_PN = "2";
BODY = "CAP","I266": #LOCATION = "C7P10" !CDS_LOCATION = "C7P10" #SEC = "1" !CDS_SEC = "1";
"A":   PN = "1"  !CDS_PN = "1";
"B":   PN = "2"  !CDS_PN = "2";
BODY = "CAP","I267": #LOCATION = "C7P7" !CDS_LOCATION = "C7P7" #SEC = "1" !CDS_SEC = "1";
"A":   PN = "1"  !CDS_PN = "1";
"B":   PN = "2"  !CDS_PN = "2";
BODY = "CAP","I268": #LOCATION = "C7P6" !CDS_LOCATION = "C7P6" #SEC = "1" !CDS_SEC = "1";
"A":   PN = "1"  !CDS_PN = "1";
"B":   PN = "2"  !CDS_PN = "2";
BODY = "CAP","I269": #LOCATION = "C7P13" !CDS_LOCATION = "C7P13" #SEC = "1" !CDS_SEC = "1";
"A":   PN = "1"  !CDS_PN = "1";
"B":   PN = "2"  !CDS_PN = "2";
BODY = "CAP","I270": #LOCATION = "C8P15" !CDS_LOCATION = "C8P15" #SEC = "1" !CDS_SEC = "1";
"A":   PN = "1"  !CDS_PN = "1";
"B":   PN = "2"  !CDS_PN = "2";
BODY = "CAP","I271": #LOCATION = "C7P4" !CDS_LOCATION = "C7P4" #SEC = "1" !CDS_SEC = "1";
"A":   PN = "1"  !CDS_PN = "1";
"B":   PN = "2"  !CDS_PN = "2";
BODY = "CAP","I272": #LOCATION = "C8P14" !CDS_LOCATION = "C8P14" #SEC = "1" !CDS_SEC = "1";
"A":   PN = "1"  !CDS_PN = "1";
"B":   PN = "2"  !CDS_PN = "2";
BODY = "CAP","I273": #LOCATION = "C8P9" !CDS_LOCATION = "C8P9" #SEC = "1" !CDS_SEC = "1";
"A":   PN = "1"  !CDS_PN = "1";
"B":   PN = "2"  !CDS_PN = "2";
BODY = "CAP","I274": #LOCATION = "C8P8" !CDS_LOCATION = "C8P8" #SEC = "1" !CDS_SEC = "1";
"A":   PN = "1"  !CDS_PN = "1";
"B":   PN = "2"  !CDS_PN = "2";
DRAWING = "@baseboard_fab2_lib.baseboard_fab2(sch_1):page77";
BODY = "SCONN288_H44441004","I43": #LOCATION = "J1G1" !CDS_LOCATION = "J1G1" #SEC = "3" !CDS_SEC = "3";
"VSS<0>":   PN = "283"  !CDS_PN = "283";
"VSS<1>":   PN = "281"  !CDS_PN = "281";
"VSS<2>":   PN = "279"  !CDS_PN = "279";
"VSS<3>":   PN = "276"  !CDS_PN = "276";
"VSS<4>":   PN = "274"  !CDS_PN = "274";
"VSS<5>":   PN = "272"  !CDS_PN = "272";
"VSS<6>":   PN = "270"  !CDS_PN = "270";
"VSS<7>":   PN = "268"  !CDS_PN = "268";
"VSS<8>":   PN = "265"  !CDS_PN = "265";
"VSS<9>":   PN = "263"  !CDS_PN = "263";
"VSS<10>":   PN = "261"  !CDS_PN = "261";
"VSS<11>":   PN = "259"  !CDS_PN = "259";
"VSS<12>":   PN = "257"  !CDS_PN = "257";
"VSS<13>":   PN = "254"  !CDS_PN = "254";
"VSS<14>":   PN = "252"  !CDS_PN = "252";
"VSS<15>":   PN = "250"  !CDS_PN = "250";
"VSS<16>":   PN = "248"  !CDS_PN = "248";
"VSS<17>":   PN = "246"  !CDS_PN = "246";
"VSS<18>":   PN = "243"  !CDS_PN = "243";
"VSS<19>":   PN = "241"  !CDS_PN = "241";
"VSS<20>":   PN = "239"  !CDS_PN = "239";
"VSS<21>":   PN = "202"  !CDS_PN = "202";
"VSS<22>":   PN = "200"  !CDS_PN = "200";
"VSS<23>":   PN = "198"  !CDS_PN = "198";
"VSS<24>":   PN = "195"  !CDS_PN = "195";
"VSS<25>":   PN = "193"  !CDS_PN = "193";
"VSS<26>":   PN = "191"  !CDS_PN = "191";
"VSS<27>":   PN = "189"  !CDS_PN = "189";
"VSS<28>":   PN = "187"  !CDS_PN = "187";
"VSS<29>":   PN = "184"  !CDS_PN = "184";
"VSS<30>":   PN = "182"  !CDS_PN = "182";
"VSS<31>":   PN = "180"  !CDS_PN = "180";
"VSS<32>":   PN = "178"  !CDS_PN = "178";
"VSS<33>":   PN = "176"  !CDS_PN = "176";
"VSS<34>":   PN = "173"  !CDS_PN = "173";
"VSS<35>":   PN = "171"  !CDS_PN = "171";
"VSS<36>":   PN = "169"  !CDS_PN = "169";
"VSS<37>":   PN = "167"  !CDS_PN = "167";
"VSS<38>":   PN = "165"  !CDS_PN = "165";
"VSS<39>":   PN = "162"  !CDS_PN = "162";
"VSS<40>":   PN = "160"  !CDS_PN = "160";
"VSS<41>":   PN = "158"  !CDS_PN = "158";
"VSS<42>":   PN = "156"  !CDS_PN = "156";
"VSS<43>":   PN = "154"  !CDS_PN = "154";
"VSS<44>":   PN = "151"  !CDS_PN = "151";
"VSS<45>":   PN = "149"  !CDS_PN = "149";
"VSS<46>":   PN = "147"  !CDS_PN = "147";
"VSS<47>":   PN = "138"  !CDS_PN = "138";
"VSS<48>":   PN = "136"  !CDS_PN = "136";
"VSS<49>":   PN = "134"  !CDS_PN = "134";
"VSS<50>":   PN = "131"  !CDS_PN = "131";
"VSS<51>":   PN = "129"  !CDS_PN = "129";
"VSS<52>":   PN = "127"  !CDS_PN = "127";
"VSS<53>":   PN = "125"  !CDS_PN = "125";
"VSS<54>":   PN = "123"  !CDS_PN = "123";
"VSS<55>":   PN = "120"  !CDS_PN = "120";
"VSS<56>":   PN = "118"  !CDS_PN = "118";
"VSS<57>":   PN = "116"  !CDS_PN = "116";
"VSS<58>":   PN = "114"  !CDS_PN = "114";
"VSS<59>":   PN = "112"  !CDS_PN = "112";
"VSS<60>":   PN = "109"  !CDS_PN = "109";
"VSS<61>":   PN = "107"  !CDS_PN = "107";
"VSS<62>":   PN = "105"  !CDS_PN = "105";
"VSS<63>":   PN = "103"  !CDS_PN = "103";
"VSS<64>":   PN = "101"  !CDS_PN = "101";
"VSS<65>":   PN = "98"  !CDS_PN = "98";
"VSS<66>":   PN = "96"  !CDS_PN = "96";
"VSS<67>":   PN = "94"  !CDS_PN = "94";
"VSS<68>":   PN = "57"  !CDS_PN = "57";
"VSS<69>":   PN = "55"  !CDS_PN = "55";
"VSS<70>":   PN = "53"  !CDS_PN = "53";
"VSS<71>":   PN = "50"  !CDS_PN = "50";
"VSS<72>":   PN = "48"  !CDS_PN = "48";
"VSS<73>":   PN = "46"  !CDS_PN = "46";
"VSS<74>":   PN = "44"  !CDS_PN = "44";
"VSS<75>":   PN = "42"  !CDS_PN = "42";
"VSS<76>":   PN = "39"  !CDS_PN = "39";
"VSS<77>":   PN = "37"  !CDS_PN = "37";
"VSS<78>":   PN = "35"  !CDS_PN = "35";
"VSS<79>":   PN = "33"  !CDS_PN = "33";
"VSS<80>":   PN = "31"  !CDS_PN = "31";
"VSS<81>":   PN = "28"  !CDS_PN = "28";
"VSS<82>":   PN = "26"  !CDS_PN = "26";
"VSS<83>":   PN = "24"  !CDS_PN = "24";
"VSS<84>":   PN = "22"  !CDS_PN = "22";
"VSS<85>":   PN = "20"  !CDS_PN = "20";
"VSS<86>":   PN = "17"  !CDS_PN = "17";
"VSS<87>":   PN = "15"  !CDS_PN = "15";
"VSS<88>":   PN = "13"  !CDS_PN = "13";
"VSS<89>":   PN = "11"  !CDS_PN = "11";
"VSS<90>":   PN = "9"  !CDS_PN = "9";
"VSS<91>":   PN = "6"  !CDS_PN = "6";
"VSS<92>":   PN = "4"  !CDS_PN = "4";
"VSS<93>":   PN = "2"  !CDS_PN = "2";
BODY = "SCONN288_H44441004","I66": #LOCATION = "J1G1" !CDS_LOCATION = "J1G1" #SEC = "2" !CDS_SEC = "2";
"DQS0N":   PN = "152"  !CDS_PN = "152";
"DQS0P":   PN = "153"  !CDS_PN = "153";
"DQS1N":   PN = "163"  !CDS_PN = "163";
"DQS1P":   PN = "164"  !CDS_PN = "164";
"DQS2N":   PN = "174"  !CDS_PN = "174";
"DQS2P":   PN = "175"  !CDS_PN = "175";
"DQS3N":   PN = "185"  !CDS_PN = "185";
"DQS3P":   PN = "186"  !CDS_PN = "186";
"DQS4N":   PN = "244"  !CDS_PN = "244";
"DQS4P":   PN = "245"  !CDS_PN = "245";
"DQS5N":   PN = "255"  !CDS_PN = "255";
"DQS5P":   PN = "256"  !CDS_PN = "256";
"DQS6N":   PN = "266"  !CDS_PN = "266";
"DQS6P":   PN = "267"  !CDS_PN = "267";
"DQS7N":   PN = "277"  !CDS_PN = "277";
"DQS7P":   PN = "278"  !CDS_PN = "278";
"DQS8N":   PN = "196"  !CDS_PN = "196";
"DQS8P":   PN = "197"  !CDS_PN = "197";
"DQS9N":   PN = "8"  !CDS_PN = "8";
"DQS9P":   PN = "7"  !CDS_PN = "7";
"DQS10N":   PN = "19"  !CDS_PN = "19";
"DQS10P":   PN = "18"  !CDS_PN = "18";
"DQS11N":   PN = "30"  !CDS_PN = "30";
"DQS11P":   PN = "29"  !CDS_PN = "29";
"DQS12N":   PN = "41"  !CDS_PN = "41";
"DQS12P":   PN = "40"  !CDS_PN = "40";
"DQS13N":   PN = "100"  !CDS_PN = "100";
"DQS13P":   PN = "99"  !CDS_PN = "99";
"DQS14N":   PN = "111"  !CDS_PN = "111";
"DQS14P":   PN = "110"  !CDS_PN = "110";
"DQS15N":   PN = "122"  !CDS_PN = "122";
"DQS15P":   PN = "121"  !CDS_PN = "121";
"DQS16N":   PN = "133"  !CDS_PN = "133";
"DQS16P":   PN = "132"  !CDS_PN = "132";
"DQS17N":   PN = "52"  !CDS_PN = "52";
"DQS17P":   PN = "51"  !CDS_PN = "51";
BODY = "SCONN288_H44441004","I111": #LOCATION = "J1G1" !CDS_LOCATION = "J1G1" #SEC = "1" !CDS_SEC = "1";
"A0":   PN = "79"  !CDS_PN = "79";
"A1":   PN = "72"  !CDS_PN = "72";
"A2":   PN = "216"  !CDS_PN = "216";
"A3":   PN = "71"  !CDS_PN = "71";
"A4":   PN = "214"  !CDS_PN = "214";
"A5":   PN = "213"  !CDS_PN = "213";
"A6":   PN = "69"  !CDS_PN = "69";
"A7":   PN = "211"  !CDS_PN = "211";
"A8":   PN = "68"  !CDS_PN = "68";
"A9":   PN = "66"  !CDS_PN = "66";
"A10":   PN = "225"  !CDS_PN = "225";
"A11":   PN = "210"  !CDS_PN = "210";
"A12":   PN = "65"  !CDS_PN = "65";
"A13":   PN = "232"  !CDS_PN = "232";
"A14_WE_N":   PN = "228"  !CDS_PN = "228";
"A15_CAS_N":   PN = "86"  !CDS_PN = "86";
"A16_RAS_N":   PN = "82"  !CDS_PN = "82";
"A17":   PN = "234"  !CDS_PN = "234";
"ACT_N":   PN = "62"  !CDS_PN = "62";
"ALERT_N":   PN = "208"  !CDS_PN = "208";
"BA<0>":   PN = "81"  !CDS_PN = "81";
"BA<1>":   PN = "224"  !CDS_PN = "224";
"BG<0>":   PN = "63"  !CDS_PN = "63";
"BG<1>":   PN = "207"  !CDS_PN = "207";
"C<2>":   PN = "235"  !CDS_PN = "235";
"CB<0>":   PN = "49"  !CDS_PN = "49";
"CB<1>":   PN = "194"  !CDS_PN = "194";
"CB<2>":   PN = "56"  !CDS_PN = "56";
"CB<3>":   PN = "201"  !CDS_PN = "201";
"CB<4>":   PN = "47"  !CDS_PN = "47";
"CB<5>":   PN = "192"  !CDS_PN = "192";
"CB<6>":   PN = "54"  !CDS_PN = "54";
"CB<7>":   PN = "199"  !CDS_PN = "199";
"CK0N":   PN = "75"  !CDS_PN = "75";
"CK0P":   PN = "74"  !CDS_PN = "74";
"CK1N":   PN = "219"  !CDS_PN = "219";
"CK1P":   PN = "218"  !CDS_PN = "218";
"CKE<0>":   PN = "60"  !CDS_PN = "60";
"CKE<1>":   PN = "203"  !CDS_PN = "203";
"DQ<0>":   PN = "5"  !CDS_PN = "5";
"DQ<1>":   PN = "150"  !CDS_PN = "150";
"DQ<2>":   PN = "12"  !CDS_PN = "12";
"DQ<3>":   PN = "157"  !CDS_PN = "157";
"DQ<4>":   PN = "3"  !CDS_PN = "3";
"DQ<5>":   PN = "148"  !CDS_PN = "148";
"DQ<6>":   PN = "10"  !CDS_PN = "10";
"DQ<7>":   PN = "155"  !CDS_PN = "155";
"DQ<8>":   PN = "16"  !CDS_PN = "16";
"DQ<9>":   PN = "161"  !CDS_PN = "161";
"DQ<10>":   PN = "23"  !CDS_PN = "23";
"DQ<11>":   PN = "168"  !CDS_PN = "168";
"DQ<12>":   PN = "14"  !CDS_PN = "14";
"DQ<13>":   PN = "159"  !CDS_PN = "159";
"DQ<14>":   PN = "21"  !CDS_PN = "21";
"DQ<15>":   PN = "166"  !CDS_PN = "166";
"DQ<16>":   PN = "27"  !CDS_PN = "27";
"DQ<17>":   PN = "172"  !CDS_PN = "172";
"DQ<18>":   PN = "34"  !CDS_PN = "34";
"DQ<19>":   PN = "179"  !CDS_PN = "179";
"DQ<20>":   PN = "25"  !CDS_PN = "25";
"DQ<21>":   PN = "170"  !CDS_PN = "170";
"DQ<22>":   PN = "32"  !CDS_PN = "32";
"DQ<23>":   PN = "177"  !CDS_PN = "177";
"DQ<24>":   PN = "38"  !CDS_PN = "38";
"DQ<25>":   PN = "183"  !CDS_PN = "183";
"DQ<26>":   PN = "45"  !CDS_PN = "45";
"DQ<27>":   PN = "190"  !CDS_PN = "190";
"DQ<28>":   PN = "36"  !CDS_PN = "36";
"DQ<29>":   PN = "181"  !CDS_PN = "181";
"DQ<30>":   PN = "43"  !CDS_PN = "43";
"DQ<31>":   PN = "188"  !CDS_PN = "188";
"DQ<32>":   PN = "97"  !CDS_PN = "97";
"DQ<33>":   PN = "242"  !CDS_PN = "242";
"DQ<34>":   PN = "104"  !CDS_PN = "104";
"DQ<35>":   PN = "249"  !CDS_PN = "249";
"DQ<36>":   PN = "95"  !CDS_PN = "95";
"DQ<37>":   PN = "240"  !CDS_PN = "240";
"DQ<38>":   PN = "102"  !CDS_PN = "102";
"DQ<39>":   PN = "247"  !CDS_PN = "247";
"DQ<40>":   PN = "108"  !CDS_PN = "108";
"DQ<41>":   PN = "253"  !CDS_PN = "253";
"DQ<42>":   PN = "115"  !CDS_PN = "115";
"DQ<43>":   PN = "260"  !CDS_PN = "260";
"DQ<44>":   PN = "106"  !CDS_PN = "106";
"DQ<45>":   PN = "251"  !CDS_PN = "251";
"DQ<46>":   PN = "113"  !CDS_PN = "113";
"DQ<47>":   PN = "258"  !CDS_PN = "258";
"DQ<48>":   PN = "119"  !CDS_PN = "119";
"DQ<49>":   PN = "264"  !CDS_PN = "264";
"DQ<50>":   PN = "126"  !CDS_PN = "126";
"DQ<51>":   PN = "271"  !CDS_PN = "271";
"DQ<52>":   PN = "117"  !CDS_PN = "117";
"DQ<53>":   PN = "262"  !CDS_PN = "262";
"DQ<54>":   PN = "124"  !CDS_PN = "124";
"DQ<55>":   PN = "269"  !CDS_PN = "269";
"DQ<56>":   PN = "130"  !CDS_PN = "130";
"DQ<57>":   PN = "275"  !CDS_PN = "275";
"DQ<58>":   PN = "137"  !CDS_PN = "137";
"DQ<59>":   PN = "282"  !CDS_PN = "282";
"DQ<60>":   PN = "128"  !CDS_PN = "128";
"DQ<61>":   PN = "273"  !CDS_PN = "273";
"DQ<62>":   PN = "135"  !CDS_PN = "135";
"DQ<63>":   PN = "280"  !CDS_PN = "280";
"EVENT_N":   PN = "78"  !CDS_PN = "78";
"ODT<0>":   PN = "87"  !CDS_PN = "87";
"ODT<1>":   PN = "91"  !CDS_PN = "91";
"PAR":   PN = "222"  !CDS_PN = "222";
"RESET_N":   PN = "58"  !CDS_PN = "58";
"RFU<0>":   PN = "205"  !CDS_PN = "205";
"RFU<1>":   PN = "227"  !CDS_PN = "227";
"RFU<2>":   PN = "144"  !CDS_PN = "144";
"S0_N":   PN = "84"  !CDS_PN = "84";
"S1_N":   PN = "89"  !CDS_PN = "89";
"S2_N_C<0>":   PN = "93"  !CDS_PN = "93";
"S3_N_C<1>":   PN = "237"  !CDS_PN = "237";
"SA<0>":   PN = "139"  !CDS_PN = "139";
"SA<1>":   PN = "140"  !CDS_PN = "140";
"SA<2>":   PN = "238"  !CDS_PN = "238";
"SAVE_N_NC":   PN = "230"  !CDS_PN = "230";
"SCL":   PN = "141"  !CDS_PN = "141";
"SDA":   PN = "285"  !CDS_PN = "285";
"VDDSPD":   PN = "284"  !CDS_PN = "284";
"VREFCA":   PN = "146"  !CDS_PN = "146";
BODY = "SCONN288_H44441004","I171": #LOCATION = "J1G1" !CDS_LOCATION = "J1G1" #SEC = "4" !CDS_SEC = "4";
"12V<0>":   PN = "145"  !CDS_PN = "145";
"12V<1>":   PN = "1"  !CDS_PN = "1";
"VDD<0>":   PN = "236"  !CDS_PN = "236";
"VDD<1>":   PN = "233"  !CDS_PN = "233";
"VDD<2>":   PN = "231"  !CDS_PN = "231";
"VDD<3>":   PN = "229"  !CDS_PN = "229";
"VDD<4>":   PN = "226"  !CDS_PN = "226";
"VDD<5>":   PN = "223"  !CDS_PN = "223";
"VDD<6>":   PN = "220"  !CDS_PN = "220";
"VDD<7>":   PN = "217"  !CDS_PN = "217";
"VDD<8>":   PN = "215"  !CDS_PN = "215";
"VDD<9>":   PN = "212"  !CDS_PN = "212";
"VDD<10>":   PN = "209"  !CDS_PN = "209";
"VDD<11>":   PN = "206"  !CDS_PN = "206";
"VDD<12>":   PN = "204"  !CDS_PN = "204";
"VDD<13>":   PN = "92"  !CDS_PN = "92";
"VDD<14>":   PN = "90"  !CDS_PN = "90";
"VDD<15>":   PN = "88"  !CDS_PN = "88";
"VDD<16>":   PN = "85"  !CDS_PN = "85";
"VDD<17>":   PN = "83"  !CDS_PN = "83";
"VDD<18>":   PN = "80"  !CDS_PN = "80";
"VDD<19>":   PN = "76"  !CDS_PN = "76";
"VDD<20>":   PN = "73"  !CDS_PN = "73";
"VDD<21>":   PN = "70"  !CDS_PN = "70";
"VDD<22>":   PN = "67"  !CDS_PN = "67";
"VDD<23>":   PN = "64"  !CDS_PN = "64";
"VDD<24>":   PN = "61"  !CDS_PN = "61";
"VDD<25>":   PN = "59"  !CDS_PN = "59";
"VPP<0>":   PN = "287"  !CDS_PN = "287";
"VPP<1>":   PN = "286"  !CDS_PN = "286";
"VPP<2>":   PN = "288"  !CDS_PN = "288";
"VPP<3>":   PN = "143"  !CDS_PN = "143";
"VPP<4>":   PN = "142"  !CDS_PN = "142";
"VTT<0>":   PN = "221"  !CDS_PN = "221";
"VTT<1>":   PN = "77"  !CDS_PN = "77";
BODY = "CAP_A","I181": #LOCATION = "C1F22" !CDS_LOCATION = "C1F22" &SEC = "1" #&CDS_SEC = "1";
"A":   PN = "1"  !CDS_PN = "1";
"B":   PN = "2"  !CDS_PN = "2";
DRAWING = "@baseboard_fab2_lib.baseboard_fab2(sch_1):page78";
BODY = "CAP_A","I2": #LOCATION = "C9T7" !CDS_LOCATION = "C9T7" &SEC = "1" #&CDS_SEC = "1";
"A":   PN = "1"  !CDS_PN = "1";
"B":   PN = "2"  !CDS_PN = "2";
BODY = "SCONN288_H44441003","I13": #LOCATION = "J9T1" !CDS_LOCATION = "J9T1" #SEC = "1" !CDS_SEC = "1";
"A0":   PN = "79"  !CDS_PN = "79";
"A1":   PN = "72"  !CDS_PN = "72";
"A2":   PN = "216"  !CDS_PN = "216";
"A3":   PN = "71"  !CDS_PN = "71";
"A4":   PN = "214"  !CDS_PN = "214";
"A5":   PN = "213"  !CDS_PN = "213";
"A6":   PN = "69"  !CDS_PN = "69";
"A7":   PN = "211"  !CDS_PN = "211";
"A8":   PN = "68"  !CDS_PN = "68";
"A9":   PN = "66"  !CDS_PN = "66";
"A10":   PN = "225"  !CDS_PN = "225";
"A11":   PN = "210"  !CDS_PN = "210";
"A12":   PN = "65"  !CDS_PN = "65";
"A13":   PN = "232"  !CDS_PN = "232";
"A14_WE_N":   PN = "228"  !CDS_PN = "228";
"A15_CAS_N":   PN = "86"  !CDS_PN = "86";
"A16_RAS_N":   PN = "82"  !CDS_PN = "82";
"A17":   PN = "234"  !CDS_PN = "234";
"ACT_N":   PN = "62"  !CDS_PN = "62";
"ALERT_N":   PN = "208"  !CDS_PN = "208";
"BA<0>":   PN = "81"  !CDS_PN = "81";
"BA<1>":   PN = "224"  !CDS_PN = "224";
"BG<0>":   PN = "63"  !CDS_PN = "63";
"BG<1>":   PN = "207"  !CDS_PN = "207";
"C<2>":   PN = "235"  !CDS_PN = "235";
"CB<0>":   PN = "49"  !CDS_PN = "49";
"CB<1>":   PN = "194"  !CDS_PN = "194";
"CB<2>":   PN = "56"  !CDS_PN = "56";
"CB<3>":   PN = "201"  !CDS_PN = "201";
"CB<4>":   PN = "47"  !CDS_PN = "47";
"CB<5>":   PN = "192"  !CDS_PN = "192";
"CB<6>":   PN = "54"  !CDS_PN = "54";
"CB<7>":   PN = "199"  !CDS_PN = "199";
"CK0N":   PN = "75"  !CDS_PN = "75";
"CK0P":   PN = "74"  !CDS_PN = "74";
"CK1N":   PN = "219"  !CDS_PN = "219";
"CK1P":   PN = "218"  !CDS_PN = "218";
"CKE<0>":   PN = "60"  !CDS_PN = "60";
"CKE<1>":   PN = "203"  !CDS_PN = "203";
"DQ<0>":   PN = "5"  !CDS_PN = "5";
"DQ<1>":   PN = "150"  !CDS_PN = "150";
"DQ<2>":   PN = "12"  !CDS_PN = "12";
"DQ<3>":   PN = "157"  !CDS_PN = "157";
"DQ<4>":   PN = "3"  !CDS_PN = "3";
"DQ<5>":   PN = "148"  !CDS_PN = "148";
"DQ<6>":   PN = "10"  !CDS_PN = "10";
"DQ<7>":   PN = "155"  !CDS_PN = "155";
"DQ<8>":   PN = "16"  !CDS_PN = "16";
"DQ<9>":   PN = "161"  !CDS_PN = "161";
"DQ<10>":   PN = "23"  !CDS_PN = "23";
"DQ<11>":   PN = "168"  !CDS_PN = "168";
"DQ<12>":   PN = "14"  !CDS_PN = "14";
"DQ<13>":   PN = "159"  !CDS_PN = "159";
"DQ<14>":   PN = "21"  !CDS_PN = "21";
"DQ<15>":   PN = "166"  !CDS_PN = "166";
"DQ<16>":   PN = "27"  !CDS_PN = "27";
"DQ<17>":   PN = "172"  !CDS_PN = "172";
"DQ<18>":   PN = "34"  !CDS_PN = "34";
"DQ<19>":   PN = "179"  !CDS_PN = "179";
"DQ<20>":   PN = "25"  !CDS_PN = "25";
"DQ<21>":   PN = "170"  !CDS_PN = "170";
"DQ<22>":   PN = "32"  !CDS_PN = "32";
"DQ<23>":   PN = "177"  !CDS_PN = "177";
"DQ<24>":   PN = "38"  !CDS_PN = "38";
"DQ<25>":   PN = "183"  !CDS_PN = "183";
"DQ<26>":   PN = "45"  !CDS_PN = "45";
"DQ<27>":   PN = "190"  !CDS_PN = "190";
"DQ<28>":   PN = "36"  !CDS_PN = "36";
"DQ<29>":   PN = "181"  !CDS_PN = "181";
"DQ<30>":   PN = "43"  !CDS_PN = "43";
"DQ<31>":   PN = "188"  !CDS_PN = "188";
"DQ<32>":   PN = "97"  !CDS_PN = "97";
"DQ<33>":   PN = "242"  !CDS_PN = "242";
"DQ<34>":   PN = "104"  !CDS_PN = "104";
"DQ<35>":   PN = "249"  !CDS_PN = "249";
"DQ<36>":   PN = "95"  !CDS_PN = "95";
"DQ<37>":   PN = "240"  !CDS_PN = "240";
"DQ<38>":   PN = "102"  !CDS_PN = "102";
"DQ<39>":   PN = "247"  !CDS_PN = "247";
"DQ<40>":   PN = "108"  !CDS_PN = "108";
"DQ<41>":   PN = "253"  !CDS_PN = "253";
"DQ<42>":   PN = "115"  !CDS_PN = "115";
"DQ<43>":   PN = "260"  !CDS_PN = "260";
"DQ<44>":   PN = "106"  !CDS_PN = "106";
"DQ<45>":   PN = "251"  !CDS_PN = "251";
"DQ<46>":   PN = "113"  !CDS_PN = "113";
"DQ<47>":   PN = "258"  !CDS_PN = "258";
"DQ<48>":   PN = "119"  !CDS_PN = "119";
"DQ<49>":   PN = "264"  !CDS_PN = "264";
"DQ<50>":   PN = "126"  !CDS_PN = "126";
"DQ<51>":   PN = "271"  !CDS_PN = "271";
"DQ<52>":   PN = "117"  !CDS_PN = "117";
"DQ<53>":   PN = "262"  !CDS_PN = "262";
"DQ<54>":   PN = "124"  !CDS_PN = "124";
"DQ<55>":   PN = "269"  !CDS_PN = "269";
"DQ<56>":   PN = "130"  !CDS_PN = "130";
"DQ<57>":   PN = "275"  !CDS_PN = "275";
"DQ<58>":   PN = "137"  !CDS_PN = "137";
"DQ<59>":   PN = "282"  !CDS_PN = "282";
"DQ<60>":   PN = "128"  !CDS_PN = "128";
"DQ<61>":   PN = "273"  !CDS_PN = "273";
"DQ<62>":   PN = "135"  !CDS_PN = "135";
"DQ<63>":   PN = "280"  !CDS_PN = "280";
"EVENT_N":   PN = "78"  !CDS_PN = "78";
"ODT<0>":   PN = "87"  !CDS_PN = "87";
"ODT<1>":   PN = "91"  !CDS_PN = "91";
"PAR":   PN = "222"  !CDS_PN = "222";
"RESET_N":   PN = "58"  !CDS_PN = "58";
"RFU<0>":   PN = "205"  !CDS_PN = "205";
"RFU<1>":   PN = "227"  !CDS_PN = "227";
"RFU<2>":   PN = "144"  !CDS_PN = "144";
"S0_N":   PN = "84"  !CDS_PN = "84";
"S1_N":   PN = "89"  !CDS_PN = "89";
"S2_N_C<0>":   PN = "93"  !CDS_PN = "93";
"S3_N_C<1>":   PN = "237"  !CDS_PN = "237";
"SA<0>":   PN = "139"  !CDS_PN = "139";
"SA<1>":   PN = "140"  !CDS_PN = "140";
"SA<2>":   PN = "238"  !CDS_PN = "238";
"SAVE_N_NC":   PN = "230"  !CDS_PN = "230";
"SCL":   PN = "141"  !CDS_PN = "141";
"SDA":   PN = "285"  !CDS_PN = "285";
"VDDSPD":   PN = "284"  !CDS_PN = "284";
"VREFCA":   PN = "146"  !CDS_PN = "146";
BODY = "SCONN288_H44441003","I75": #LOCATION = "J9T1" !CDS_LOCATION = "J9T1" #SEC = "4" !CDS_SEC = "4";
"12V<0>":   PN = "145"  !CDS_PN = "145";
"12V<1>":   PN = "1"  !CDS_PN = "1";
"VDD<0>":   PN = "236"  !CDS_PN = "236";
"VDD<1>":   PN = "233"  !CDS_PN = "233";
"VDD<2>":   PN = "231"  !CDS_PN = "231";
"VDD<3>":   PN = "229"  !CDS_PN = "229";
"VDD<4>":   PN = "226"  !CDS_PN = "226";
"VDD<5>":   PN = "223"  !CDS_PN = "223";
"VDD<6>":   PN = "220"  !CDS_PN = "220";
"VDD<7>":   PN = "217"  !CDS_PN = "217";
"VDD<8>":   PN = "215"  !CDS_PN = "215";
"VDD<9>":   PN = "212"  !CDS_PN = "212";
"VDD<10>":   PN = "209"  !CDS_PN = "209";
"VDD<11>":   PN = "206"  !CDS_PN = "206";
"VDD<12>":   PN = "204"  !CDS_PN = "204";
"VDD<13>":   PN = "92"  !CDS_PN = "92";
"VDD<14>":   PN = "90"  !CDS_PN = "90";
"VDD<15>":   PN = "88"  !CDS_PN = "88";
"VDD<16>":   PN = "85"  !CDS_PN = "85";
"VDD<17>":   PN = "83"  !CDS_PN = "83";
"VDD<18>":   PN = "80"  !CDS_PN = "80";
"VDD<19>":   PN = "76"  !CDS_PN = "76";
"VDD<20>":   PN = "73"  !CDS_PN = "73";
"VDD<21>":   PN = "70"  !CDS_PN = "70";
"VDD<22>":   PN = "67"  !CDS_PN = "67";
"VDD<23>":   PN = "64"  !CDS_PN = "64";
"VDD<24>":   PN = "61"  !CDS_PN = "61";
"VDD<25>":   PN = "59"  !CDS_PN = "59";
"VPP<0>":   PN = "287"  !CDS_PN = "287";
"VPP<1>":   PN = "286"  !CDS_PN = "286";
"VPP<2>":   PN = "288"  !CDS_PN = "288";
"VPP<3>":   PN = "143"  !CDS_PN = "143";
"VPP<4>":   PN = "142"  !CDS_PN = "142";
"VTT<0>":   PN = "221"  !CDS_PN = "221";
"VTT<1>":   PN = "77"  !CDS_PN = "77";
BODY = "SCONN288_H44441003","I120": #LOCATION = "J9T1" !CDS_LOCATION = "J9T1" #SEC = "2" !CDS_SEC = "2";
"DQS0N":   PN = "152"  !CDS_PN = "152";
"DQS0P":   PN = "153"  !CDS_PN = "153";
"DQS1N":   PN = "163"  !CDS_PN = "163";
"DQS1P":   PN = "164"  !CDS_PN = "164";
"DQS2N":   PN = "174"  !CDS_PN = "174";
"DQS2P":   PN = "175"  !CDS_PN = "175";
"DQS3N":   PN = "185"  !CDS_PN = "185";
"DQS3P":   PN = "186"  !CDS_PN = "186";
"DQS4N":   PN = "244"  !CDS_PN = "244";
"DQS4P":   PN = "245"  !CDS_PN = "245";
"DQS5N":   PN = "255"  !CDS_PN = "255";
"DQS5P":   PN = "256"  !CDS_PN = "256";
"DQS6N":   PN = "266"  !CDS_PN = "266";
"DQS6P":   PN = "267"  !CDS_PN = "267";
"DQS7N":   PN = "277"  !CDS_PN = "277";
"DQS7P":   PN = "278"  !CDS_PN = "278";
"DQS8N":   PN = "196"  !CDS_PN = "196";
"DQS8P":   PN = "197"  !CDS_PN = "197";
"DQS9N":   PN = "8"  !CDS_PN = "8";
"DQS9P":   PN = "7"  !CDS_PN = "7";
"DQS10N":   PN = "19"  !CDS_PN = "19";
"DQS10P":   PN = "18"  !CDS_PN = "18";
"DQS11N":   PN = "30"  !CDS_PN = "30";
"DQS11P":   PN = "29"  !CDS_PN = "29";
"DQS12N":   PN = "41"  !CDS_PN = "41";
"DQS12P":   PN = "40"  !CDS_PN = "40";
"DQS13N":   PN = "100"  !CDS_PN = "100";
"DQS13P":   PN = "99"  !CDS_PN = "99";
"DQS14N":   PN = "111"  !CDS_PN = "111";
"DQS14P":   PN = "110"  !CDS_PN = "110";
"DQS15N":   PN = "122"  !CDS_PN = "122";
"DQS15P":   PN = "121"  !CDS_PN = "121";
"DQS16N":   PN = "133"  !CDS_PN = "133";
"DQS16P":   PN = "132"  !CDS_PN = "132";
"DQS17N":   PN = "52"  !CDS_PN = "52";
"DQS17P":   PN = "51"  !CDS_PN = "51";
BODY = "SCONN288_H44441003","I144": #LOCATION = "J9T1" !CDS_LOCATION = "J9T1" #SEC = "3" !CDS_SEC = "3";
"VSS<0>":   PN = "283"  !CDS_PN = "283";
"VSS<1>":   PN = "281"  !CDS_PN = "281";
"VSS<2>":   PN = "279"  !CDS_PN = "279";
"VSS<3>":   PN = "276"  !CDS_PN = "276";
"VSS<4>":   PN = "274"  !CDS_PN = "274";
"VSS<5>":   PN = "272"  !CDS_PN = "272";
"VSS<6>":   PN = "270"  !CDS_PN = "270";
"VSS<7>":   PN = "268"  !CDS_PN = "268";
"VSS<8>":   PN = "265"  !CDS_PN = "265";
"VSS<9>":   PN = "263"  !CDS_PN = "263";
"VSS<10>":   PN = "261"  !CDS_PN = "261";
"VSS<11>":   PN = "259"  !CDS_PN = "259";
"VSS<12>":   PN = "257"  !CDS_PN = "257";
"VSS<13>":   PN = "254"  !CDS_PN = "254";
"VSS<14>":   PN = "252"  !CDS_PN = "252";
"VSS<15>":   PN = "250"  !CDS_PN = "250";
"VSS<16>":   PN = "248"  !CDS_PN = "248";
"VSS<17>":   PN = "246"  !CDS_PN = "246";
"VSS<18>":   PN = "243"  !CDS_PN = "243";
"VSS<19>":   PN = "241"  !CDS_PN = "241";
"VSS<20>":   PN = "239"  !CDS_PN = "239";
"VSS<21>":   PN = "202"  !CDS_PN = "202";
"VSS<22>":   PN = "200"  !CDS_PN = "200";
"VSS<23>":   PN = "198"  !CDS_PN = "198";
"VSS<24>":   PN = "195"  !CDS_PN = "195";
"VSS<25>":   PN = "193"  !CDS_PN = "193";
"VSS<26>":   PN = "191"  !CDS_PN = "191";
"VSS<27>":   PN = "189"  !CDS_PN = "189";
"VSS<28>":   PN = "187"  !CDS_PN = "187";
"VSS<29>":   PN = "184"  !CDS_PN = "184";
"VSS<30>":   PN = "182"  !CDS_PN = "182";
"VSS<31>":   PN = "180"  !CDS_PN = "180";
"VSS<32>":   PN = "178"  !CDS_PN = "178";
"VSS<33>":   PN = "176"  !CDS_PN = "176";
"VSS<34>":   PN = "173"  !CDS_PN = "173";
"VSS<35>":   PN = "171"  !CDS_PN = "171";
"VSS<36>":   PN = "169"  !CDS_PN = "169";
"VSS<37>":   PN = "167"  !CDS_PN = "167";
"VSS<38>":   PN = "165"  !CDS_PN = "165";
"VSS<39>":   PN = "162"  !CDS_PN = "162";
"VSS<40>":   PN = "160"  !CDS_PN = "160";
"VSS<41>":   PN = "158"  !CDS_PN = "158";
"VSS<42>":   PN = "156"  !CDS_PN = "156";
"VSS<43>":   PN = "154"  !CDS_PN = "154";
"VSS<44>":   PN = "151"  !CDS_PN = "151";
"VSS<45>":   PN = "149"  !CDS_PN = "149";
"VSS<46>":   PN = "147"  !CDS_PN = "147";
"VSS<47>":   PN = "138"  !CDS_PN = "138";
"VSS<48>":   PN = "136"  !CDS_PN = "136";
"VSS<49>":   PN = "134"  !CDS_PN = "134";
"VSS<50>":   PN = "131"  !CDS_PN = "131";
"VSS<51>":   PN = "129"  !CDS_PN = "129";
"VSS<52>":   PN = "127"  !CDS_PN = "127";
"VSS<53>":   PN = "125"  !CDS_PN = "125";
"VSS<54>":   PN = "123"  !CDS_PN = "123";
"VSS<55>":   PN = "120"  !CDS_PN = "120";
"VSS<56>":   PN = "118"  !CDS_PN = "118";
"VSS<57>":   PN = "116"  !CDS_PN = "116";
"VSS<58>":   PN = "114"  !CDS_PN = "114";
"VSS<59>":   PN = "112"  !CDS_PN = "112";
"VSS<60>":   PN = "109"  !CDS_PN = "109";
"VSS<61>":   PN = "107"  !CDS_PN = "107";
"VSS<62>":   PN = "105"  !CDS_PN = "105";
"VSS<63>":   PN = "103"  !CDS_PN = "103";
"VSS<64>":   PN = "101"  !CDS_PN = "101";
"VSS<65>":   PN = "98"  !CDS_PN = "98";
"VSS<66>":   PN = "96"  !CDS_PN = "96";
"VSS<67>":   PN = "94"  !CDS_PN = "94";
"VSS<68>":   PN = "57"  !CDS_PN = "57";
"VSS<69>":   PN = "55"  !CDS_PN = "55";
"VSS<70>":   PN = "53"  !CDS_PN = "53";
"VSS<71>":   PN = "50"  !CDS_PN = "50";
"VSS<72>":   PN = "48"  !CDS_PN = "48";
"VSS<73>":   PN = "46"  !CDS_PN = "46";
"VSS<74>":   PN = "44"  !CDS_PN = "44";
"VSS<75>":   PN = "42"  !CDS_PN = "42";
"VSS<76>":   PN = "39"  !CDS_PN = "39";
"VSS<77>":   PN = "37"  !CDS_PN = "37";
"VSS<78>":   PN = "35"  !CDS_PN = "35";
"VSS<79>":   PN = "33"  !CDS_PN = "33";
"VSS<80>":   PN = "31"  !CDS_PN = "31";
"VSS<81>":   PN = "28"  !CDS_PN = "28";
"VSS<82>":   PN = "26"  !CDS_PN = "26";
"VSS<83>":   PN = "24"  !CDS_PN = "24";
"VSS<84>":   PN = "22"  !CDS_PN = "22";
"VSS<85>":   PN = "20"  !CDS_PN = "20";
"VSS<86>":   PN = "17"  !CDS_PN = "17";
"VSS<87>":   PN = "15"  !CDS_PN = "15";
"VSS<88>":   PN = "13"  !CDS_PN = "13";
"VSS<89>":   PN = "11"  !CDS_PN = "11";
"VSS<90>":   PN = "9"  !CDS_PN = "9";
"VSS<91>":   PN = "6"  !CDS_PN = "6";
"VSS<92>":   PN = "4"  !CDS_PN = "4";
"VSS<93>":   PN = "2"  !CDS_PN = "2";
DRAWING = "@baseboard_fab2_lib.baseboard_fab2(sch_1):page79";
BODY = "SCONN288_H44441004","I43": #LOCATION = "J1G2" !CDS_LOCATION = "J1G2" #SEC = "3" !CDS_SEC = "3";
"VSS<0>":   PN = "283"  !CDS_PN = "283";
"VSS<1>":   PN = "281"  !CDS_PN = "281";
"VSS<2>":   PN = "279"  !CDS_PN = "279";
"VSS<3>":   PN = "276"  !CDS_PN = "276";
"VSS<4>":   PN = "274"  !CDS_PN = "274";
"VSS<5>":   PN = "272"  !CDS_PN = "272";
"VSS<6>":   PN = "270"  !CDS_PN = "270";
"VSS<7>":   PN = "268"  !CDS_PN = "268";
"VSS<8>":   PN = "265"  !CDS_PN = "265";
"VSS<9>":   PN = "263"  !CDS_PN = "263";
"VSS<10>":   PN = "261"  !CDS_PN = "261";
"VSS<11>":   PN = "259"  !CDS_PN = "259";
"VSS<12>":   PN = "257"  !CDS_PN = "257";
"VSS<13>":   PN = "254"  !CDS_PN = "254";
"VSS<14>":   PN = "252"  !CDS_PN = "252";
"VSS<15>":   PN = "250"  !CDS_PN = "250";
"VSS<16>":   PN = "248"  !CDS_PN = "248";
"VSS<17>":   PN = "246"  !CDS_PN = "246";
"VSS<18>":   PN = "243"  !CDS_PN = "243";
"VSS<19>":   PN = "241"  !CDS_PN = "241";
"VSS<20>":   PN = "239"  !CDS_PN = "239";
"VSS<21>":   PN = "202"  !CDS_PN = "202";
"VSS<22>":   PN = "200"  !CDS_PN = "200";
"VSS<23>":   PN = "198"  !CDS_PN = "198";
"VSS<24>":   PN = "195"  !CDS_PN = "195";
"VSS<25>":   PN = "193"  !CDS_PN = "193";
"VSS<26>":   PN = "191"  !CDS_PN = "191";
"VSS<27>":   PN = "189"  !CDS_PN = "189";
"VSS<28>":   PN = "187"  !CDS_PN = "187";
"VSS<29>":   PN = "184"  !CDS_PN = "184";
"VSS<30>":   PN = "182"  !CDS_PN = "182";
"VSS<31>":   PN = "180"  !CDS_PN = "180";
"VSS<32>":   PN = "178"  !CDS_PN = "178";
"VSS<33>":   PN = "176"  !CDS_PN = "176";
"VSS<34>":   PN = "173"  !CDS_PN = "173";
"VSS<35>":   PN = "171"  !CDS_PN = "171";
"VSS<36>":   PN = "169"  !CDS_PN = "169";
"VSS<37>":   PN = "167"  !CDS_PN = "167";
"VSS<38>":   PN = "165"  !CDS_PN = "165";
"VSS<39>":   PN = "162"  !CDS_PN = "162";
"VSS<40>":   PN = "160"  !CDS_PN = "160";
"VSS<41>":   PN = "158"  !CDS_PN = "158";
"VSS<42>":   PN = "156"  !CDS_PN = "156";
"VSS<43>":   PN = "154"  !CDS_PN = "154";
"VSS<44>":   PN = "151"  !CDS_PN = "151";
"VSS<45>":   PN = "149"  !CDS_PN = "149";
"VSS<46>":   PN = "147"  !CDS_PN = "147";
"VSS<47>":   PN = "138"  !CDS_PN = "138";
"VSS<48>":   PN = "136"  !CDS_PN = "136";
"VSS<49>":   PN = "134"  !CDS_PN = "134";
"VSS<50>":   PN = "131"  !CDS_PN = "131";
"VSS<51>":   PN = "129"  !CDS_PN = "129";
"VSS<52>":   PN = "127"  !CDS_PN = "127";
"VSS<53>":   PN = "125"  !CDS_PN = "125";
"VSS<54>":   PN = "123"  !CDS_PN = "123";
"VSS<55>":   PN = "120"  !CDS_PN = "120";
"VSS<56>":   PN = "118"  !CDS_PN = "118";
"VSS<57>":   PN = "116"  !CDS_PN = "116";
"VSS<58>":   PN = "114"  !CDS_PN = "114";
"VSS<59>":   PN = "112"  !CDS_PN = "112";
"VSS<60>":   PN = "109"  !CDS_PN = "109";
"VSS<61>":   PN = "107"  !CDS_PN = "107";
"VSS<62>":   PN = "105"  !CDS_PN = "105";
"VSS<63>":   PN = "103"  !CDS_PN = "103";
"VSS<64>":   PN = "101"  !CDS_PN = "101";
"VSS<65>":   PN = "98"  !CDS_PN = "98";
"VSS<66>":   PN = "96"  !CDS_PN = "96";
"VSS<67>":   PN = "94"  !CDS_PN = "94";
"VSS<68>":   PN = "57"  !CDS_PN = "57";
"VSS<69>":   PN = "55"  !CDS_PN = "55";
"VSS<70>":   PN = "53"  !CDS_PN = "53";
"VSS<71>":   PN = "50"  !CDS_PN = "50";
"VSS<72>":   PN = "48"  !CDS_PN = "48";
"VSS<73>":   PN = "46"  !CDS_PN = "46";
"VSS<74>":   PN = "44"  !CDS_PN = "44";
"VSS<75>":   PN = "42"  !CDS_PN = "42";
"VSS<76>":   PN = "39"  !CDS_PN = "39";
"VSS<77>":   PN = "37"  !CDS_PN = "37";
"VSS<78>":   PN = "35"  !CDS_PN = "35";
"VSS<79>":   PN = "33"  !CDS_PN = "33";
"VSS<80>":   PN = "31"  !CDS_PN = "31";
"VSS<81>":   PN = "28"  !CDS_PN = "28";
"VSS<82>":   PN = "26"  !CDS_PN = "26";
"VSS<83>":   PN = "24"  !CDS_PN = "24";
"VSS<84>":   PN = "22"  !CDS_PN = "22";
"VSS<85>":   PN = "20"  !CDS_PN = "20";
"VSS<86>":   PN = "17"  !CDS_PN = "17";
"VSS<87>":   PN = "15"  !CDS_PN = "15";
"VSS<88>":   PN = "13"  !CDS_PN = "13";
"VSS<89>":   PN = "11"  !CDS_PN = "11";
"VSS<90>":   PN = "9"  !CDS_PN = "9";
"VSS<91>":   PN = "6"  !CDS_PN = "6";
"VSS<92>":   PN = "4"  !CDS_PN = "4";
"VSS<93>":   PN = "2"  !CDS_PN = "2";
BODY = "SCONN288_H44441004","I64": #LOCATION = "J1G2" !CDS_LOCATION = "J1G2" #SEC = "2" !CDS_SEC = "2";
"DQS0N":   PN = "152"  !CDS_PN = "152";
"DQS0P":   PN = "153"  !CDS_PN = "153";
"DQS1N":   PN = "163"  !CDS_PN = "163";
"DQS1P":   PN = "164"  !CDS_PN = "164";
"DQS2N":   PN = "174"  !CDS_PN = "174";
"DQS2P":   PN = "175"  !CDS_PN = "175";
"DQS3N":   PN = "185"  !CDS_PN = "185";
"DQS3P":   PN = "186"  !CDS_PN = "186";
"DQS4N":   PN = "244"  !CDS_PN = "244";
"DQS4P":   PN = "245"  !CDS_PN = "245";
"DQS5N":   PN = "255"  !CDS_PN = "255";
"DQS5P":   PN = "256"  !CDS_PN = "256";
"DQS6N":   PN = "266"  !CDS_PN = "266";
"DQS6P":   PN = "267"  !CDS_PN = "267";
"DQS7N":   PN = "277"  !CDS_PN = "277";
"DQS7P":   PN = "278"  !CDS_PN = "278";
"DQS8N":   PN = "196"  !CDS_PN = "196";
"DQS8P":   PN = "197"  !CDS_PN = "197";
"DQS9N":   PN = "8"  !CDS_PN = "8";
"DQS9P":   PN = "7"  !CDS_PN = "7";
"DQS10N":   PN = "19"  !CDS_PN = "19";
"DQS10P":   PN = "18"  !CDS_PN = "18";
"DQS11N":   PN = "30"  !CDS_PN = "30";
"DQS11P":   PN = "29"  !CDS_PN = "29";
"DQS12N":   PN = "41"  !CDS_PN = "41";
"DQS12P":   PN = "40"  !CDS_PN = "40";
"DQS13N":   PN = "100"  !CDS_PN = "100";
"DQS13P":   PN = "99"  !CDS_PN = "99";
"DQS14N":   PN = "111"  !CDS_PN = "111";
"DQS14P":   PN = "110"  !CDS_PN = "110";
"DQS15N":   PN = "122"  !CDS_PN = "122";
"DQS15P":   PN = "121"  !CDS_PN = "121";
"DQS16N":   PN = "133"  !CDS_PN = "133";
"DQS16P":   PN = "132"  !CDS_PN = "132";
"DQS17N":   PN = "52"  !CDS_PN = "52";
"DQS17P":   PN = "51"  !CDS_PN = "51";
BODY = "SCONN288_H44441004","I111": #LOCATION = "J1G2" !CDS_LOCATION = "J1G2" #SEC = "1" !CDS_SEC = "1";
"A0":   PN = "79"  !CDS_PN = "79";
"A1":   PN = "72"  !CDS_PN = "72";
"A2":   PN = "216"  !CDS_PN = "216";
"A3":   PN = "71"  !CDS_PN = "71";
"A4":   PN = "214"  !CDS_PN = "214";
"A5":   PN = "213"  !CDS_PN = "213";
"A6":   PN = "69"  !CDS_PN = "69";
"A7":   PN = "211"  !CDS_PN = "211";
"A8":   PN = "68"  !CDS_PN = "68";
"A9":   PN = "66"  !CDS_PN = "66";
"A10":   PN = "225"  !CDS_PN = "225";
"A11":   PN = "210"  !CDS_PN = "210";
"A12":   PN = "65"  !CDS_PN = "65";
"A13":   PN = "232"  !CDS_PN = "232";
"A14_WE_N":   PN = "228"  !CDS_PN = "228";
"A15_CAS_N":   PN = "86"  !CDS_PN = "86";
"A16_RAS_N":   PN = "82"  !CDS_PN = "82";
"A17":   PN = "234"  !CDS_PN = "234";
"ACT_N":   PN = "62"  !CDS_PN = "62";
"ALERT_N":   PN = "208"  !CDS_PN = "208";
"BA<0>":   PN = "81"  !CDS_PN = "81";
"BA<1>":   PN = "224"  !CDS_PN = "224";
"BG<0>":   PN = "63"  !CDS_PN = "63";
"BG<1>":   PN = "207"  !CDS_PN = "207";
"C<2>":   PN = "235"  !CDS_PN = "235";
"CB<0>":   PN = "49"  !CDS_PN = "49";
"CB<1>":   PN = "194"  !CDS_PN = "194";
"CB<2>":   PN = "56"  !CDS_PN = "56";
"CB<3>":   PN = "201"  !CDS_PN = "201";
"CB<4>":   PN = "47"  !CDS_PN = "47";
"CB<5>":   PN = "192"  !CDS_PN = "192";
"CB<6>":   PN = "54"  !CDS_PN = "54";
"CB<7>":   PN = "199"  !CDS_PN = "199";
"CK0N":   PN = "75"  !CDS_PN = "75";
"CK0P":   PN = "74"  !CDS_PN = "74";
"CK1N":   PN = "219"  !CDS_PN = "219";
"CK1P":   PN = "218"  !CDS_PN = "218";
"CKE<0>":   PN = "60"  !CDS_PN = "60";
"CKE<1>":   PN = "203"  !CDS_PN = "203";
"DQ<0>":   PN = "5"  !CDS_PN = "5";
"DQ<1>":   PN = "150"  !CDS_PN = "150";
"DQ<2>":   PN = "12"  !CDS_PN = "12";
"DQ<3>":   PN = "157"  !CDS_PN = "157";
"DQ<4>":   PN = "3"  !CDS_PN = "3";
"DQ<5>":   PN = "148"  !CDS_PN = "148";
"DQ<6>":   PN = "10"  !CDS_PN = "10";
"DQ<7>":   PN = "155"  !CDS_PN = "155";
"DQ<8>":   PN = "16"  !CDS_PN = "16";
"DQ<9>":   PN = "161"  !CDS_PN = "161";
"DQ<10>":   PN = "23"  !CDS_PN = "23";
"DQ<11>":   PN = "168"  !CDS_PN = "168";
"DQ<12>":   PN = "14"  !CDS_PN = "14";
"DQ<13>":   PN = "159"  !CDS_PN = "159";
"DQ<14>":   PN = "21"  !CDS_PN = "21";
"DQ<15>":   PN = "166"  !CDS_PN = "166";
"DQ<16>":   PN = "27"  !CDS_PN = "27";
"DQ<17>":   PN = "172"  !CDS_PN = "172";
"DQ<18>":   PN = "34"  !CDS_PN = "34";
"DQ<19>":   PN = "179"  !CDS_PN = "179";
"DQ<20>":   PN = "25"  !CDS_PN = "25";
"DQ<21>":   PN = "170"  !CDS_PN = "170";
"DQ<22>":   PN = "32"  !CDS_PN = "32";
"DQ<23>":   PN = "177"  !CDS_PN = "177";
"DQ<24>":   PN = "38"  !CDS_PN = "38";
"DQ<25>":   PN = "183"  !CDS_PN = "183";
"DQ<26>":   PN = "45"  !CDS_PN = "45";
"DQ<27>":   PN = "190"  !CDS_PN = "190";
"DQ<28>":   PN = "36"  !CDS_PN = "36";
"DQ<29>":   PN = "181"  !CDS_PN = "181";
"DQ<30>":   PN = "43"  !CDS_PN = "43";
"DQ<31>":   PN = "188"  !CDS_PN = "188";
"DQ<32>":   PN = "97"  !CDS_PN = "97";
"DQ<33>":   PN = "242"  !CDS_PN = "242";
"DQ<34>":   PN = "104"  !CDS_PN = "104";
"DQ<35>":   PN = "249"  !CDS_PN = "249";
"DQ<36>":   PN = "95"  !CDS_PN = "95";
"DQ<37>":   PN = "240"  !CDS_PN = "240";
"DQ<38>":   PN = "102"  !CDS_PN = "102";
"DQ<39>":   PN = "247"  !CDS_PN = "247";
"DQ<40>":   PN = "108"  !CDS_PN = "108";
"DQ<41>":   PN = "253"  !CDS_PN = "253";
"DQ<42>":   PN = "115"  !CDS_PN = "115";
"DQ<43>":   PN = "260"  !CDS_PN = "260";
"DQ<44>":   PN = "106"  !CDS_PN = "106";
"DQ<45>":   PN = "251"  !CDS_PN = "251";
"DQ<46>":   PN = "113"  !CDS_PN = "113";
"DQ<47>":   PN = "258"  !CDS_PN = "258";
"DQ<48>":   PN = "119"  !CDS_PN = "119";
"DQ<49>":   PN = "264"  !CDS_PN = "264";
"DQ<50>":   PN = "126"  !CDS_PN = "126";
"DQ<51>":   PN = "271"  !CDS_PN = "271";
"DQ<52>":   PN = "117"  !CDS_PN = "117";
"DQ<53>":   PN = "262"  !CDS_PN = "262";
"DQ<54>":   PN = "124"  !CDS_PN = "124";
"DQ<55>":   PN = "269"  !CDS_PN = "269";
"DQ<56>":   PN = "130"  !CDS_PN = "130";
"DQ<57>":   PN = "275"  !CDS_PN = "275";
"DQ<58>":   PN = "137"  !CDS_PN = "137";
"DQ<59>":   PN = "282"  !CDS_PN = "282";
"DQ<60>":   PN = "128"  !CDS_PN = "128";
"DQ<61>":   PN = "273"  !CDS_PN = "273";
"DQ<62>":   PN = "135"  !CDS_PN = "135";
"DQ<63>":   PN = "280"  !CDS_PN = "280";
"EVENT_N":   PN = "78"  !CDS_PN = "78";
"ODT<0>":   PN = "87"  !CDS_PN = "87";
"ODT<1>":   PN = "91"  !CDS_PN = "91";
"PAR":   PN = "222"  !CDS_PN = "222";
"RESET_N":   PN = "58"  !CDS_PN = "58";
"RFU<0>":   PN = "205"  !CDS_PN = "205";
"RFU<1>":   PN = "227"  !CDS_PN = "227";
"RFU<2>":   PN = "144"  !CDS_PN = "144";
"S0_N":   PN = "84"  !CDS_PN = "84";
"S1_N":   PN = "89"  !CDS_PN = "89";
"S2_N_C<0>":   PN = "93"  !CDS_PN = "93";
"S3_N_C<1>":   PN = "237"  !CDS_PN = "237";
"SA<0>":   PN = "139"  !CDS_PN = "139";
"SA<1>":   PN = "140"  !CDS_PN = "140";
"SA<2>":   PN = "238"  !CDS_PN = "238";
"SAVE_N_NC":   PN = "230"  !CDS_PN = "230";
"SCL":   PN = "141"  !CDS_PN = "141";
"SDA":   PN = "285"  !CDS_PN = "285";
"VDDSPD":   PN = "284"  !CDS_PN = "284";
"VREFCA":   PN = "146"  !CDS_PN = "146";
BODY = "SCONN288_H44441004","I169": #LOCATION = "J1G2" !CDS_LOCATION = "J1G2" #SEC = "4" !CDS_SEC = "4";
"12V<0>":   PN = "145"  !CDS_PN = "145";
"12V<1>":   PN = "1"  !CDS_PN = "1";
"VDD<0>":   PN = "236"  !CDS_PN = "236";
"VDD<1>":   PN = "233"  !CDS_PN = "233";
"VDD<2>":   PN = "231"  !CDS_PN = "231";
"VDD<3>":   PN = "229"  !CDS_PN = "229";
"VDD<4>":   PN = "226"  !CDS_PN = "226";
"VDD<5>":   PN = "223"  !CDS_PN = "223";
"VDD<6>":   PN = "220"  !CDS_PN = "220";
"VDD<7>":   PN = "217"  !CDS_PN = "217";
"VDD<8>":   PN = "215"  !CDS_PN = "215";
"VDD<9>":   PN = "212"  !CDS_PN = "212";
"VDD<10>":   PN = "209"  !CDS_PN = "209";
"VDD<11>":   PN = "206"  !CDS_PN = "206";
"VDD<12>":   PN = "204"  !CDS_PN = "204";
"VDD<13>":   PN = "92"  !CDS_PN = "92";
"VDD<14>":   PN = "90"  !CDS_PN = "90";
"VDD<15>":   PN = "88"  !CDS_PN = "88";
"VDD<16>":   PN = "85"  !CDS_PN = "85";
"VDD<17>":   PN = "83"  !CDS_PN = "83";
"VDD<18>":   PN = "80"  !CDS_PN = "80";
"VDD<19>":   PN = "76"  !CDS_PN = "76";
"VDD<20>":   PN = "73"  !CDS_PN = "73";
"VDD<21>":   PN = "70"  !CDS_PN = "70";
"VDD<22>":   PN = "67"  !CDS_PN = "67";
"VDD<23>":   PN = "64"  !CDS_PN = "64";
"VDD<24>":   PN = "61"  !CDS_PN = "61";
"VDD<25>":   PN = "59"  !CDS_PN = "59";
"VPP<0>":   PN = "287"  !CDS_PN = "287";
"VPP<1>":   PN = "286"  !CDS_PN = "286";
"VPP<2>":   PN = "288"  !CDS_PN = "288";
"VPP<3>":   PN = "143"  !CDS_PN = "143";
"VPP<4>":   PN = "142"  !CDS_PN = "142";
"VTT<0>":   PN = "221"  !CDS_PN = "221";
"VTT<1>":   PN = "77"  !CDS_PN = "77";
BODY = "CAP_A","I178": #LOCATION = "C9U7" !CDS_LOCATION = "C9U7" &SEC = "1" #&CDS_SEC = "1";
"A":   PN = "1"  !CDS_PN = "1";
"B":   PN = "2"  !CDS_PN = "2";
DRAWING = "@baseboard_fab2_lib.baseboard_fab2(sch_1):page80";
BODY = "CAP_A","I3": #LOCATION = "C1G10" !CDS_LOCATION = "C1G10" &SEC = "1" #&CDS_SEC = "1";
"A":   PN = "1"  !CDS_PN = "1";
"B":   PN = "2"  !CDS_PN = "2";
BODY = "SCONN288_H44441003","I24": #LOCATION = "J9U1" !CDS_LOCATION = "J9U1" #SEC = "1" !CDS_SEC = "1";
"A0":   PN = "79"  !CDS_PN = "79";
"A1":   PN = "72"  !CDS_PN = "72";
"A2":   PN = "216"  !CDS_PN = "216";
"A3":   PN = "71"  !CDS_PN = "71";
"A4":   PN = "214"  !CDS_PN = "214";
"A5":   PN = "213"  !CDS_PN = "213";
"A6":   PN = "69"  !CDS_PN = "69";
"A7":   PN = "211"  !CDS_PN = "211";
"A8":   PN = "68"  !CDS_PN = "68";
"A9":   PN = "66"  !CDS_PN = "66";
"A10":   PN = "225"  !CDS_PN = "225";
"A11":   PN = "210"  !CDS_PN = "210";
"A12":   PN = "65"  !CDS_PN = "65";
"A13":   PN = "232"  !CDS_PN = "232";
"A14_WE_N":   PN = "228"  !CDS_PN = "228";
"A15_CAS_N":   PN = "86"  !CDS_PN = "86";
"A16_RAS_N":   PN = "82"  !CDS_PN = "82";
"A17":   PN = "234"  !CDS_PN = "234";
"ACT_N":   PN = "62"  !CDS_PN = "62";
"ALERT_N":   PN = "208"  !CDS_PN = "208";
"BA<0>":   PN = "81"  !CDS_PN = "81";
"BA<1>":   PN = "224"  !CDS_PN = "224";
"BG<0>":   PN = "63"  !CDS_PN = "63";
"BG<1>":   PN = "207"  !CDS_PN = "207";
"C<2>":   PN = "235"  !CDS_PN = "235";
"CB<0>":   PN = "49"  !CDS_PN = "49";
"CB<1>":   PN = "194"  !CDS_PN = "194";
"CB<2>":   PN = "56"  !CDS_PN = "56";
"CB<3>":   PN = "201"  !CDS_PN = "201";
"CB<4>":   PN = "47"  !CDS_PN = "47";
"CB<5>":   PN = "192"  !CDS_PN = "192";
"CB<6>":   PN = "54"  !CDS_PN = "54";
"CB<7>":   PN = "199"  !CDS_PN = "199";
"CK0N":   PN = "75"  !CDS_PN = "75";
"CK0P":   PN = "74"  !CDS_PN = "74";
"CK1N":   PN = "219"  !CDS_PN = "219";
"CK1P":   PN = "218"  !CDS_PN = "218";
"CKE<0>":   PN = "60"  !CDS_PN = "60";
"CKE<1>":   PN = "203"  !CDS_PN = "203";
"DQ<0>":   PN = "5"  !CDS_PN = "5";
"DQ<1>":   PN = "150"  !CDS_PN = "150";
"DQ<2>":   PN = "12"  !CDS_PN = "12";
"DQ<3>":   PN = "157"  !CDS_PN = "157";
"DQ<4>":   PN = "3"  !CDS_PN = "3";
"DQ<5>":   PN = "148"  !CDS_PN = "148";
"DQ<6>":   PN = "10"  !CDS_PN = "10";
"DQ<7>":   PN = "155"  !CDS_PN = "155";
"DQ<8>":   PN = "16"  !CDS_PN = "16";
"DQ<9>":   PN = "161"  !CDS_PN = "161";
"DQ<10>":   PN = "23"  !CDS_PN = "23";
"DQ<11>":   PN = "168"  !CDS_PN = "168";
"DQ<12>":   PN = "14"  !CDS_PN = "14";
"DQ<13>":   PN = "159"  !CDS_PN = "159";
"DQ<14>":   PN = "21"  !CDS_PN = "21";
"DQ<15>":   PN = "166"  !CDS_PN = "166";
"DQ<16>":   PN = "27"  !CDS_PN = "27";
"DQ<17>":   PN = "172"  !CDS_PN = "172";
"DQ<18>":   PN = "34"  !CDS_PN = "34";
"DQ<19>":   PN = "179"  !CDS_PN = "179";
"DQ<20>":   PN = "25"  !CDS_PN = "25";
"DQ<21>":   PN = "170"  !CDS_PN = "170";
"DQ<22>":   PN = "32"  !CDS_PN = "32";
"DQ<23>":   PN = "177"  !CDS_PN = "177";
"DQ<24>":   PN = "38"  !CDS_PN = "38";
"DQ<25>":   PN = "183"  !CDS_PN = "183";
"DQ<26>":   PN = "45"  !CDS_PN = "45";
"DQ<27>":   PN = "190"  !CDS_PN = "190";
"DQ<28>":   PN = "36"  !CDS_PN = "36";
"DQ<29>":   PN = "181"  !CDS_PN = "181";
"DQ<30>":   PN = "43"  !CDS_PN = "43";
"DQ<31>":   PN = "188"  !CDS_PN = "188";
"DQ<32>":   PN = "97"  !CDS_PN = "97";
"DQ<33>":   PN = "242"  !CDS_PN = "242";
"DQ<34>":   PN = "104"  !CDS_PN = "104";
"DQ<35>":   PN = "249"  !CDS_PN = "249";
"DQ<36>":   PN = "95"  !CDS_PN = "95";
"DQ<37>":   PN = "240"  !CDS_PN = "240";
"DQ<38>":   PN = "102"  !CDS_PN = "102";
"DQ<39>":   PN = "247"  !CDS_PN = "247";
"DQ<40>":   PN = "108"  !CDS_PN = "108";
"DQ<41>":   PN = "253"  !CDS_PN = "253";
"DQ<42>":   PN = "115"  !CDS_PN = "115";
"DQ<43>":   PN = "260"  !CDS_PN = "260";
"DQ<44>":   PN = "106"  !CDS_PN = "106";
"DQ<45>":   PN = "251"  !CDS_PN = "251";
"DQ<46>":   PN = "113"  !CDS_PN = "113";
"DQ<47>":   PN = "258"  !CDS_PN = "258";
"DQ<48>":   PN = "119"  !CDS_PN = "119";
"DQ<49>":   PN = "264"  !CDS_PN = "264";
"DQ<50>":   PN = "126"  !CDS_PN = "126";
"DQ<51>":   PN = "271"  !CDS_PN = "271";
"DQ<52>":   PN = "117"  !CDS_PN = "117";
"DQ<53>":   PN = "262"  !CDS_PN = "262";
"DQ<54>":   PN = "124"  !CDS_PN = "124";
"DQ<55>":   PN = "269"  !CDS_PN = "269";
"DQ<56>":   PN = "130"  !CDS_PN = "130";
"DQ<57>":   PN = "275"  !CDS_PN = "275";
"DQ<58>":   PN = "137"  !CDS_PN = "137";
"DQ<59>":   PN = "282"  !CDS_PN = "282";
"DQ<60>":   PN = "128"  !CDS_PN = "128";
"DQ<61>":   PN = "273"  !CDS_PN = "273";
"DQ<62>":   PN = "135"  !CDS_PN = "135";
"DQ<63>":   PN = "280"  !CDS_PN = "280";
"EVENT_N":   PN = "78"  !CDS_PN = "78";
"ODT<0>":   PN = "87"  !CDS_PN = "87";
"ODT<1>":   PN = "91"  !CDS_PN = "91";
"PAR":   PN = "222"  !CDS_PN = "222";
"RESET_N":   PN = "58"  !CDS_PN = "58";
"RFU<0>":   PN = "205"  !CDS_PN = "205";
"RFU<1>":   PN = "227"  !CDS_PN = "227";
"RFU<2>":   PN = "144"  !CDS_PN = "144";
"S0_N":   PN = "84"  !CDS_PN = "84";
"S1_N":   PN = "89"  !CDS_PN = "89";
"S2_N_C<0>":   PN = "93"  !CDS_PN = "93";
"S3_N_C<1>":   PN = "237"  !CDS_PN = "237";
"SA<0>":   PN = "139"  !CDS_PN = "139";
"SA<1>":   PN = "140"  !CDS_PN = "140";
"SA<2>":   PN = "238"  !CDS_PN = "238";
"SAVE_N_NC":   PN = "230"  !CDS_PN = "230";
"SCL":   PN = "141"  !CDS_PN = "141";
"SDA":   PN = "285"  !CDS_PN = "285";
"VDDSPD":   PN = "284"  !CDS_PN = "284";
"VREFCA":   PN = "146"  !CDS_PN = "146";
BODY = "SCONN288_H44441003","I56": #LOCATION = "J9U1" !CDS_LOCATION = "J9U1" #SEC = "4" !CDS_SEC = "4";
"12V<0>":   PN = "145"  !CDS_PN = "145";
"12V<1>":   PN = "1"  !CDS_PN = "1";
"VDD<0>":   PN = "236"  !CDS_PN = "236";
"VDD<1>":   PN = "233"  !CDS_PN = "233";
"VDD<2>":   PN = "231"  !CDS_PN = "231";
"VDD<3>":   PN = "229"  !CDS_PN = "229";
"VDD<4>":   PN = "226"  !CDS_PN = "226";
"VDD<5>":   PN = "223"  !CDS_PN = "223";
"VDD<6>":   PN = "220"  !CDS_PN = "220";
"VDD<7>":   PN = "217"  !CDS_PN = "217";
"VDD<8>":   PN = "215"  !CDS_PN = "215";
"VDD<9>":   PN = "212"  !CDS_PN = "212";
"VDD<10>":   PN = "209"  !CDS_PN = "209";
"VDD<11>":   PN = "206"  !CDS_PN = "206";
"VDD<12>":   PN = "204"  !CDS_PN = "204";
"VDD<13>":   PN = "92"  !CDS_PN = "92";
"VDD<14>":   PN = "90"  !CDS_PN = "90";
"VDD<15>":   PN = "88"  !CDS_PN = "88";
"VDD<16>":   PN = "85"  !CDS_PN = "85";
"VDD<17>":   PN = "83"  !CDS_PN = "83";
"VDD<18>":   PN = "80"  !CDS_PN = "80";
"VDD<19>":   PN = "76"  !CDS_PN = "76";
"VDD<20>":   PN = "73"  !CDS_PN = "73";
"VDD<21>":   PN = "70"  !CDS_PN = "70";
"VDD<22>":   PN = "67"  !CDS_PN = "67";
"VDD<23>":   PN = "64"  !CDS_PN = "64";
"VDD<24>":   PN = "61"  !CDS_PN = "61";
"VDD<25>":   PN = "59"  !CDS_PN = "59";
"VPP<0>":   PN = "287"  !CDS_PN = "287";
"VPP<1>":   PN = "286"  !CDS_PN = "286";
"VPP<2>":   PN = "288"  !CDS_PN = "288";
"VPP<3>":   PN = "143"  !CDS_PN = "143";
"VPP<4>":   PN = "142"  !CDS_PN = "142";
"VTT<0>":   PN = "221"  !CDS_PN = "221";
"VTT<1>":   PN = "77"  !CDS_PN = "77";
BODY = "SCONN288_H44441003","I101": #LOCATION = "J9U1" !CDS_LOCATION = "J9U1" #SEC = "2" !CDS_SEC = "2";
"DQS0N":   PN = "152"  !CDS_PN = "152";
"DQS0P":   PN = "153"  !CDS_PN = "153";
"DQS1N":   PN = "163"  !CDS_PN = "163";
"DQS1P":   PN = "164"  !CDS_PN = "164";
"DQS2N":   PN = "174"  !CDS_PN = "174";
"DQS2P":   PN = "175"  !CDS_PN = "175";
"DQS3N":   PN = "185"  !CDS_PN = "185";
"DQS3P":   PN = "186"  !CDS_PN = "186";
"DQS4N":   PN = "244"  !CDS_PN = "244";
"DQS4P":   PN = "245"  !CDS_PN = "245";
"DQS5N":   PN = "255"  !CDS_PN = "255";
"DQS5P":   PN = "256"  !CDS_PN = "256";
"DQS6N":   PN = "266"  !CDS_PN = "266";
"DQS6P":   PN = "267"  !CDS_PN = "267";
"DQS7N":   PN = "277"  !CDS_PN = "277";
"DQS7P":   PN = "278"  !CDS_PN = "278";
"DQS8N":   PN = "196"  !CDS_PN = "196";
"DQS8P":   PN = "197"  !CDS_PN = "197";
"DQS9N":   PN = "8"  !CDS_PN = "8";
"DQS9P":   PN = "7"  !CDS_PN = "7";
"DQS10N":   PN = "19"  !CDS_PN = "19";
"DQS10P":   PN = "18"  !CDS_PN = "18";
"DQS11N":   PN = "30"  !CDS_PN = "30";
"DQS11P":   PN = "29"  !CDS_PN = "29";
"DQS12N":   PN = "41"  !CDS_PN = "41";
"DQS12P":   PN = "40"  !CDS_PN = "40";
"DQS13N":   PN = "100"  !CDS_PN = "100";
"DQS13P":   PN = "99"  !CDS_PN = "99";
"DQS14N":   PN = "111"  !CDS_PN = "111";
"DQS14P":   PN = "110"  !CDS_PN = "110";
"DQS15N":   PN = "122"  !CDS_PN = "122";
"DQS15P":   PN = "121"  !CDS_PN = "121";
"DQS16N":   PN = "133"  !CDS_PN = "133";
"DQS16P":   PN = "132"  !CDS_PN = "132";
"DQS17N":   PN = "52"  !CDS_PN = "52";
"DQS17P":   PN = "51"  !CDS_PN = "51";
BODY = "SCONN288_H44441003","I138": #LOCATION = "J9U1" !CDS_LOCATION = "J9U1" #SEC = "3" !CDS_SEC = "3";
"VSS<0>":   PN = "283"  !CDS_PN = "283";
"VSS<1>":   PN = "281"  !CDS_PN = "281";
"VSS<2>":   PN = "279"  !CDS_PN = "279";
"VSS<3>":   PN = "276"  !CDS_PN = "276";
"VSS<4>":   PN = "274"  !CDS_PN = "274";
"VSS<5>":   PN = "272"  !CDS_PN = "272";
"VSS<6>":   PN = "270"  !CDS_PN = "270";
"VSS<7>":   PN = "268"  !CDS_PN = "268";
"VSS<8>":   PN = "265"  !CDS_PN = "265";
"VSS<9>":   PN = "263"  !CDS_PN = "263";
"VSS<10>":   PN = "261"  !CDS_PN = "261";
"VSS<11>":   PN = "259"  !CDS_PN = "259";
"VSS<12>":   PN = "257"  !CDS_PN = "257";
"VSS<13>":   PN = "254"  !CDS_PN = "254";
"VSS<14>":   PN = "252"  !CDS_PN = "252";
"VSS<15>":   PN = "250"  !CDS_PN = "250";
"VSS<16>":   PN = "248"  !CDS_PN = "248";
"VSS<17>":   PN = "246"  !CDS_PN = "246";
"VSS<18>":   PN = "243"  !CDS_PN = "243";
"VSS<19>":   PN = "241"  !CDS_PN = "241";
"VSS<20>":   PN = "239"  !CDS_PN = "239";
"VSS<21>":   PN = "202"  !CDS_PN = "202";
"VSS<22>":   PN = "200"  !CDS_PN = "200";
"VSS<23>":   PN = "198"  !CDS_PN = "198";
"VSS<24>":   PN = "195"  !CDS_PN = "195";
"VSS<25>":   PN = "193"  !CDS_PN = "193";
"VSS<26>":   PN = "191"  !CDS_PN = "191";
"VSS<27>":   PN = "189"  !CDS_PN = "189";
"VSS<28>":   PN = "187"  !CDS_PN = "187";
"VSS<29>":   PN = "184"  !CDS_PN = "184";
"VSS<30>":   PN = "182"  !CDS_PN = "182";
"VSS<31>":   PN = "180"  !CDS_PN = "180";
"VSS<32>":   PN = "178"  !CDS_PN = "178";
"VSS<33>":   PN = "176"  !CDS_PN = "176";
"VSS<34>":   PN = "173"  !CDS_PN = "173";
"VSS<35>":   PN = "171"  !CDS_PN = "171";
"VSS<36>":   PN = "169"  !CDS_PN = "169";
"VSS<37>":   PN = "167"  !CDS_PN = "167";
"VSS<38>":   PN = "165"  !CDS_PN = "165";
"VSS<39>":   PN = "162"  !CDS_PN = "162";
"VSS<40>":   PN = "160"  !CDS_PN = "160";
"VSS<41>":   PN = "158"  !CDS_PN = "158";
"VSS<42>":   PN = "156"  !CDS_PN = "156";
"VSS<43>":   PN = "154"  !CDS_PN = "154";
"VSS<44>":   PN = "151"  !CDS_PN = "151";
"VSS<45>":   PN = "149"  !CDS_PN = "149";
"VSS<46>":   PN = "147"  !CDS_PN = "147";
"VSS<47>":   PN = "138"  !CDS_PN = "138";
"VSS<48>":   PN = "136"  !CDS_PN = "136";
"VSS<49>":   PN = "134"  !CDS_PN = "134";
"VSS<50>":   PN = "131"  !CDS_PN = "131";
"VSS<51>":   PN = "129"  !CDS_PN = "129";
"VSS<52>":   PN = "127"  !CDS_PN = "127";
"VSS<53>":   PN = "125"  !CDS_PN = "125";
"VSS<54>":   PN = "123"  !CDS_PN = "123";
"VSS<55>":   PN = "120"  !CDS_PN = "120";
"VSS<56>":   PN = "118"  !CDS_PN = "118";
"VSS<57>":   PN = "116"  !CDS_PN = "116";
"VSS<58>":   PN = "114"  !CDS_PN = "114";
"VSS<59>":   PN = "112"  !CDS_PN = "112";
"VSS<60>":   PN = "109"  !CDS_PN = "109";
"VSS<61>":   PN = "107"  !CDS_PN = "107";
"VSS<62>":   PN = "105"  !CDS_PN = "105";
"VSS<63>":   PN = "103"  !CDS_PN = "103";
"VSS<64>":   PN = "101"  !CDS_PN = "101";
"VSS<65>":   PN = "98"  !CDS_PN = "98";
"VSS<66>":   PN = "96"  !CDS_PN = "96";
"VSS<67>":   PN = "94"  !CDS_PN = "94";
"VSS<68>":   PN = "57"  !CDS_PN = "57";
"VSS<69>":   PN = "55"  !CDS_PN = "55";
"VSS<70>":   PN = "53"  !CDS_PN = "53";
"VSS<71>":   PN = "50"  !CDS_PN = "50";
"VSS<72>":   PN = "48"  !CDS_PN = "48";
"VSS<73>":   PN = "46"  !CDS_PN = "46";
"VSS<74>":   PN = "44"  !CDS_PN = "44";
"VSS<75>":   PN = "42"  !CDS_PN = "42";
"VSS<76>":   PN = "39"  !CDS_PN = "39";
"VSS<77>":   PN = "37"  !CDS_PN = "37";
"VSS<78>":   PN = "35"  !CDS_PN = "35";
"VSS<79>":   PN = "33"  !CDS_PN = "33";
"VSS<80>":   PN = "31"  !CDS_PN = "31";
"VSS<81>":   PN = "28"  !CDS_PN = "28";
"VSS<82>":   PN = "26"  !CDS_PN = "26";
"VSS<83>":   PN = "24"  !CDS_PN = "24";
"VSS<84>":   PN = "22"  !CDS_PN = "22";
"VSS<85>":   PN = "20"  !CDS_PN = "20";
"VSS<86>":   PN = "17"  !CDS_PN = "17";
"VSS<87>":   PN = "15"  !CDS_PN = "15";
"VSS<88>":   PN = "13"  !CDS_PN = "13";
"VSS<89>":   PN = "11"  !CDS_PN = "11";
"VSS<90>":   PN = "9"  !CDS_PN = "9";
"VSS<91>":   PN = "6"  !CDS_PN = "6";
"VSS<92>":   PN = "4"  !CDS_PN = "4";
"VSS<93>":   PN = "2"  !CDS_PN = "2";
DRAWING = "@baseboard_fab2_lib.baseboard_fab2(sch_1):page81";
BODY = "SCONN288_H44441004","I67": #LOCATION = "J1G3" !CDS_LOCATION = "J1G3" #SEC = "2" !CDS_SEC = "2";
"DQS0N":   PN = "152"  !CDS_PN = "152";
"DQS0P":   PN = "153"  !CDS_PN = "153";
"DQS1N":   PN = "163"  !CDS_PN = "163";
"DQS1P":   PN = "164"  !CDS_PN = "164";
"DQS2N":   PN = "174"  !CDS_PN = "174";
"DQS2P":   PN = "175"  !CDS_PN = "175";
"DQS3N":   PN = "185"  !CDS_PN = "185";
"DQS3P":   PN = "186"  !CDS_PN = "186";
"DQS4N":   PN = "244"  !CDS_PN = "244";
"DQS4P":   PN = "245"  !CDS_PN = "245";
"DQS5N":   PN = "255"  !CDS_PN = "255";
"DQS5P":   PN = "256"  !CDS_PN = "256";
"DQS6N":   PN = "266"  !CDS_PN = "266";
"DQS6P":   PN = "267"  !CDS_PN = "267";
"DQS7N":   PN = "277"  !CDS_PN = "277";
"DQS7P":   PN = "278"  !CDS_PN = "278";
"DQS8N":   PN = "196"  !CDS_PN = "196";
"DQS8P":   PN = "197"  !CDS_PN = "197";
"DQS9N":   PN = "8"  !CDS_PN = "8";
"DQS9P":   PN = "7"  !CDS_PN = "7";
"DQS10N":   PN = "19"  !CDS_PN = "19";
"DQS10P":   PN = "18"  !CDS_PN = "18";
"DQS11N":   PN = "30"  !CDS_PN = "30";
"DQS11P":   PN = "29"  !CDS_PN = "29";
"DQS12N":   PN = "41"  !CDS_PN = "41";
"DQS12P":   PN = "40"  !CDS_PN = "40";
"DQS13N":   PN = "100"  !CDS_PN = "100";
"DQS13P":   PN = "99"  !CDS_PN = "99";
"DQS14N":   PN = "111"  !CDS_PN = "111";
"DQS14P":   PN = "110"  !CDS_PN = "110";
"DQS15N":   PN = "122"  !CDS_PN = "122";
"DQS15P":   PN = "121"  !CDS_PN = "121";
"DQS16N":   PN = "133"  !CDS_PN = "133";
"DQS16P":   PN = "132"  !CDS_PN = "132";
"DQS17N":   PN = "52"  !CDS_PN = "52";
"DQS17P":   PN = "51"  !CDS_PN = "51";
BODY = "SCONN288_H44441004","I169": #LOCATION = "J1G3" !CDS_LOCATION = "J1G3" #SEC = "4" !CDS_SEC = "4";
"12V<0>":   PN = "145"  !CDS_PN = "145";
"12V<1>":   PN = "1"  !CDS_PN = "1";
"VDD<0>":   PN = "236"  !CDS_PN = "236";
"VDD<1>":   PN = "233"  !CDS_PN = "233";
"VDD<2>":   PN = "231"  !CDS_PN = "231";
"VDD<3>":   PN = "229"  !CDS_PN = "229";
"VDD<4>":   PN = "226"  !CDS_PN = "226";
"VDD<5>":   PN = "223"  !CDS_PN = "223";
"VDD<6>":   PN = "220"  !CDS_PN = "220";
"VDD<7>":   PN = "217"  !CDS_PN = "217";
"VDD<8>":   PN = "215"  !CDS_PN = "215";
"VDD<9>":   PN = "212"  !CDS_PN = "212";
"VDD<10>":   PN = "209"  !CDS_PN = "209";
"VDD<11>":   PN = "206"  !CDS_PN = "206";
"VDD<12>":   PN = "204"  !CDS_PN = "204";
"VDD<13>":   PN = "92"  !CDS_PN = "92";
"VDD<14>":   PN = "90"  !CDS_PN = "90";
"VDD<15>":   PN = "88"  !CDS_PN = "88";
"VDD<16>":   PN = "85"  !CDS_PN = "85";
"VDD<17>":   PN = "83"  !CDS_PN = "83";
"VDD<18>":   PN = "80"  !CDS_PN = "80";
"VDD<19>":   PN = "76"  !CDS_PN = "76";
"VDD<20>":   PN = "73"  !CDS_PN = "73";
"VDD<21>":   PN = "70"  !CDS_PN = "70";
"VDD<22>":   PN = "67"  !CDS_PN = "67";
"VDD<23>":   PN = "64"  !CDS_PN = "64";
"VDD<24>":   PN = "61"  !CDS_PN = "61";
"VDD<25>":   PN = "59"  !CDS_PN = "59";
"VPP<0>":   PN = "287"  !CDS_PN = "287";
"VPP<1>":   PN = "286"  !CDS_PN = "286";
"VPP<2>":   PN = "288"  !CDS_PN = "288";
"VPP<3>":   PN = "143"  !CDS_PN = "143";
"VPP<4>":   PN = "142"  !CDS_PN = "142";
"VTT<0>":   PN = "221"  !CDS_PN = "221";
"VTT<1>":   PN = "77"  !CDS_PN = "77";
BODY = "CAP_A","I178": #LOCATION = "C9U10" !CDS_LOCATION = "C9U10" &SEC = "1" #&CDS_SEC = "1";
"A":   PN = "1"  !CDS_PN = "1";
"B":   PN = "2"  !CDS_PN = "2";
BODY = "SCONN288_H44441004","I185": #LOCATION = "J1G3" !CDS_LOCATION = "J1G3" #SEC = "3" !CDS_SEC = "3";
"VSS<0>":   PN = "283"  !CDS_PN = "283";
"VSS<1>":   PN = "281"  !CDS_PN = "281";
"VSS<2>":   PN = "279"  !CDS_PN = "279";
"VSS<3>":   PN = "276"  !CDS_PN = "276";
"VSS<4>":   PN = "274"  !CDS_PN = "274";
"VSS<5>":   PN = "272"  !CDS_PN = "272";
"VSS<6>":   PN = "270"  !CDS_PN = "270";
"VSS<7>":   PN = "268"  !CDS_PN = "268";
"VSS<8>":   PN = "265"  !CDS_PN = "265";
"VSS<9>":   PN = "263"  !CDS_PN = "263";
"VSS<10>":   PN = "261"  !CDS_PN = "261";
"VSS<11>":   PN = "259"  !CDS_PN = "259";
"VSS<12>":   PN = "257"  !CDS_PN = "257";
"VSS<13>":   PN = "254"  !CDS_PN = "254";
"VSS<14>":   PN = "252"  !CDS_PN = "252";
"VSS<15>":   PN = "250"  !CDS_PN = "250";
"VSS<16>":   PN = "248"  !CDS_PN = "248";
"VSS<17>":   PN = "246"  !CDS_PN = "246";
"VSS<18>":   PN = "243"  !CDS_PN = "243";
"VSS<19>":   PN = "241"  !CDS_PN = "241";
"VSS<20>":   PN = "239"  !CDS_PN = "239";
"VSS<21>":   PN = "202"  !CDS_PN = "202";
"VSS<22>":   PN = "200"  !CDS_PN = "200";
"VSS<23>":   PN = "198"  !CDS_PN = "198";
"VSS<24>":   PN = "195"  !CDS_PN = "195";
"VSS<25>":   PN = "193"  !CDS_PN = "193";
"VSS<26>":   PN = "191"  !CDS_PN = "191";
"VSS<27>":   PN = "189"  !CDS_PN = "189";
"VSS<28>":   PN = "187"  !CDS_PN = "187";
"VSS<29>":   PN = "184"  !CDS_PN = "184";
"VSS<30>":   PN = "182"  !CDS_PN = "182";
"VSS<31>":   PN = "180"  !CDS_PN = "180";
"VSS<32>":   PN = "178"  !CDS_PN = "178";
"VSS<33>":   PN = "176"  !CDS_PN = "176";
"VSS<34>":   PN = "173"  !CDS_PN = "173";
"VSS<35>":   PN = "171"  !CDS_PN = "171";
"VSS<36>":   PN = "169"  !CDS_PN = "169";
"VSS<37>":   PN = "167"  !CDS_PN = "167";
"VSS<38>":   PN = "165"  !CDS_PN = "165";
"VSS<39>":   PN = "162"  !CDS_PN = "162";
"VSS<40>":   PN = "160"  !CDS_PN = "160";
"VSS<41>":   PN = "158"  !CDS_PN = "158";
"VSS<42>":   PN = "156"  !CDS_PN = "156";
"VSS<43>":   PN = "154"  !CDS_PN = "154";
"VSS<44>":   PN = "151"  !CDS_PN = "151";
"VSS<45>":   PN = "149"  !CDS_PN = "149";
"VSS<46>":   PN = "147"  !CDS_PN = "147";
"VSS<47>":   PN = "138"  !CDS_PN = "138";
"VSS<48>":   PN = "136"  !CDS_PN = "136";
"VSS<49>":   PN = "134"  !CDS_PN = "134";
"VSS<50>":   PN = "131"  !CDS_PN = "131";
"VSS<51>":   PN = "129"  !CDS_PN = "129";
"VSS<52>":   PN = "127"  !CDS_PN = "127";
"VSS<53>":   PN = "125"  !CDS_PN = "125";
"VSS<54>":   PN = "123"  !CDS_PN = "123";
"VSS<55>":   PN = "120"  !CDS_PN = "120";
"VSS<56>":   PN = "118"  !CDS_PN = "118";
"VSS<57>":   PN = "116"  !CDS_PN = "116";
"VSS<58>":   PN = "114"  !CDS_PN = "114";
"VSS<59>":   PN = "112"  !CDS_PN = "112";
"VSS<60>":   PN = "109"  !CDS_PN = "109";
"VSS<61>":   PN = "107"  !CDS_PN = "107";
"VSS<62>":   PN = "105"  !CDS_PN = "105";
"VSS<63>":   PN = "103"  !CDS_PN = "103";
"VSS<64>":   PN = "101"  !CDS_PN = "101";
"VSS<65>":   PN = "98"  !CDS_PN = "98";
"VSS<66>":   PN = "96"  !CDS_PN = "96";
"VSS<67>":   PN = "94"  !CDS_PN = "94";
"VSS<68>":   PN = "57"  !CDS_PN = "57";
"VSS<69>":   PN = "55"  !CDS_PN = "55";
"VSS<70>":   PN = "53"  !CDS_PN = "53";
"VSS<71>":   PN = "50"  !CDS_PN = "50";
"VSS<72>":   PN = "48"  !CDS_PN = "48";
"VSS<73>":   PN = "46"  !CDS_PN = "46";
"VSS<74>":   PN = "44"  !CDS_PN = "44";
"VSS<75>":   PN = "42"  !CDS_PN = "42";
"VSS<76>":   PN = "39"  !CDS_PN = "39";
"VSS<77>":   PN = "37"  !CDS_PN = "37";
"VSS<78>":   PN = "35"  !CDS_PN = "35";
"VSS<79>":   PN = "33"  !CDS_PN = "33";
"VSS<80>":   PN = "31"  !CDS_PN = "31";
"VSS<81>":   PN = "28"  !CDS_PN = "28";
"VSS<82>":   PN = "26"  !CDS_PN = "26";
"VSS<83>":   PN = "24"  !CDS_PN = "24";
"VSS<84>":   PN = "22"  !CDS_PN = "22";
"VSS<85>":   PN = "20"  !CDS_PN = "20";
"VSS<86>":   PN = "17"  !CDS_PN = "17";
"VSS<87>":   PN = "15"  !CDS_PN = "15";
"VSS<88>":   PN = "13"  !CDS_PN = "13";
"VSS<89>":   PN = "11"  !CDS_PN = "11";
"VSS<90>":   PN = "9"  !CDS_PN = "9";
"VSS<91>":   PN = "6"  !CDS_PN = "6";
"VSS<92>":   PN = "4"  !CDS_PN = "4";
"VSS<93>":   PN = "2"  !CDS_PN = "2";
BODY = "SCONN288_H44441004","I186": #LOCATION = "J1G3" !CDS_LOCATION = "J1G3" #SEC = "1" !CDS_SEC = "1";
"A0":   PN = "79"  !CDS_PN = "79";
"A1":   PN = "72"  !CDS_PN = "72";
"A2":   PN = "216"  !CDS_PN = "216";
"A3":   PN = "71"  !CDS_PN = "71";
"A4":   PN = "214"  !CDS_PN = "214";
"A5":   PN = "213"  !CDS_PN = "213";
"A6":   PN = "69"  !CDS_PN = "69";
"A7":   PN = "211"  !CDS_PN = "211";
"A8":   PN = "68"  !CDS_PN = "68";
"A9":   PN = "66"  !CDS_PN = "66";
"A10":   PN = "225"  !CDS_PN = "225";
"A11":   PN = "210"  !CDS_PN = "210";
"A12":   PN = "65"  !CDS_PN = "65";
"A13":   PN = "232"  !CDS_PN = "232";
"A14_WE_N":   PN = "228"  !CDS_PN = "228";
"A15_CAS_N":   PN = "86"  !CDS_PN = "86";
"A16_RAS_N":   PN = "82"  !CDS_PN = "82";
"A17":   PN = "234"  !CDS_PN = "234";
"ACT_N":   PN = "62"  !CDS_PN = "62";
"ALERT_N":   PN = "208"  !CDS_PN = "208";
"BA<0>":   PN = "81"  !CDS_PN = "81";
"BA<1>":   PN = "224"  !CDS_PN = "224";
"BG<0>":   PN = "63"  !CDS_PN = "63";
"BG<1>":   PN = "207"  !CDS_PN = "207";
"C<2>":   PN = "235"  !CDS_PN = "235";
"CB<0>":   PN = "49"  !CDS_PN = "49";
"CB<1>":   PN = "194"  !CDS_PN = "194";
"CB<2>":   PN = "56"  !CDS_PN = "56";
"CB<3>":   PN = "201"  !CDS_PN = "201";
"CB<4>":   PN = "47"  !CDS_PN = "47";
"CB<5>":   PN = "192"  !CDS_PN = "192";
"CB<6>":   PN = "54"  !CDS_PN = "54";
"CB<7>":   PN = "199"  !CDS_PN = "199";
"CK0N":   PN = "75"  !CDS_PN = "75";
"CK0P":   PN = "74"  !CDS_PN = "74";
"CK1N":   PN = "219"  !CDS_PN = "219";
"CK1P":   PN = "218"  !CDS_PN = "218";
"CKE<0>":   PN = "60"  !CDS_PN = "60";
"CKE<1>":   PN = "203"  !CDS_PN = "203";
"DQ<0>":   PN = "5"  !CDS_PN = "5";
"DQ<1>":   PN = "150"  !CDS_PN = "150";
"DQ<2>":   PN = "12"  !CDS_PN = "12";
"DQ<3>":   PN = "157"  !CDS_PN = "157";
"DQ<4>":   PN = "3"  !CDS_PN = "3";
"DQ<5>":   PN = "148"  !CDS_PN = "148";
"DQ<6>":   PN = "10"  !CDS_PN = "10";
"DQ<7>":   PN = "155"  !CDS_PN = "155";
"DQ<8>":   PN = "16"  !CDS_PN = "16";
"DQ<9>":   PN = "161"  !CDS_PN = "161";
"DQ<10>":   PN = "23"  !CDS_PN = "23";
"DQ<11>":   PN = "168"  !CDS_PN = "168";
"DQ<12>":   PN = "14"  !CDS_PN = "14";
"DQ<13>":   PN = "159"  !CDS_PN = "159";
"DQ<14>":   PN = "21"  !CDS_PN = "21";
"DQ<15>":   PN = "166"  !CDS_PN = "166";
"DQ<16>":   PN = "27"  !CDS_PN = "27";
"DQ<17>":   PN = "172"  !CDS_PN = "172";
"DQ<18>":   PN = "34"  !CDS_PN = "34";
"DQ<19>":   PN = "179"  !CDS_PN = "179";
"DQ<20>":   PN = "25"  !CDS_PN = "25";
"DQ<21>":   PN = "170"  !CDS_PN = "170";
"DQ<22>":   PN = "32"  !CDS_PN = "32";
"DQ<23>":   PN = "177"  !CDS_PN = "177";
"DQ<24>":   PN = "38"  !CDS_PN = "38";
"DQ<25>":   PN = "183"  !CDS_PN = "183";
"DQ<26>":   PN = "45"  !CDS_PN = "45";
"DQ<27>":   PN = "190"  !CDS_PN = "190";
"DQ<28>":   PN = "36"  !CDS_PN = "36";
"DQ<29>":   PN = "181"  !CDS_PN = "181";
"DQ<30>":   PN = "43"  !CDS_PN = "43";
"DQ<31>":   PN = "188"  !CDS_PN = "188";
"DQ<32>":   PN = "97"  !CDS_PN = "97";
"DQ<33>":   PN = "242"  !CDS_PN = "242";
"DQ<34>":   PN = "104"  !CDS_PN = "104";
"DQ<35>":   PN = "249"  !CDS_PN = "249";
"DQ<36>":   PN = "95"  !CDS_PN = "95";
"DQ<37>":   PN = "240"  !CDS_PN = "240";
"DQ<38>":   PN = "102"  !CDS_PN = "102";
"DQ<39>":   PN = "247"  !CDS_PN = "247";
"DQ<40>":   PN = "108"  !CDS_PN = "108";
"DQ<41>":   PN = "253"  !CDS_PN = "253";
"DQ<42>":   PN = "115"  !CDS_PN = "115";
"DQ<43>":   PN = "260"  !CDS_PN = "260";
"DQ<44>":   PN = "106"  !CDS_PN = "106";
"DQ<45>":   PN = "251"  !CDS_PN = "251";
"DQ<46>":   PN = "113"  !CDS_PN = "113";
"DQ<47>":   PN = "258"  !CDS_PN = "258";
"DQ<48>":   PN = "119"  !CDS_PN = "119";
"DQ<49>":   PN = "264"  !CDS_PN = "264";
"DQ<50>":   PN = "126"  !CDS_PN = "126";
"DQ<51>":   PN = "271"  !CDS_PN = "271";
"DQ<52>":   PN = "117"  !CDS_PN = "117";
"DQ<53>":   PN = "262"  !CDS_PN = "262";
"DQ<54>":   PN = "124"  !CDS_PN = "124";
"DQ<55>":   PN = "269"  !CDS_PN = "269";
"DQ<56>":   PN = "130"  !CDS_PN = "130";
"DQ<57>":   PN = "275"  !CDS_PN = "275";
"DQ<58>":   PN = "137"  !CDS_PN = "137";
"DQ<59>":   PN = "282"  !CDS_PN = "282";
"DQ<60>":   PN = "128"  !CDS_PN = "128";
"DQ<61>":   PN = "273"  !CDS_PN = "273";
"DQ<62>":   PN = "135"  !CDS_PN = "135";
"DQ<63>":   PN = "280"  !CDS_PN = "280";
"EVENT_N":   PN = "78"  !CDS_PN = "78";
"ODT<0>":   PN = "87"  !CDS_PN = "87";
"ODT<1>":   PN = "91"  !CDS_PN = "91";
"PAR":   PN = "222"  !CDS_PN = "222";
"RESET_N":   PN = "58"  !CDS_PN = "58";
"RFU<0>":   PN = "205"  !CDS_PN = "205";
"RFU<1>":   PN = "227"  !CDS_PN = "227";
"RFU<2>":   PN = "144"  !CDS_PN = "144";
"S0_N":   PN = "84"  !CDS_PN = "84";
"S1_N":   PN = "89"  !CDS_PN = "89";
"S2_N_C<0>":   PN = "93"  !CDS_PN = "93";
"S3_N_C<1>":   PN = "237"  !CDS_PN = "237";
"SA<0>":   PN = "139"  !CDS_PN = "139";
"SA<1>":   PN = "140"  !CDS_PN = "140";
"SA<2>":   PN = "238"  !CDS_PN = "238";
"SAVE_N_NC":   PN = "230"  !CDS_PN = "230";
"SCL":   PN = "141"  !CDS_PN = "141";
"SDA":   PN = "285"  !CDS_PN = "285";
"VDDSPD":   PN = "284"  !CDS_PN = "284";
"VREFCA":   PN = "146"  !CDS_PN = "146";
DRAWING = "@baseboard_fab2_lib.baseboard_fab2(sch_1):page82";
BODY = "SCONN288_H44441003","I64": #LOCATION = "J9U2" !CDS_LOCATION = "J9U2" #SEC = "2" !CDS_SEC = "2";
"DQS0N":   PN = "152"  !CDS_PN = "152";
"DQS0P":   PN = "153"  !CDS_PN = "153";
"DQS1N":   PN = "163"  !CDS_PN = "163";
"DQS1P":   PN = "164"  !CDS_PN = "164";
"DQS2N":   PN = "174"  !CDS_PN = "174";
"DQS2P":   PN = "175"  !CDS_PN = "175";
"DQS3N":   PN = "185"  !CDS_PN = "185";
"DQS3P":   PN = "186"  !CDS_PN = "186";
"DQS4N":   PN = "244"  !CDS_PN = "244";
"DQS4P":   PN = "245"  !CDS_PN = "245";
"DQS5N":   PN = "255"  !CDS_PN = "255";
"DQS5P":   PN = "256"  !CDS_PN = "256";
"DQS6N":   PN = "266"  !CDS_PN = "266";
"DQS6P":   PN = "267"  !CDS_PN = "267";
"DQS7N":   PN = "277"  !CDS_PN = "277";
"DQS7P":   PN = "278"  !CDS_PN = "278";
"DQS8N":   PN = "196"  !CDS_PN = "196";
"DQS8P":   PN = "197"  !CDS_PN = "197";
"DQS9N":   PN = "8"  !CDS_PN = "8";
"DQS9P":   PN = "7"  !CDS_PN = "7";
"DQS10N":   PN = "19"  !CDS_PN = "19";
"DQS10P":   PN = "18"  !CDS_PN = "18";
"DQS11N":   PN = "30"  !CDS_PN = "30";
"DQS11P":   PN = "29"  !CDS_PN = "29";
"DQS12N":   PN = "41"  !CDS_PN = "41";
"DQS12P":   PN = "40"  !CDS_PN = "40";
"DQS13N":   PN = "100"  !CDS_PN = "100";
"DQS13P":   PN = "99"  !CDS_PN = "99";
"DQS14N":   PN = "111"  !CDS_PN = "111";
"DQS14P":   PN = "110"  !CDS_PN = "110";
"DQS15N":   PN = "122"  !CDS_PN = "122";
"DQS15P":   PN = "121"  !CDS_PN = "121";
"DQS16N":   PN = "133"  !CDS_PN = "133";
"DQS16P":   PN = "132"  !CDS_PN = "132";
"DQS17N":   PN = "52"  !CDS_PN = "52";
"DQS17P":   PN = "51"  !CDS_PN = "51";
BODY = "SCONN288_H44441003","I171": #LOCATION = "J9U2" !CDS_LOCATION = "J9U2" #SEC = "4" !CDS_SEC = "4";
"12V<0>":   PN = "145"  !CDS_PN = "145";
"12V<1>":   PN = "1"  !CDS_PN = "1";
"VDD<0>":   PN = "236"  !CDS_PN = "236";
"VDD<1>":   PN = "233"  !CDS_PN = "233";
"VDD<2>":   PN = "231"  !CDS_PN = "231";
"VDD<3>":   PN = "229"  !CDS_PN = "229";
"VDD<4>":   PN = "226"  !CDS_PN = "226";
"VDD<5>":   PN = "223"  !CDS_PN = "223";
"VDD<6>":   PN = "220"  !CDS_PN = "220";
"VDD<7>":   PN = "217"  !CDS_PN = "217";
"VDD<8>":   PN = "215"  !CDS_PN = "215";
"VDD<9>":   PN = "212"  !CDS_PN = "212";
"VDD<10>":   PN = "209"  !CDS_PN = "209";
"VDD<11>":   PN = "206"  !CDS_PN = "206";
"VDD<12>":   PN = "204"  !CDS_PN = "204";
"VDD<13>":   PN = "92"  !CDS_PN = "92";
"VDD<14>":   PN = "90"  !CDS_PN = "90";
"VDD<15>":   PN = "88"  !CDS_PN = "88";
"VDD<16>":   PN = "85"  !CDS_PN = "85";
"VDD<17>":   PN = "83"  !CDS_PN = "83";
"VDD<18>":   PN = "80"  !CDS_PN = "80";
"VDD<19>":   PN = "76"  !CDS_PN = "76";
"VDD<20>":   PN = "73"  !CDS_PN = "73";
"VDD<21>":   PN = "70"  !CDS_PN = "70";
"VDD<22>":   PN = "67"  !CDS_PN = "67";
"VDD<23>":   PN = "64"  !CDS_PN = "64";
"VDD<24>":   PN = "61"  !CDS_PN = "61";
"VDD<25>":   PN = "59"  !CDS_PN = "59";
"VPP<0>":   PN = "287"  !CDS_PN = "287";
"VPP<1>":   PN = "286"  !CDS_PN = "286";
"VPP<2>":   PN = "288"  !CDS_PN = "288";
"VPP<3>":   PN = "143"  !CDS_PN = "143";
"VPP<4>":   PN = "142"  !CDS_PN = "142";
"VTT<0>":   PN = "221"  !CDS_PN = "221";
"VTT<1>":   PN = "77"  !CDS_PN = "77";
BODY = "CAP_A","I180": #LOCATION = "C1G19" !CDS_LOCATION = "C1G19" &SEC = "1" #&CDS_SEC = "1";
"A":   PN = "1"  !CDS_PN = "1";
"B":   PN = "2"  !CDS_PN = "2";
BODY = "SCONN288_H44441003","I187": #LOCATION = "J9U2" !CDS_LOCATION = "J9U2" #SEC = "1" !CDS_SEC = "1";
"A0":   PN = "79"  !CDS_PN = "79";
"A1":   PN = "72"  !CDS_PN = "72";
"A2":   PN = "216"  !CDS_PN = "216";
"A3":   PN = "71"  !CDS_PN = "71";
"A4":   PN = "214"  !CDS_PN = "214";
"A5":   PN = "213"  !CDS_PN = "213";
"A6":   PN = "69"  !CDS_PN = "69";
"A7":   PN = "211"  !CDS_PN = "211";
"A8":   PN = "68"  !CDS_PN = "68";
"A9":   PN = "66"  !CDS_PN = "66";
"A10":   PN = "225"  !CDS_PN = "225";
"A11":   PN = "210"  !CDS_PN = "210";
"A12":   PN = "65"  !CDS_PN = "65";
"A13":   PN = "232"  !CDS_PN = "232";
"A14_WE_N":   PN = "228"  !CDS_PN = "228";
"A15_CAS_N":   PN = "86"  !CDS_PN = "86";
"A16_RAS_N":   PN = "82"  !CDS_PN = "82";
"A17":   PN = "234"  !CDS_PN = "234";
"ACT_N":   PN = "62"  !CDS_PN = "62";
"ALERT_N":   PN = "208"  !CDS_PN = "208";
"BA<0>":   PN = "81"  !CDS_PN = "81";
"BA<1>":   PN = "224"  !CDS_PN = "224";
"BG<0>":   PN = "63"  !CDS_PN = "63";
"BG<1>":   PN = "207"  !CDS_PN = "207";
"C<2>":   PN = "235"  !CDS_PN = "235";
"CB<0>":   PN = "49"  !CDS_PN = "49";
"CB<1>":   PN = "194"  !CDS_PN = "194";
"CB<2>":   PN = "56"  !CDS_PN = "56";
"CB<3>":   PN = "201"  !CDS_PN = "201";
"CB<4>":   PN = "47"  !CDS_PN = "47";
"CB<5>":   PN = "192"  !CDS_PN = "192";
"CB<6>":   PN = "54"  !CDS_PN = "54";
"CB<7>":   PN = "199"  !CDS_PN = "199";
"CK0N":   PN = "75"  !CDS_PN = "75";
"CK0P":   PN = "74"  !CDS_PN = "74";
"CK1N":   PN = "219"  !CDS_PN = "219";
"CK1P":   PN = "218"  !CDS_PN = "218";
"CKE<0>":   PN = "60"  !CDS_PN = "60";
"CKE<1>":   PN = "203"  !CDS_PN = "203";
"DQ<0>":   PN = "5"  !CDS_PN = "5";
"DQ<1>":   PN = "150"  !CDS_PN = "150";
"DQ<2>":   PN = "12"  !CDS_PN = "12";
"DQ<3>":   PN = "157"  !CDS_PN = "157";
"DQ<4>":   PN = "3"  !CDS_PN = "3";
"DQ<5>":   PN = "148"  !CDS_PN = "148";
"DQ<6>":   PN = "10"  !CDS_PN = "10";
"DQ<7>":   PN = "155"  !CDS_PN = "155";
"DQ<8>":   PN = "16"  !CDS_PN = "16";
"DQ<9>":   PN = "161"  !CDS_PN = "161";
"DQ<10>":   PN = "23"  !CDS_PN = "23";
"DQ<11>":   PN = "168"  !CDS_PN = "168";
"DQ<12>":   PN = "14"  !CDS_PN = "14";
"DQ<13>":   PN = "159"  !CDS_PN = "159";
"DQ<14>":   PN = "21"  !CDS_PN = "21";
"DQ<15>":   PN = "166"  !CDS_PN = "166";
"DQ<16>":   PN = "27"  !CDS_PN = "27";
"DQ<17>":   PN = "172"  !CDS_PN = "172";
"DQ<18>":   PN = "34"  !CDS_PN = "34";
"DQ<19>":   PN = "179"  !CDS_PN = "179";
"DQ<20>":   PN = "25"  !CDS_PN = "25";
"DQ<21>":   PN = "170"  !CDS_PN = "170";
"DQ<22>":   PN = "32"  !CDS_PN = "32";
"DQ<23>":   PN = "177"  !CDS_PN = "177";
"DQ<24>":   PN = "38"  !CDS_PN = "38";
"DQ<25>":   PN = "183"  !CDS_PN = "183";
"DQ<26>":   PN = "45"  !CDS_PN = "45";
"DQ<27>":   PN = "190"  !CDS_PN = "190";
"DQ<28>":   PN = "36"  !CDS_PN = "36";
"DQ<29>":   PN = "181"  !CDS_PN = "181";
"DQ<30>":   PN = "43"  !CDS_PN = "43";
"DQ<31>":   PN = "188"  !CDS_PN = "188";
"DQ<32>":   PN = "97"  !CDS_PN = "97";
"DQ<33>":   PN = "242"  !CDS_PN = "242";
"DQ<34>":   PN = "104"  !CDS_PN = "104";
"DQ<35>":   PN = "249"  !CDS_PN = "249";
"DQ<36>":   PN = "95"  !CDS_PN = "95";
"DQ<37>":   PN = "240"  !CDS_PN = "240";
"DQ<38>":   PN = "102"  !CDS_PN = "102";
"DQ<39>":   PN = "247"  !CDS_PN = "247";
"DQ<40>":   PN = "108"  !CDS_PN = "108";
"DQ<41>":   PN = "253"  !CDS_PN = "253";
"DQ<42>":   PN = "115"  !CDS_PN = "115";
"DQ<43>":   PN = "260"  !CDS_PN = "260";
"DQ<44>":   PN = "106"  !CDS_PN = "106";
"DQ<45>":   PN = "251"  !CDS_PN = "251";
"DQ<46>":   PN = "113"  !CDS_PN = "113";
"DQ<47>":   PN = "258"  !CDS_PN = "258";
"DQ<48>":   PN = "119"  !CDS_PN = "119";
"DQ<49>":   PN = "264"  !CDS_PN = "264";
"DQ<50>":   PN = "126"  !CDS_PN = "126";
"DQ<51>":   PN = "271"  !CDS_PN = "271";
"DQ<52>":   PN = "117"  !CDS_PN = "117";
"DQ<53>":   PN = "262"  !CDS_PN = "262";
"DQ<54>":   PN = "124"  !CDS_PN = "124";
"DQ<55>":   PN = "269"  !CDS_PN = "269";
"DQ<56>":   PN = "130"  !CDS_PN = "130";
"DQ<57>":   PN = "275"  !CDS_PN = "275";
"DQ<58>":   PN = "137"  !CDS_PN = "137";
"DQ<59>":   PN = "282"  !CDS_PN = "282";
"DQ<60>":   PN = "128"  !CDS_PN = "128";
"DQ<61>":   PN = "273"  !CDS_PN = "273";
"DQ<62>":   PN = "135"  !CDS_PN = "135";
"DQ<63>":   PN = "280"  !CDS_PN = "280";
"EVENT_N":   PN = "78"  !CDS_PN = "78";
"ODT<0>":   PN = "87"  !CDS_PN = "87";
"ODT<1>":   PN = "91"  !CDS_PN = "91";
"PAR":   PN = "222"  !CDS_PN = "222";
"RESET_N":   PN = "58"  !CDS_PN = "58";
"RFU<0>":   PN = "205"  !CDS_PN = "205";
"RFU<1>":   PN = "227"  !CDS_PN = "227";
"RFU<2>":   PN = "144"  !CDS_PN = "144";
"S0_N":   PN = "84"  !CDS_PN = "84";
"S1_N":   PN = "89"  !CDS_PN = "89";
"S2_N_C<0>":   PN = "93"  !CDS_PN = "93";
"S3_N_C<1>":   PN = "237"  !CDS_PN = "237";
"SA<0>":   PN = "139"  !CDS_PN = "139";
"SA<1>":   PN = "140"  !CDS_PN = "140";
"SA<2>":   PN = "238"  !CDS_PN = "238";
"SAVE_N_NC":   PN = "230"  !CDS_PN = "230";
"SCL":   PN = "141"  !CDS_PN = "141";
"SDA":   PN = "285"  !CDS_PN = "285";
"VDDSPD":   PN = "284"  !CDS_PN = "284";
"VREFCA":   PN = "146"  !CDS_PN = "146";
BODY = "SCONN288_H44441003","I188": #LOCATION = "J9U2" !CDS_LOCATION = "J9U2" #SEC = "3" !CDS_SEC = "3";
"VSS<0>":   PN = "283"  !CDS_PN = "283";
"VSS<1>":   PN = "281"  !CDS_PN = "281";
"VSS<2>":   PN = "279"  !CDS_PN = "279";
"VSS<3>":   PN = "276"  !CDS_PN = "276";
"VSS<4>":   PN = "274"  !CDS_PN = "274";
"VSS<5>":   PN = "272"  !CDS_PN = "272";
"VSS<6>":   PN = "270"  !CDS_PN = "270";
"VSS<7>":   PN = "268"  !CDS_PN = "268";
"VSS<8>":   PN = "265"  !CDS_PN = "265";
"VSS<9>":   PN = "263"  !CDS_PN = "263";
"VSS<10>":   PN = "261"  !CDS_PN = "261";
"VSS<11>":   PN = "259"  !CDS_PN = "259";
"VSS<12>":   PN = "257"  !CDS_PN = "257";
"VSS<13>":   PN = "254"  !CDS_PN = "254";
"VSS<14>":   PN = "252"  !CDS_PN = "252";
"VSS<15>":   PN = "250"  !CDS_PN = "250";
"VSS<16>":   PN = "248"  !CDS_PN = "248";
"VSS<17>":   PN = "246"  !CDS_PN = "246";
"VSS<18>":   PN = "243"  !CDS_PN = "243";
"VSS<19>":   PN = "241"  !CDS_PN = "241";
"VSS<20>":   PN = "239"  !CDS_PN = "239";
"VSS<21>":   PN = "202"  !CDS_PN = "202";
"VSS<22>":   PN = "200"  !CDS_PN = "200";
"VSS<23>":   PN = "198"  !CDS_PN = "198";
"VSS<24>":   PN = "195"  !CDS_PN = "195";
"VSS<25>":   PN = "193"  !CDS_PN = "193";
"VSS<26>":   PN = "191"  !CDS_PN = "191";
"VSS<27>":   PN = "189"  !CDS_PN = "189";
"VSS<28>":   PN = "187"  !CDS_PN = "187";
"VSS<29>":   PN = "184"  !CDS_PN = "184";
"VSS<30>":   PN = "182"  !CDS_PN = "182";
"VSS<31>":   PN = "180"  !CDS_PN = "180";
"VSS<32>":   PN = "178"  !CDS_PN = "178";
"VSS<33>":   PN = "176"  !CDS_PN = "176";
"VSS<34>":   PN = "173"  !CDS_PN = "173";
"VSS<35>":   PN = "171"  !CDS_PN = "171";
"VSS<36>":   PN = "169"  !CDS_PN = "169";
"VSS<37>":   PN = "167"  !CDS_PN = "167";
"VSS<38>":   PN = "165"  !CDS_PN = "165";
"VSS<39>":   PN = "162"  !CDS_PN = "162";
"VSS<40>":   PN = "160"  !CDS_PN = "160";
"VSS<41>":   PN = "158"  !CDS_PN = "158";
"VSS<42>":   PN = "156"  !CDS_PN = "156";
"VSS<43>":   PN = "154"  !CDS_PN = "154";
"VSS<44>":   PN = "151"  !CDS_PN = "151";
"VSS<45>":   PN = "149"  !CDS_PN = "149";
"VSS<46>":   PN = "147"  !CDS_PN = "147";
"VSS<47>":   PN = "138"  !CDS_PN = "138";
"VSS<48>":   PN = "136"  !CDS_PN = "136";
"VSS<49>":   PN = "134"  !CDS_PN = "134";
"VSS<50>":   PN = "131"  !CDS_PN = "131";
"VSS<51>":   PN = "129"  !CDS_PN = "129";
"VSS<52>":   PN = "127"  !CDS_PN = "127";
"VSS<53>":   PN = "125"  !CDS_PN = "125";
"VSS<54>":   PN = "123"  !CDS_PN = "123";
"VSS<55>":   PN = "120"  !CDS_PN = "120";
"VSS<56>":   PN = "118"  !CDS_PN = "118";
"VSS<57>":   PN = "116"  !CDS_PN = "116";
"VSS<58>":   PN = "114"  !CDS_PN = "114";
"VSS<59>":   PN = "112"  !CDS_PN = "112";
"VSS<60>":   PN = "109"  !CDS_PN = "109";
"VSS<61>":   PN = "107"  !CDS_PN = "107";
"VSS<62>":   PN = "105"  !CDS_PN = "105";
"VSS<63>":   PN = "103"  !CDS_PN = "103";
"VSS<64>":   PN = "101"  !CDS_PN = "101";
"VSS<65>":   PN = "98"  !CDS_PN = "98";
"VSS<66>":   PN = "96"  !CDS_PN = "96";
"VSS<67>":   PN = "94"  !CDS_PN = "94";
"VSS<68>":   PN = "57"  !CDS_PN = "57";
"VSS<69>":   PN = "55"  !CDS_PN = "55";
"VSS<70>":   PN = "53"  !CDS_PN = "53";
"VSS<71>":   PN = "50"  !CDS_PN = "50";
"VSS<72>":   PN = "48"  !CDS_PN = "48";
"VSS<73>":   PN = "46"  !CDS_PN = "46";
"VSS<74>":   PN = "44"  !CDS_PN = "44";
"VSS<75>":   PN = "42"  !CDS_PN = "42";
"VSS<76>":   PN = "39"  !CDS_PN = "39";
"VSS<77>":   PN = "37"  !CDS_PN = "37";
"VSS<78>":   PN = "35"  !CDS_PN = "35";
"VSS<79>":   PN = "33"  !CDS_PN = "33";
"VSS<80>":   PN = "31"  !CDS_PN = "31";
"VSS<81>":   PN = "28"  !CDS_PN = "28";
"VSS<82>":   PN = "26"  !CDS_PN = "26";
"VSS<83>":   PN = "24"  !CDS_PN = "24";
"VSS<84>":   PN = "22"  !CDS_PN = "22";
"VSS<85>":   PN = "20"  !CDS_PN = "20";
"VSS<86>":   PN = "17"  !CDS_PN = "17";
"VSS<87>":   PN = "15"  !CDS_PN = "15";
"VSS<88>":   PN = "13"  !CDS_PN = "13";
"VSS<89>":   PN = "11"  !CDS_PN = "11";
"VSS<90>":   PN = "9"  !CDS_PN = "9";
"VSS<91>":   PN = "6"  !CDS_PN = "6";
"VSS<92>":   PN = "4"  !CDS_PN = "4";
"VSS<93>":   PN = "2"  !CDS_PN = "2";
DRAWING = "@baseboard_fab2_lib.baseboard_fab2(sch_1):page83";
BODY = "SCONN288_H44441004","I43": #LOCATION = "J1B1" !CDS_LOCATION = "J1B1" #SEC = "3" !CDS_SEC = "3";
"VSS<0>":   PN = "283"  !CDS_PN = "283";
"VSS<1>":   PN = "281"  !CDS_PN = "281";
"VSS<2>":   PN = "279"  !CDS_PN = "279";
"VSS<3>":   PN = "276"  !CDS_PN = "276";
"VSS<4>":   PN = "274"  !CDS_PN = "274";
"VSS<5>":   PN = "272"  !CDS_PN = "272";
"VSS<6>":   PN = "270"  !CDS_PN = "270";
"VSS<7>":   PN = "268"  !CDS_PN = "268";
"VSS<8>":   PN = "265"  !CDS_PN = "265";
"VSS<9>":   PN = "263"  !CDS_PN = "263";
"VSS<10>":   PN = "261"  !CDS_PN = "261";
"VSS<11>":   PN = "259"  !CDS_PN = "259";
"VSS<12>":   PN = "257"  !CDS_PN = "257";
"VSS<13>":   PN = "254"  !CDS_PN = "254";
"VSS<14>":   PN = "252"  !CDS_PN = "252";
"VSS<15>":   PN = "250"  !CDS_PN = "250";
"VSS<16>":   PN = "248"  !CDS_PN = "248";
"VSS<17>":   PN = "246"  !CDS_PN = "246";
"VSS<18>":   PN = "243"  !CDS_PN = "243";
"VSS<19>":   PN = "241"  !CDS_PN = "241";
"VSS<20>":   PN = "239"  !CDS_PN = "239";
"VSS<21>":   PN = "202"  !CDS_PN = "202";
"VSS<22>":   PN = "200"  !CDS_PN = "200";
"VSS<23>":   PN = "198"  !CDS_PN = "198";
"VSS<24>":   PN = "195"  !CDS_PN = "195";
"VSS<25>":   PN = "193"  !CDS_PN = "193";
"VSS<26>":   PN = "191"  !CDS_PN = "191";
"VSS<27>":   PN = "189"  !CDS_PN = "189";
"VSS<28>":   PN = "187"  !CDS_PN = "187";
"VSS<29>":   PN = "184"  !CDS_PN = "184";
"VSS<30>":   PN = "182"  !CDS_PN = "182";
"VSS<31>":   PN = "180"  !CDS_PN = "180";
"VSS<32>":   PN = "178"  !CDS_PN = "178";
"VSS<33>":   PN = "176"  !CDS_PN = "176";
"VSS<34>":   PN = "173"  !CDS_PN = "173";
"VSS<35>":   PN = "171"  !CDS_PN = "171";
"VSS<36>":   PN = "169"  !CDS_PN = "169";
"VSS<37>":   PN = "167"  !CDS_PN = "167";
"VSS<38>":   PN = "165"  !CDS_PN = "165";
"VSS<39>":   PN = "162"  !CDS_PN = "162";
"VSS<40>":   PN = "160"  !CDS_PN = "160";
"VSS<41>":   PN = "158"  !CDS_PN = "158";
"VSS<42>":   PN = "156"  !CDS_PN = "156";
"VSS<43>":   PN = "154"  !CDS_PN = "154";
"VSS<44>":   PN = "151"  !CDS_PN = "151";
"VSS<45>":   PN = "149"  !CDS_PN = "149";
"VSS<46>":   PN = "147"  !CDS_PN = "147";
"VSS<47>":   PN = "138"  !CDS_PN = "138";
"VSS<48>":   PN = "136"  !CDS_PN = "136";
"VSS<49>":   PN = "134"  !CDS_PN = "134";
"VSS<50>":   PN = "131"  !CDS_PN = "131";
"VSS<51>":   PN = "129"  !CDS_PN = "129";
"VSS<52>":   PN = "127"  !CDS_PN = "127";
"VSS<53>":   PN = "125"  !CDS_PN = "125";
"VSS<54>":   PN = "123"  !CDS_PN = "123";
"VSS<55>":   PN = "120"  !CDS_PN = "120";
"VSS<56>":   PN = "118"  !CDS_PN = "118";
"VSS<57>":   PN = "116"  !CDS_PN = "116";
"VSS<58>":   PN = "114"  !CDS_PN = "114";
"VSS<59>":   PN = "112"  !CDS_PN = "112";
"VSS<60>":   PN = "109"  !CDS_PN = "109";
"VSS<61>":   PN = "107"  !CDS_PN = "107";
"VSS<62>":   PN = "105"  !CDS_PN = "105";
"VSS<63>":   PN = "103"  !CDS_PN = "103";
"VSS<64>":   PN = "101"  !CDS_PN = "101";
"VSS<65>":   PN = "98"  !CDS_PN = "98";
"VSS<66>":   PN = "96"  !CDS_PN = "96";
"VSS<67>":   PN = "94"  !CDS_PN = "94";
"VSS<68>":   PN = "57"  !CDS_PN = "57";
"VSS<69>":   PN = "55"  !CDS_PN = "55";
"VSS<70>":   PN = "53"  !CDS_PN = "53";
"VSS<71>":   PN = "50"  !CDS_PN = "50";
"VSS<72>":   PN = "48"  !CDS_PN = "48";
"VSS<73>":   PN = "46"  !CDS_PN = "46";
"VSS<74>":   PN = "44"  !CDS_PN = "44";
"VSS<75>":   PN = "42"  !CDS_PN = "42";
"VSS<76>":   PN = "39"  !CDS_PN = "39";
"VSS<77>":   PN = "37"  !CDS_PN = "37";
"VSS<78>":   PN = "35"  !CDS_PN = "35";
"VSS<79>":   PN = "33"  !CDS_PN = "33";
"VSS<80>":   PN = "31"  !CDS_PN = "31";
"VSS<81>":   PN = "28"  !CDS_PN = "28";
"VSS<82>":   PN = "26"  !CDS_PN = "26";
"VSS<83>":   PN = "24"  !CDS_PN = "24";
"VSS<84>":   PN = "22"  !CDS_PN = "22";
"VSS<85>":   PN = "20"  !CDS_PN = "20";
"VSS<86>":   PN = "17"  !CDS_PN = "17";
"VSS<87>":   PN = "15"  !CDS_PN = "15";
"VSS<88>":   PN = "13"  !CDS_PN = "13";
"VSS<89>":   PN = "11"  !CDS_PN = "11";
"VSS<90>":   PN = "9"  !CDS_PN = "9";
"VSS<91>":   PN = "6"  !CDS_PN = "6";
"VSS<92>":   PN = "4"  !CDS_PN = "4";
"VSS<93>":   PN = "2"  !CDS_PN = "2";
BODY = "SCONN288_H44441004","I66": #LOCATION = "J1B1" !CDS_LOCATION = "J1B1" #SEC = "2" !CDS_SEC = "2";
"DQS0N":   PN = "152"  !CDS_PN = "152";
"DQS0P":   PN = "153"  !CDS_PN = "153";
"DQS1N":   PN = "163"  !CDS_PN = "163";
"DQS1P":   PN = "164"  !CDS_PN = "164";
"DQS2N":   PN = "174"  !CDS_PN = "174";
"DQS2P":   PN = "175"  !CDS_PN = "175";
"DQS3N":   PN = "185"  !CDS_PN = "185";
"DQS3P":   PN = "186"  !CDS_PN = "186";
"DQS4N":   PN = "244"  !CDS_PN = "244";
"DQS4P":   PN = "245"  !CDS_PN = "245";
"DQS5N":   PN = "255"  !CDS_PN = "255";
"DQS5P":   PN = "256"  !CDS_PN = "256";
"DQS6N":   PN = "266"  !CDS_PN = "266";
"DQS6P":   PN = "267"  !CDS_PN = "267";
"DQS7N":   PN = "277"  !CDS_PN = "277";
"DQS7P":   PN = "278"  !CDS_PN = "278";
"DQS8N":   PN = "196"  !CDS_PN = "196";
"DQS8P":   PN = "197"  !CDS_PN = "197";
"DQS9N":   PN = "8"  !CDS_PN = "8";
"DQS9P":   PN = "7"  !CDS_PN = "7";
"DQS10N":   PN = "19"  !CDS_PN = "19";
"DQS10P":   PN = "18"  !CDS_PN = "18";
"DQS11N":   PN = "30"  !CDS_PN = "30";
"DQS11P":   PN = "29"  !CDS_PN = "29";
"DQS12N":   PN = "41"  !CDS_PN = "41";
"DQS12P":   PN = "40"  !CDS_PN = "40";
"DQS13N":   PN = "100"  !CDS_PN = "100";
"DQS13P":   PN = "99"  !CDS_PN = "99";
"DQS14N":   PN = "111"  !CDS_PN = "111";
"DQS14P":   PN = "110"  !CDS_PN = "110";
"DQS15N":   PN = "122"  !CDS_PN = "122";
"DQS15P":   PN = "121"  !CDS_PN = "121";
"DQS16N":   PN = "133"  !CDS_PN = "133";
"DQS16P":   PN = "132"  !CDS_PN = "132";
"DQS17N":   PN = "52"  !CDS_PN = "52";
"DQS17P":   PN = "51"  !CDS_PN = "51";
BODY = "SCONN288_H44441004","I111": #LOCATION = "J1B1" !CDS_LOCATION = "J1B1" #SEC = "1" !CDS_SEC = "1";
"A0":   PN = "79"  !CDS_PN = "79";
"A1":   PN = "72"  !CDS_PN = "72";
"A2":   PN = "216"  !CDS_PN = "216";
"A3":   PN = "71"  !CDS_PN = "71";
"A4":   PN = "214"  !CDS_PN = "214";
"A5":   PN = "213"  !CDS_PN = "213";
"A6":   PN = "69"  !CDS_PN = "69";
"A7":   PN = "211"  !CDS_PN = "211";
"A8":   PN = "68"  !CDS_PN = "68";
"A9":   PN = "66"  !CDS_PN = "66";
"A10":   PN = "225"  !CDS_PN = "225";
"A11":   PN = "210"  !CDS_PN = "210";
"A12":   PN = "65"  !CDS_PN = "65";
"A13":   PN = "232"  !CDS_PN = "232";
"A14_WE_N":   PN = "228"  !CDS_PN = "228";
"A15_CAS_N":   PN = "86"  !CDS_PN = "86";
"A16_RAS_N":   PN = "82"  !CDS_PN = "82";
"A17":   PN = "234"  !CDS_PN = "234";
"ACT_N":   PN = "62"  !CDS_PN = "62";
"ALERT_N":   PN = "208"  !CDS_PN = "208";
"BA<0>":   PN = "81"  !CDS_PN = "81";
"BA<1>":   PN = "224"  !CDS_PN = "224";
"BG<0>":   PN = "63"  !CDS_PN = "63";
"BG<1>":   PN = "207"  !CDS_PN = "207";
"C<2>":   PN = "235"  !CDS_PN = "235";
"CB<0>":   PN = "49"  !CDS_PN = "49";
"CB<1>":   PN = "194"  !CDS_PN = "194";
"CB<2>":   PN = "56"  !CDS_PN = "56";
"CB<3>":   PN = "201"  !CDS_PN = "201";
"CB<4>":   PN = "47"  !CDS_PN = "47";
"CB<5>":   PN = "192"  !CDS_PN = "192";
"CB<6>":   PN = "54"  !CDS_PN = "54";
"CB<7>":   PN = "199"  !CDS_PN = "199";
"CK0N":   PN = "75"  !CDS_PN = "75";
"CK0P":   PN = "74"  !CDS_PN = "74";
"CK1N":   PN = "219"  !CDS_PN = "219";
"CK1P":   PN = "218"  !CDS_PN = "218";
"CKE<0>":   PN = "60"  !CDS_PN = "60";
"CKE<1>":   PN = "203"  !CDS_PN = "203";
"DQ<0>":   PN = "5"  !CDS_PN = "5";
"DQ<1>":   PN = "150"  !CDS_PN = "150";
"DQ<2>":   PN = "12"  !CDS_PN = "12";
"DQ<3>":   PN = "157"  !CDS_PN = "157";
"DQ<4>":   PN = "3"  !CDS_PN = "3";
"DQ<5>":   PN = "148"  !CDS_PN = "148";
"DQ<6>":   PN = "10"  !CDS_PN = "10";
"DQ<7>":   PN = "155"  !CDS_PN = "155";
"DQ<8>":   PN = "16"  !CDS_PN = "16";
"DQ<9>":   PN = "161"  !CDS_PN = "161";
"DQ<10>":   PN = "23"  !CDS_PN = "23";
"DQ<11>":   PN = "168"  !CDS_PN = "168";
"DQ<12>":   PN = "14"  !CDS_PN = "14";
"DQ<13>":   PN = "159"  !CDS_PN = "159";
"DQ<14>":   PN = "21"  !CDS_PN = "21";
"DQ<15>":   PN = "166"  !CDS_PN = "166";
"DQ<16>":   PN = "27"  !CDS_PN = "27";
"DQ<17>":   PN = "172"  !CDS_PN = "172";
"DQ<18>":   PN = "34"  !CDS_PN = "34";
"DQ<19>":   PN = "179"  !CDS_PN = "179";
"DQ<20>":   PN = "25"  !CDS_PN = "25";
"DQ<21>":   PN = "170"  !CDS_PN = "170";
"DQ<22>":   PN = "32"  !CDS_PN = "32";
"DQ<23>":   PN = "177"  !CDS_PN = "177";
"DQ<24>":   PN = "38"  !CDS_PN = "38";
"DQ<25>":   PN = "183"  !CDS_PN = "183";
"DQ<26>":   PN = "45"  !CDS_PN = "45";
"DQ<27>":   PN = "190"  !CDS_PN = "190";
"DQ<28>":   PN = "36"  !CDS_PN = "36";
"DQ<29>":   PN = "181"  !CDS_PN = "181";
"DQ<30>":   PN = "43"  !CDS_PN = "43";
"DQ<31>":   PN = "188"  !CDS_PN = "188";
"DQ<32>":   PN = "97"  !CDS_PN = "97";
"DQ<33>":   PN = "242"  !CDS_PN = "242";
"DQ<34>":   PN = "104"  !CDS_PN = "104";
"DQ<35>":   PN = "249"  !CDS_PN = "249";
"DQ<36>":   PN = "95"  !CDS_PN = "95";
"DQ<37>":   PN = "240"  !CDS_PN = "240";
"DQ<38>":   PN = "102"  !CDS_PN = "102";
"DQ<39>":   PN = "247"  !CDS_PN = "247";
"DQ<40>":   PN = "108"  !CDS_PN = "108";
"DQ<41>":   PN = "253"  !CDS_PN = "253";
"DQ<42>":   PN = "115"  !CDS_PN = "115";
"DQ<43>":   PN = "260"  !CDS_PN = "260";
"DQ<44>":   PN = "106"  !CDS_PN = "106";
"DQ<45>":   PN = "251"  !CDS_PN = "251";
"DQ<46>":   PN = "113"  !CDS_PN = "113";
"DQ<47>":   PN = "258"  !CDS_PN = "258";
"DQ<48>":   PN = "119"  !CDS_PN = "119";
"DQ<49>":   PN = "264"  !CDS_PN = "264";
"DQ<50>":   PN = "126"  !CDS_PN = "126";
"DQ<51>":   PN = "271"  !CDS_PN = "271";
"DQ<52>":   PN = "117"  !CDS_PN = "117";
"DQ<53>":   PN = "262"  !CDS_PN = "262";
"DQ<54>":   PN = "124"  !CDS_PN = "124";
"DQ<55>":   PN = "269"  !CDS_PN = "269";
"DQ<56>":   PN = "130"  !CDS_PN = "130";
"DQ<57>":   PN = "275"  !CDS_PN = "275";
"DQ<58>":   PN = "137"  !CDS_PN = "137";
"DQ<59>":   PN = "282"  !CDS_PN = "282";
"DQ<60>":   PN = "128"  !CDS_PN = "128";
"DQ<61>":   PN = "273"  !CDS_PN = "273";
"DQ<62>":   PN = "135"  !CDS_PN = "135";
"DQ<63>":   PN = "280"  !CDS_PN = "280";
"EVENT_N":   PN = "78"  !CDS_PN = "78";
"ODT<0>":   PN = "87"  !CDS_PN = "87";
"ODT<1>":   PN = "91"  !CDS_PN = "91";
"PAR":   PN = "222"  !CDS_PN = "222";
"RESET_N":   PN = "58"  !CDS_PN = "58";
"RFU<0>":   PN = "205"  !CDS_PN = "205";
"RFU<1>":   PN = "227"  !CDS_PN = "227";
"RFU<2>":   PN = "144"  !CDS_PN = "144";
"S0_N":   PN = "84"  !CDS_PN = "84";
"S1_N":   PN = "89"  !CDS_PN = "89";
"S2_N_C<0>":   PN = "93"  !CDS_PN = "93";
"S3_N_C<1>":   PN = "237"  !CDS_PN = "237";
"SA<0>":   PN = "139"  !CDS_PN = "139";
"SA<1>":   PN = "140"  !CDS_PN = "140";
"SA<2>":   PN = "238"  !CDS_PN = "238";
"SAVE_N_NC":   PN = "230"  !CDS_PN = "230";
"SCL":   PN = "141"  !CDS_PN = "141";
"SDA":   PN = "285"  !CDS_PN = "285";
"VDDSPD":   PN = "284"  !CDS_PN = "284";
"VREFCA":   PN = "146"  !CDS_PN = "146";
BODY = "SCONN288_H44441004","I167": #LOCATION = "J1B1" !CDS_LOCATION = "J1B1" #SEC = "4" !CDS_SEC = "4";
"12V<0>":   PN = "145"  !CDS_PN = "145";
"12V<1>":   PN = "1"  !CDS_PN = "1";
"VDD<0>":   PN = "236"  !CDS_PN = "236";
"VDD<1>":   PN = "233"  !CDS_PN = "233";
"VDD<2>":   PN = "231"  !CDS_PN = "231";
"VDD<3>":   PN = "229"  !CDS_PN = "229";
"VDD<4>":   PN = "226"  !CDS_PN = "226";
"VDD<5>":   PN = "223"  !CDS_PN = "223";
"VDD<6>":   PN = "220"  !CDS_PN = "220";
"VDD<7>":   PN = "217"  !CDS_PN = "217";
"VDD<8>":   PN = "215"  !CDS_PN = "215";
"VDD<9>":   PN = "212"  !CDS_PN = "212";
"VDD<10>":   PN = "209"  !CDS_PN = "209";
"VDD<11>":   PN = "206"  !CDS_PN = "206";
"VDD<12>":   PN = "204"  !CDS_PN = "204";
"VDD<13>":   PN = "92"  !CDS_PN = "92";
"VDD<14>":   PN = "90"  !CDS_PN = "90";
"VDD<15>":   PN = "88"  !CDS_PN = "88";
"VDD<16>":   PN = "85"  !CDS_PN = "85";
"VDD<17>":   PN = "83"  !CDS_PN = "83";
"VDD<18>":   PN = "80"  !CDS_PN = "80";
"VDD<19>":   PN = "76"  !CDS_PN = "76";
"VDD<20>":   PN = "73"  !CDS_PN = "73";
"VDD<21>":   PN = "70"  !CDS_PN = "70";
"VDD<22>":   PN = "67"  !CDS_PN = "67";
"VDD<23>":   PN = "64"  !CDS_PN = "64";
"VDD<24>":   PN = "61"  !CDS_PN = "61";
"VDD<25>":   PN = "59"  !CDS_PN = "59";
"VPP<0>":   PN = "287"  !CDS_PN = "287";
"VPP<1>":   PN = "286"  !CDS_PN = "286";
"VPP<2>":   PN = "288"  !CDS_PN = "288";
"VPP<3>":   PN = "143"  !CDS_PN = "143";
"VPP<4>":   PN = "142"  !CDS_PN = "142";
"VTT<0>":   PN = "221"  !CDS_PN = "221";
"VTT<1>":   PN = "77"  !CDS_PN = "77";
BODY = "CAP_A","I176": #LOCATION = "C1B9" !CDS_LOCATION = "C1B9" &SEC = "1" #&CDS_SEC = "1";
"A":   PN = "1"  !CDS_PN = "1";
"B":   PN = "2"  !CDS_PN = "2";
DRAWING = "@baseboard_fab2_lib.baseboard_fab2(sch_1):page84";
BODY = "CAP_A","I4": #LOCATION = "C9M1" !CDS_LOCATION = "C9M1" &SEC = "1" #&CDS_SEC = "1";
"A":   PN = "1"  !CDS_PN = "1";
"B":   PN = "2"  !CDS_PN = "2";
BODY = "SCONN288_H44441003","I14": #LOCATION = "J9M1" !CDS_LOCATION = "J9M1" #SEC = "1" !CDS_SEC = "1";
"A0":   PN = "79"  !CDS_PN = "79";
"A1":   PN = "72"  !CDS_PN = "72";
"A2":   PN = "216"  !CDS_PN = "216";
"A3":   PN = "71"  !CDS_PN = "71";
"A4":   PN = "214"  !CDS_PN = "214";
"A5":   PN = "213"  !CDS_PN = "213";
"A6":   PN = "69"  !CDS_PN = "69";
"A7":   PN = "211"  !CDS_PN = "211";
"A8":   PN = "68"  !CDS_PN = "68";
"A9":   PN = "66"  !CDS_PN = "66";
"A10":   PN = "225"  !CDS_PN = "225";
"A11":   PN = "210"  !CDS_PN = "210";
"A12":   PN = "65"  !CDS_PN = "65";
"A13":   PN = "232"  !CDS_PN = "232";
"A14_WE_N":   PN = "228"  !CDS_PN = "228";
"A15_CAS_N":   PN = "86"  !CDS_PN = "86";
"A16_RAS_N":   PN = "82"  !CDS_PN = "82";
"A17":   PN = "234"  !CDS_PN = "234";
"ACT_N":   PN = "62"  !CDS_PN = "62";
"ALERT_N":   PN = "208"  !CDS_PN = "208";
"BA<0>":   PN = "81"  !CDS_PN = "81";
"BA<1>":   PN = "224"  !CDS_PN = "224";
"BG<0>":   PN = "63"  !CDS_PN = "63";
"BG<1>":   PN = "207"  !CDS_PN = "207";
"C<2>":   PN = "235"  !CDS_PN = "235";
"CB<0>":   PN = "49"  !CDS_PN = "49";
"CB<1>":   PN = "194"  !CDS_PN = "194";
"CB<2>":   PN = "56"  !CDS_PN = "56";
"CB<3>":   PN = "201"  !CDS_PN = "201";
"CB<4>":   PN = "47"  !CDS_PN = "47";
"CB<5>":   PN = "192"  !CDS_PN = "192";
"CB<6>":   PN = "54"  !CDS_PN = "54";
"CB<7>":   PN = "199"  !CDS_PN = "199";
"CK0N":   PN = "75"  !CDS_PN = "75";
"CK0P":   PN = "74"  !CDS_PN = "74";
"CK1N":   PN = "219"  !CDS_PN = "219";
"CK1P":   PN = "218"  !CDS_PN = "218";
"CKE<0>":   PN = "60"  !CDS_PN = "60";
"CKE<1>":   PN = "203"  !CDS_PN = "203";
"DQ<0>":   PN = "5"  !CDS_PN = "5";
"DQ<1>":   PN = "150"  !CDS_PN = "150";
"DQ<2>":   PN = "12"  !CDS_PN = "12";
"DQ<3>":   PN = "157"  !CDS_PN = "157";
"DQ<4>":   PN = "3"  !CDS_PN = "3";
"DQ<5>":   PN = "148"  !CDS_PN = "148";
"DQ<6>":   PN = "10"  !CDS_PN = "10";
"DQ<7>":   PN = "155"  !CDS_PN = "155";
"DQ<8>":   PN = "16"  !CDS_PN = "16";
"DQ<9>":   PN = "161"  !CDS_PN = "161";
"DQ<10>":   PN = "23"  !CDS_PN = "23";
"DQ<11>":   PN = "168"  !CDS_PN = "168";
"DQ<12>":   PN = "14"  !CDS_PN = "14";
"DQ<13>":   PN = "159"  !CDS_PN = "159";
"DQ<14>":   PN = "21"  !CDS_PN = "21";
"DQ<15>":   PN = "166"  !CDS_PN = "166";
"DQ<16>":   PN = "27"  !CDS_PN = "27";
"DQ<17>":   PN = "172"  !CDS_PN = "172";
"DQ<18>":   PN = "34"  !CDS_PN = "34";
"DQ<19>":   PN = "179"  !CDS_PN = "179";
"DQ<20>":   PN = "25"  !CDS_PN = "25";
"DQ<21>":   PN = "170"  !CDS_PN = "170";
"DQ<22>":   PN = "32"  !CDS_PN = "32";
"DQ<23>":   PN = "177"  !CDS_PN = "177";
"DQ<24>":   PN = "38"  !CDS_PN = "38";
"DQ<25>":   PN = "183"  !CDS_PN = "183";
"DQ<26>":   PN = "45"  !CDS_PN = "45";
"DQ<27>":   PN = "190"  !CDS_PN = "190";
"DQ<28>":   PN = "36"  !CDS_PN = "36";
"DQ<29>":   PN = "181"  !CDS_PN = "181";
"DQ<30>":   PN = "43"  !CDS_PN = "43";
"DQ<31>":   PN = "188"  !CDS_PN = "188";
"DQ<32>":   PN = "97"  !CDS_PN = "97";
"DQ<33>":   PN = "242"  !CDS_PN = "242";
"DQ<34>":   PN = "104"  !CDS_PN = "104";
"DQ<35>":   PN = "249"  !CDS_PN = "249";
"DQ<36>":   PN = "95"  !CDS_PN = "95";
"DQ<37>":   PN = "240"  !CDS_PN = "240";
"DQ<38>":   PN = "102"  !CDS_PN = "102";
"DQ<39>":   PN = "247"  !CDS_PN = "247";
"DQ<40>":   PN = "108"  !CDS_PN = "108";
"DQ<41>":   PN = "253"  !CDS_PN = "253";
"DQ<42>":   PN = "115"  !CDS_PN = "115";
"DQ<43>":   PN = "260"  !CDS_PN = "260";
"DQ<44>":   PN = "106"  !CDS_PN = "106";
"DQ<45>":   PN = "251"  !CDS_PN = "251";
"DQ<46>":   PN = "113"  !CDS_PN = "113";
"DQ<47>":   PN = "258"  !CDS_PN = "258";
"DQ<48>":   PN = "119"  !CDS_PN = "119";
"DQ<49>":   PN = "264"  !CDS_PN = "264";
"DQ<50>":   PN = "126"  !CDS_PN = "126";
"DQ<51>":   PN = "271"  !CDS_PN = "271";
"DQ<52>":   PN = "117"  !CDS_PN = "117";
"DQ<53>":   PN = "262"  !CDS_PN = "262";
"DQ<54>":   PN = "124"  !CDS_PN = "124";
"DQ<55>":   PN = "269"  !CDS_PN = "269";
"DQ<56>":   PN = "130"  !CDS_PN = "130";
"DQ<57>":   PN = "275"  !CDS_PN = "275";
"DQ<58>":   PN = "137"  !CDS_PN = "137";
"DQ<59>":   PN = "282"  !CDS_PN = "282";
"DQ<60>":   PN = "128"  !CDS_PN = "128";
"DQ<61>":   PN = "273"  !CDS_PN = "273";
"DQ<62>":   PN = "135"  !CDS_PN = "135";
"DQ<63>":   PN = "280"  !CDS_PN = "280";
"EVENT_N":   PN = "78"  !CDS_PN = "78";
"ODT<0>":   PN = "87"  !CDS_PN = "87";
"ODT<1>":   PN = "91"  !CDS_PN = "91";
"PAR":   PN = "222"  !CDS_PN = "222";
"RESET_N":   PN = "58"  !CDS_PN = "58";
"RFU<0>":   PN = "205"  !CDS_PN = "205";
"RFU<1>":   PN = "227"  !CDS_PN = "227";
"RFU<2>":   PN = "144"  !CDS_PN = "144";
"S0_N":   PN = "84"  !CDS_PN = "84";
"S1_N":   PN = "89"  !CDS_PN = "89";
"S2_N_C<0>":   PN = "93"  !CDS_PN = "93";
"S3_N_C<1>":   PN = "237"  !CDS_PN = "237";
"SA<0>":   PN = "139"  !CDS_PN = "139";
"SA<1>":   PN = "140"  !CDS_PN = "140";
"SA<2>":   PN = "238"  !CDS_PN = "238";
"SAVE_N_NC":   PN = "230"  !CDS_PN = "230";
"SCL":   PN = "141"  !CDS_PN = "141";
"SDA":   PN = "285"  !CDS_PN = "285";
"VDDSPD":   PN = "284"  !CDS_PN = "284";
"VREFCA":   PN = "146"  !CDS_PN = "146";
BODY = "SCONN288_H44441003","I57": #LOCATION = "J9M1" !CDS_LOCATION = "J9M1" #SEC = "4" !CDS_SEC = "4";
"12V<0>":   PN = "145"  !CDS_PN = "145";
"12V<1>":   PN = "1"  !CDS_PN = "1";
"VDD<0>":   PN = "236"  !CDS_PN = "236";
"VDD<1>":   PN = "233"  !CDS_PN = "233";
"VDD<2>":   PN = "231"  !CDS_PN = "231";
"VDD<3>":   PN = "229"  !CDS_PN = "229";
"VDD<4>":   PN = "226"  !CDS_PN = "226";
"VDD<5>":   PN = "223"  !CDS_PN = "223";
"VDD<6>":   PN = "220"  !CDS_PN = "220";
"VDD<7>":   PN = "217"  !CDS_PN = "217";
"VDD<8>":   PN = "215"  !CDS_PN = "215";
"VDD<9>":   PN = "212"  !CDS_PN = "212";
"VDD<10>":   PN = "209"  !CDS_PN = "209";
"VDD<11>":   PN = "206"  !CDS_PN = "206";
"VDD<12>":   PN = "204"  !CDS_PN = "204";
"VDD<13>":   PN = "92"  !CDS_PN = "92";
"VDD<14>":   PN = "90"  !CDS_PN = "90";
"VDD<15>":   PN = "88"  !CDS_PN = "88";
"VDD<16>":   PN = "85"  !CDS_PN = "85";
"VDD<17>":   PN = "83"  !CDS_PN = "83";
"VDD<18>":   PN = "80"  !CDS_PN = "80";
"VDD<19>":   PN = "76"  !CDS_PN = "76";
"VDD<20>":   PN = "73"  !CDS_PN = "73";
"VDD<21>":   PN = "70"  !CDS_PN = "70";
"VDD<22>":   PN = "67"  !CDS_PN = "67";
"VDD<23>":   PN = "64"  !CDS_PN = "64";
"VDD<24>":   PN = "61"  !CDS_PN = "61";
"VDD<25>":   PN = "59"  !CDS_PN = "59";
"VPP<0>":   PN = "287"  !CDS_PN = "287";
"VPP<1>":   PN = "286"  !CDS_PN = "286";
"VPP<2>":   PN = "288"  !CDS_PN = "288";
"VPP<3>":   PN = "143"  !CDS_PN = "143";
"VPP<4>":   PN = "142"  !CDS_PN = "142";
"VTT<0>":   PN = "221"  !CDS_PN = "221";
"VTT<1>":   PN = "77"  !CDS_PN = "77";
BODY = "SCONN288_H44441003","I102": #LOCATION = "J9M1" !CDS_LOCATION = "J9M1" #SEC = "2" !CDS_SEC = "2";
"DQS0N":   PN = "152"  !CDS_PN = "152";
"DQS0P":   PN = "153"  !CDS_PN = "153";
"DQS1N":   PN = "163"  !CDS_PN = "163";
"DQS1P":   PN = "164"  !CDS_PN = "164";
"DQS2N":   PN = "174"  !CDS_PN = "174";
"DQS2P":   PN = "175"  !CDS_PN = "175";
"DQS3N":   PN = "185"  !CDS_PN = "185";
"DQS3P":   PN = "186"  !CDS_PN = "186";
"DQS4N":   PN = "244"  !CDS_PN = "244";
"DQS4P":   PN = "245"  !CDS_PN = "245";
"DQS5N":   PN = "255"  !CDS_PN = "255";
"DQS5P":   PN = "256"  !CDS_PN = "256";
"DQS6N":   PN = "266"  !CDS_PN = "266";
"DQS6P":   PN = "267"  !CDS_PN = "267";
"DQS7N":   PN = "277"  !CDS_PN = "277";
"DQS7P":   PN = "278"  !CDS_PN = "278";
"DQS8N":   PN = "196"  !CDS_PN = "196";
"DQS8P":   PN = "197"  !CDS_PN = "197";
"DQS9N":   PN = "8"  !CDS_PN = "8";
"DQS9P":   PN = "7"  !CDS_PN = "7";
"DQS10N":   PN = "19"  !CDS_PN = "19";
"DQS10P":   PN = "18"  !CDS_PN = "18";
"DQS11N":   PN = "30"  !CDS_PN = "30";
"DQS11P":   PN = "29"  !CDS_PN = "29";
"DQS12N":   PN = "41"  !CDS_PN = "41";
"DQS12P":   PN = "40"  !CDS_PN = "40";
"DQS13N":   PN = "100"  !CDS_PN = "100";
"DQS13P":   PN = "99"  !CDS_PN = "99";
"DQS14N":   PN = "111"  !CDS_PN = "111";
"DQS14P":   PN = "110"  !CDS_PN = "110";
"DQS15N":   PN = "122"  !CDS_PN = "122";
"DQS15P":   PN = "121"  !CDS_PN = "121";
"DQS16N":   PN = "133"  !CDS_PN = "133";
"DQS16P":   PN = "132"  !CDS_PN = "132";
"DQS17N":   PN = "52"  !CDS_PN = "52";
"DQS17P":   PN = "51"  !CDS_PN = "51";
BODY = "SCONN288_H44441003","I138": #LOCATION = "J9M1" !CDS_LOCATION = "J9M1" #SEC = "3" !CDS_SEC = "3";
"VSS<0>":   PN = "283"  !CDS_PN = "283";
"VSS<1>":   PN = "281"  !CDS_PN = "281";
"VSS<2>":   PN = "279"  !CDS_PN = "279";
"VSS<3>":   PN = "276"  !CDS_PN = "276";
"VSS<4>":   PN = "274"  !CDS_PN = "274";
"VSS<5>":   PN = "272"  !CDS_PN = "272";
"VSS<6>":   PN = "270"  !CDS_PN = "270";
"VSS<7>":   PN = "268"  !CDS_PN = "268";
"VSS<8>":   PN = "265"  !CDS_PN = "265";
"VSS<9>":   PN = "263"  !CDS_PN = "263";
"VSS<10>":   PN = "261"  !CDS_PN = "261";
"VSS<11>":   PN = "259"  !CDS_PN = "259";
"VSS<12>":   PN = "257"  !CDS_PN = "257";
"VSS<13>":   PN = "254"  !CDS_PN = "254";
"VSS<14>":   PN = "252"  !CDS_PN = "252";
"VSS<15>":   PN = "250"  !CDS_PN = "250";
"VSS<16>":   PN = "248"  !CDS_PN = "248";
"VSS<17>":   PN = "246"  !CDS_PN = "246";
"VSS<18>":   PN = "243"  !CDS_PN = "243";
"VSS<19>":   PN = "241"  !CDS_PN = "241";
"VSS<20>":   PN = "239"  !CDS_PN = "239";
"VSS<21>":   PN = "202"  !CDS_PN = "202";
"VSS<22>":   PN = "200"  !CDS_PN = "200";
"VSS<23>":   PN = "198"  !CDS_PN = "198";
"VSS<24>":   PN = "195"  !CDS_PN = "195";
"VSS<25>":   PN = "193"  !CDS_PN = "193";
"VSS<26>":   PN = "191"  !CDS_PN = "191";
"VSS<27>":   PN = "189"  !CDS_PN = "189";
"VSS<28>":   PN = "187"  !CDS_PN = "187";
"VSS<29>":   PN = "184"  !CDS_PN = "184";
"VSS<30>":   PN = "182"  !CDS_PN = "182";
"VSS<31>":   PN = "180"  !CDS_PN = "180";
"VSS<32>":   PN = "178"  !CDS_PN = "178";
"VSS<33>":   PN = "176"  !CDS_PN = "176";
"VSS<34>":   PN = "173"  !CDS_PN = "173";
"VSS<35>":   PN = "171"  !CDS_PN = "171";
"VSS<36>":   PN = "169"  !CDS_PN = "169";
"VSS<37>":   PN = "167"  !CDS_PN = "167";
"VSS<38>":   PN = "165"  !CDS_PN = "165";
"VSS<39>":   PN = "162"  !CDS_PN = "162";
"VSS<40>":   PN = "160"  !CDS_PN = "160";
"VSS<41>":   PN = "158"  !CDS_PN = "158";
"VSS<42>":   PN = "156"  !CDS_PN = "156";
"VSS<43>":   PN = "154"  !CDS_PN = "154";
"VSS<44>":   PN = "151"  !CDS_PN = "151";
"VSS<45>":   PN = "149"  !CDS_PN = "149";
"VSS<46>":   PN = "147"  !CDS_PN = "147";
"VSS<47>":   PN = "138"  !CDS_PN = "138";
"VSS<48>":   PN = "136"  !CDS_PN = "136";
"VSS<49>":   PN = "134"  !CDS_PN = "134";
"VSS<50>":   PN = "131"  !CDS_PN = "131";
"VSS<51>":   PN = "129"  !CDS_PN = "129";
"VSS<52>":   PN = "127"  !CDS_PN = "127";
"VSS<53>":   PN = "125"  !CDS_PN = "125";
"VSS<54>":   PN = "123"  !CDS_PN = "123";
"VSS<55>":   PN = "120"  !CDS_PN = "120";
"VSS<56>":   PN = "118"  !CDS_PN = "118";
"VSS<57>":   PN = "116"  !CDS_PN = "116";
"VSS<58>":   PN = "114"  !CDS_PN = "114";
"VSS<59>":   PN = "112"  !CDS_PN = "112";
"VSS<60>":   PN = "109"  !CDS_PN = "109";
"VSS<61>":   PN = "107"  !CDS_PN = "107";
"VSS<62>":   PN = "105"  !CDS_PN = "105";
"VSS<63>":   PN = "103"  !CDS_PN = "103";
"VSS<64>":   PN = "101"  !CDS_PN = "101";
"VSS<65>":   PN = "98"  !CDS_PN = "98";
"VSS<66>":   PN = "96"  !CDS_PN = "96";
"VSS<67>":   PN = "94"  !CDS_PN = "94";
"VSS<68>":   PN = "57"  !CDS_PN = "57";
"VSS<69>":   PN = "55"  !CDS_PN = "55";
"VSS<70>":   PN = "53"  !CDS_PN = "53";
"VSS<71>":   PN = "50"  !CDS_PN = "50";
"VSS<72>":   PN = "48"  !CDS_PN = "48";
"VSS<73>":   PN = "46"  !CDS_PN = "46";
"VSS<74>":   PN = "44"  !CDS_PN = "44";
"VSS<75>":   PN = "42"  !CDS_PN = "42";
"VSS<76>":   PN = "39"  !CDS_PN = "39";
"VSS<77>":   PN = "37"  !CDS_PN = "37";
"VSS<78>":   PN = "35"  !CDS_PN = "35";
"VSS<79>":   PN = "33"  !CDS_PN = "33";
"VSS<80>":   PN = "31"  !CDS_PN = "31";
"VSS<81>":   PN = "28"  !CDS_PN = "28";
"VSS<82>":   PN = "26"  !CDS_PN = "26";
"VSS<83>":   PN = "24"  !CDS_PN = "24";
"VSS<84>":   PN = "22"  !CDS_PN = "22";
"VSS<85>":   PN = "20"  !CDS_PN = "20";
"VSS<86>":   PN = "17"  !CDS_PN = "17";
"VSS<87>":   PN = "15"  !CDS_PN = "15";
"VSS<88>":   PN = "13"  !CDS_PN = "13";
"VSS<89>":   PN = "11"  !CDS_PN = "11";
"VSS<90>":   PN = "9"  !CDS_PN = "9";
"VSS<91>":   PN = "6"  !CDS_PN = "6";
"VSS<92>":   PN = "4"  !CDS_PN = "4";
"VSS<93>":   PN = "2"  !CDS_PN = "2";
DRAWING = "@baseboard_fab2_lib.baseboard_fab2(sch_1):page85";
BODY = "SCONN288_H44441004","I43": #LOCATION = "J1A2" !CDS_LOCATION = "J1A2" #SEC = "3" !CDS_SEC = "3";
"VSS<0>":   PN = "283"  !CDS_PN = "283";
"VSS<1>":   PN = "281"  !CDS_PN = "281";
"VSS<2>":   PN = "279"  !CDS_PN = "279";
"VSS<3>":   PN = "276"  !CDS_PN = "276";
"VSS<4>":   PN = "274"  !CDS_PN = "274";
"VSS<5>":   PN = "272"  !CDS_PN = "272";
"VSS<6>":   PN = "270"  !CDS_PN = "270";
"VSS<7>":   PN = "268"  !CDS_PN = "268";
"VSS<8>":   PN = "265"  !CDS_PN = "265";
"VSS<9>":   PN = "263"  !CDS_PN = "263";
"VSS<10>":   PN = "261"  !CDS_PN = "261";
"VSS<11>":   PN = "259"  !CDS_PN = "259";
"VSS<12>":   PN = "257"  !CDS_PN = "257";
"VSS<13>":   PN = "254"  !CDS_PN = "254";
"VSS<14>":   PN = "252"  !CDS_PN = "252";
"VSS<15>":   PN = "250"  !CDS_PN = "250";
"VSS<16>":   PN = "248"  !CDS_PN = "248";
"VSS<17>":   PN = "246"  !CDS_PN = "246";
"VSS<18>":   PN = "243"  !CDS_PN = "243";
"VSS<19>":   PN = "241"  !CDS_PN = "241";
"VSS<20>":   PN = "239"  !CDS_PN = "239";
"VSS<21>":   PN = "202"  !CDS_PN = "202";
"VSS<22>":   PN = "200"  !CDS_PN = "200";
"VSS<23>":   PN = "198"  !CDS_PN = "198";
"VSS<24>":   PN = "195"  !CDS_PN = "195";
"VSS<25>":   PN = "193"  !CDS_PN = "193";
"VSS<26>":   PN = "191"  !CDS_PN = "191";
"VSS<27>":   PN = "189"  !CDS_PN = "189";
"VSS<28>":   PN = "187"  !CDS_PN = "187";
"VSS<29>":   PN = "184"  !CDS_PN = "184";
"VSS<30>":   PN = "182"  !CDS_PN = "182";
"VSS<31>":   PN = "180"  !CDS_PN = "180";
"VSS<32>":   PN = "178"  !CDS_PN = "178";
"VSS<33>":   PN = "176"  !CDS_PN = "176";
"VSS<34>":   PN = "173"  !CDS_PN = "173";
"VSS<35>":   PN = "171"  !CDS_PN = "171";
"VSS<36>":   PN = "169"  !CDS_PN = "169";
"VSS<37>":   PN = "167"  !CDS_PN = "167";
"VSS<38>":   PN = "165"  !CDS_PN = "165";
"VSS<39>":   PN = "162"  !CDS_PN = "162";
"VSS<40>":   PN = "160"  !CDS_PN = "160";
"VSS<41>":   PN = "158"  !CDS_PN = "158";
"VSS<42>":   PN = "156"  !CDS_PN = "156";
"VSS<43>":   PN = "154"  !CDS_PN = "154";
"VSS<44>":   PN = "151"  !CDS_PN = "151";
"VSS<45>":   PN = "149"  !CDS_PN = "149";
"VSS<46>":   PN = "147"  !CDS_PN = "147";
"VSS<47>":   PN = "138"  !CDS_PN = "138";
"VSS<48>":   PN = "136"  !CDS_PN = "136";
"VSS<49>":   PN = "134"  !CDS_PN = "134";
"VSS<50>":   PN = "131"  !CDS_PN = "131";
"VSS<51>":   PN = "129"  !CDS_PN = "129";
"VSS<52>":   PN = "127"  !CDS_PN = "127";
"VSS<53>":   PN = "125"  !CDS_PN = "125";
"VSS<54>":   PN = "123"  !CDS_PN = "123";
"VSS<55>":   PN = "120"  !CDS_PN = "120";
"VSS<56>":   PN = "118"  !CDS_PN = "118";
"VSS<57>":   PN = "116"  !CDS_PN = "116";
"VSS<58>":   PN = "114"  !CDS_PN = "114";
"VSS<59>":   PN = "112"  !CDS_PN = "112";
"VSS<60>":   PN = "109"  !CDS_PN = "109";
"VSS<61>":   PN = "107"  !CDS_PN = "107";
"VSS<62>":   PN = "105"  !CDS_PN = "105";
"VSS<63>":   PN = "103"  !CDS_PN = "103";
"VSS<64>":   PN = "101"  !CDS_PN = "101";
"VSS<65>":   PN = "98"  !CDS_PN = "98";
"VSS<66>":   PN = "96"  !CDS_PN = "96";
"VSS<67>":   PN = "94"  !CDS_PN = "94";
"VSS<68>":   PN = "57"  !CDS_PN = "57";
"VSS<69>":   PN = "55"  !CDS_PN = "55";
"VSS<70>":   PN = "53"  !CDS_PN = "53";
"VSS<71>":   PN = "50"  !CDS_PN = "50";
"VSS<72>":   PN = "48"  !CDS_PN = "48";
"VSS<73>":   PN = "46"  !CDS_PN = "46";
"VSS<74>":   PN = "44"  !CDS_PN = "44";
"VSS<75>":   PN = "42"  !CDS_PN = "42";
"VSS<76>":   PN = "39"  !CDS_PN = "39";
"VSS<77>":   PN = "37"  !CDS_PN = "37";
"VSS<78>":   PN = "35"  !CDS_PN = "35";
"VSS<79>":   PN = "33"  !CDS_PN = "33";
"VSS<80>":   PN = "31"  !CDS_PN = "31";
"VSS<81>":   PN = "28"  !CDS_PN = "28";
"VSS<82>":   PN = "26"  !CDS_PN = "26";
"VSS<83>":   PN = "24"  !CDS_PN = "24";
"VSS<84>":   PN = "22"  !CDS_PN = "22";
"VSS<85>":   PN = "20"  !CDS_PN = "20";
"VSS<86>":   PN = "17"  !CDS_PN = "17";
"VSS<87>":   PN = "15"  !CDS_PN = "15";
"VSS<88>":   PN = "13"  !CDS_PN = "13";
"VSS<89>":   PN = "11"  !CDS_PN = "11";
"VSS<90>":   PN = "9"  !CDS_PN = "9";
"VSS<91>":   PN = "6"  !CDS_PN = "6";
"VSS<92>":   PN = "4"  !CDS_PN = "4";
"VSS<93>":   PN = "2"  !CDS_PN = "2";
BODY = "SCONN288_H44441004","I66": #LOCATION = "J1A2" !CDS_LOCATION = "J1A2" #SEC = "2" !CDS_SEC = "2";
"DQS0N":   PN = "152"  !CDS_PN = "152";
"DQS0P":   PN = "153"  !CDS_PN = "153";
"DQS1N":   PN = "163"  !CDS_PN = "163";
"DQS1P":   PN = "164"  !CDS_PN = "164";
"DQS2N":   PN = "174"  !CDS_PN = "174";
"DQS2P":   PN = "175"  !CDS_PN = "175";
"DQS3N":   PN = "185"  !CDS_PN = "185";
"DQS3P":   PN = "186"  !CDS_PN = "186";
"DQS4N":   PN = "244"  !CDS_PN = "244";
"DQS4P":   PN = "245"  !CDS_PN = "245";
"DQS5N":   PN = "255"  !CDS_PN = "255";
"DQS5P":   PN = "256"  !CDS_PN = "256";
"DQS6N":   PN = "266"  !CDS_PN = "266";
"DQS6P":   PN = "267"  !CDS_PN = "267";
"DQS7N":   PN = "277"  !CDS_PN = "277";
"DQS7P":   PN = "278"  !CDS_PN = "278";
"DQS8N":   PN = "196"  !CDS_PN = "196";
"DQS8P":   PN = "197"  !CDS_PN = "197";
"DQS9N":   PN = "8"  !CDS_PN = "8";
"DQS9P":   PN = "7"  !CDS_PN = "7";
"DQS10N":   PN = "19"  !CDS_PN = "19";
"DQS10P":   PN = "18"  !CDS_PN = "18";
"DQS11N":   PN = "30"  !CDS_PN = "30";
"DQS11P":   PN = "29"  !CDS_PN = "29";
"DQS12N":   PN = "41"  !CDS_PN = "41";
"DQS12P":   PN = "40"  !CDS_PN = "40";
"DQS13N":   PN = "100"  !CDS_PN = "100";
"DQS13P":   PN = "99"  !CDS_PN = "99";
"DQS14N":   PN = "111"  !CDS_PN = "111";
"DQS14P":   PN = "110"  !CDS_PN = "110";
"DQS15N":   PN = "122"  !CDS_PN = "122";
"DQS15P":   PN = "121"  !CDS_PN = "121";
"DQS16N":   PN = "133"  !CDS_PN = "133";
"DQS16P":   PN = "132"  !CDS_PN = "132";
"DQS17N":   PN = "52"  !CDS_PN = "52";
"DQS17P":   PN = "51"  !CDS_PN = "51";
BODY = "SCONN288_H44441004","I111": #LOCATION = "J1A2" !CDS_LOCATION = "J1A2" #SEC = "1" !CDS_SEC = "1";
"A0":   PN = "79"  !CDS_PN = "79";
"A1":   PN = "72"  !CDS_PN = "72";
"A2":   PN = "216"  !CDS_PN = "216";
"A3":   PN = "71"  !CDS_PN = "71";
"A4":   PN = "214"  !CDS_PN = "214";
"A5":   PN = "213"  !CDS_PN = "213";
"A6":   PN = "69"  !CDS_PN = "69";
"A7":   PN = "211"  !CDS_PN = "211";
"A8":   PN = "68"  !CDS_PN = "68";
"A9":   PN = "66"  !CDS_PN = "66";
"A10":   PN = "225"  !CDS_PN = "225";
"A11":   PN = "210"  !CDS_PN = "210";
"A12":   PN = "65"  !CDS_PN = "65";
"A13":   PN = "232"  !CDS_PN = "232";
"A14_WE_N":   PN = "228"  !CDS_PN = "228";
"A15_CAS_N":   PN = "86"  !CDS_PN = "86";
"A16_RAS_N":   PN = "82"  !CDS_PN = "82";
"A17":   PN = "234"  !CDS_PN = "234";
"ACT_N":   PN = "62"  !CDS_PN = "62";
"ALERT_N":   PN = "208"  !CDS_PN = "208";
"BA<0>":   PN = "81"  !CDS_PN = "81";
"BA<1>":   PN = "224"  !CDS_PN = "224";
"BG<0>":   PN = "63"  !CDS_PN = "63";
"BG<1>":   PN = "207"  !CDS_PN = "207";
"C<2>":   PN = "235"  !CDS_PN = "235";
"CB<0>":   PN = "49"  !CDS_PN = "49";
"CB<1>":   PN = "194"  !CDS_PN = "194";
"CB<2>":   PN = "56"  !CDS_PN = "56";
"CB<3>":   PN = "201"  !CDS_PN = "201";
"CB<4>":   PN = "47"  !CDS_PN = "47";
"CB<5>":   PN = "192"  !CDS_PN = "192";
"CB<6>":   PN = "54"  !CDS_PN = "54";
"CB<7>":   PN = "199"  !CDS_PN = "199";
"CK0N":   PN = "75"  !CDS_PN = "75";
"CK0P":   PN = "74"  !CDS_PN = "74";
"CK1N":   PN = "219"  !CDS_PN = "219";
"CK1P":   PN = "218"  !CDS_PN = "218";
"CKE<0>":   PN = "60"  !CDS_PN = "60";
"CKE<1>":   PN = "203"  !CDS_PN = "203";
"DQ<0>":   PN = "5"  !CDS_PN = "5";
"DQ<1>":   PN = "150"  !CDS_PN = "150";
"DQ<2>":   PN = "12"  !CDS_PN = "12";
"DQ<3>":   PN = "157"  !CDS_PN = "157";
"DQ<4>":   PN = "3"  !CDS_PN = "3";
"DQ<5>":   PN = "148"  !CDS_PN = "148";
"DQ<6>":   PN = "10"  !CDS_PN = "10";
"DQ<7>":   PN = "155"  !CDS_PN = "155";
"DQ<8>":   PN = "16"  !CDS_PN = "16";
"DQ<9>":   PN = "161"  !CDS_PN = "161";
"DQ<10>":   PN = "23"  !CDS_PN = "23";
"DQ<11>":   PN = "168"  !CDS_PN = "168";
"DQ<12>":   PN = "14"  !CDS_PN = "14";
"DQ<13>":   PN = "159"  !CDS_PN = "159";
"DQ<14>":   PN = "21"  !CDS_PN = "21";
"DQ<15>":   PN = "166"  !CDS_PN = "166";
"DQ<16>":   PN = "27"  !CDS_PN = "27";
"DQ<17>":   PN = "172"  !CDS_PN = "172";
"DQ<18>":   PN = "34"  !CDS_PN = "34";
"DQ<19>":   PN = "179"  !CDS_PN = "179";
"DQ<20>":   PN = "25"  !CDS_PN = "25";
"DQ<21>":   PN = "170"  !CDS_PN = "170";
"DQ<22>":   PN = "32"  !CDS_PN = "32";
"DQ<23>":   PN = "177"  !CDS_PN = "177";
"DQ<24>":   PN = "38"  !CDS_PN = "38";
"DQ<25>":   PN = "183"  !CDS_PN = "183";
"DQ<26>":   PN = "45"  !CDS_PN = "45";
"DQ<27>":   PN = "190"  !CDS_PN = "190";
"DQ<28>":   PN = "36"  !CDS_PN = "36";
"DQ<29>":   PN = "181"  !CDS_PN = "181";
"DQ<30>":   PN = "43"  !CDS_PN = "43";
"DQ<31>":   PN = "188"  !CDS_PN = "188";
"DQ<32>":   PN = "97"  !CDS_PN = "97";
"DQ<33>":   PN = "242"  !CDS_PN = "242";
"DQ<34>":   PN = "104"  !CDS_PN = "104";
"DQ<35>":   PN = "249"  !CDS_PN = "249";
"DQ<36>":   PN = "95"  !CDS_PN = "95";
"DQ<37>":   PN = "240"  !CDS_PN = "240";
"DQ<38>":   PN = "102"  !CDS_PN = "102";
"DQ<39>":   PN = "247"  !CDS_PN = "247";
"DQ<40>":   PN = "108"  !CDS_PN = "108";
"DQ<41>":   PN = "253"  !CDS_PN = "253";
"DQ<42>":   PN = "115"  !CDS_PN = "115";
"DQ<43>":   PN = "260"  !CDS_PN = "260";
"DQ<44>":   PN = "106"  !CDS_PN = "106";
"DQ<45>":   PN = "251"  !CDS_PN = "251";
"DQ<46>":   PN = "113"  !CDS_PN = "113";
"DQ<47>":   PN = "258"  !CDS_PN = "258";
"DQ<48>":   PN = "119"  !CDS_PN = "119";
"DQ<49>":   PN = "264"  !CDS_PN = "264";
"DQ<50>":   PN = "126"  !CDS_PN = "126";
"DQ<51>":   PN = "271"  !CDS_PN = "271";
"DQ<52>":   PN = "117"  !CDS_PN = "117";
"DQ<53>":   PN = "262"  !CDS_PN = "262";
"DQ<54>":   PN = "124"  !CDS_PN = "124";
"DQ<55>":   PN = "269"  !CDS_PN = "269";
"DQ<56>":   PN = "130"  !CDS_PN = "130";
"DQ<57>":   PN = "275"  !CDS_PN = "275";
"DQ<58>":   PN = "137"  !CDS_PN = "137";
"DQ<59>":   PN = "282"  !CDS_PN = "282";
"DQ<60>":   PN = "128"  !CDS_PN = "128";
"DQ<61>":   PN = "273"  !CDS_PN = "273";
"DQ<62>":   PN = "135"  !CDS_PN = "135";
"DQ<63>":   PN = "280"  !CDS_PN = "280";
"EVENT_N":   PN = "78"  !CDS_PN = "78";
"ODT<0>":   PN = "87"  !CDS_PN = "87";
"ODT<1>":   PN = "91"  !CDS_PN = "91";
"PAR":   PN = "222"  !CDS_PN = "222";
"RESET_N":   PN = "58"  !CDS_PN = "58";
"RFU<0>":   PN = "205"  !CDS_PN = "205";
"RFU<1>":   PN = "227"  !CDS_PN = "227";
"RFU<2>":   PN = "144"  !CDS_PN = "144";
"S0_N":   PN = "84"  !CDS_PN = "84";
"S1_N":   PN = "89"  !CDS_PN = "89";
"S2_N_C<0>":   PN = "93"  !CDS_PN = "93";
"S3_N_C<1>":   PN = "237"  !CDS_PN = "237";
"SA<0>":   PN = "139"  !CDS_PN = "139";
"SA<1>":   PN = "140"  !CDS_PN = "140";
"SA<2>":   PN = "238"  !CDS_PN = "238";
"SAVE_N_NC":   PN = "230"  !CDS_PN = "230";
"SCL":   PN = "141"  !CDS_PN = "141";
"SDA":   PN = "285"  !CDS_PN = "285";
"VDDSPD":   PN = "284"  !CDS_PN = "284";
"VREFCA":   PN = "146"  !CDS_PN = "146";
BODY = "SCONN288_H44441004","I172": #LOCATION = "J1A2" !CDS_LOCATION = "J1A2" #SEC = "4" !CDS_SEC = "4";
"12V<0>":   PN = "145"  !CDS_PN = "145";
"12V<1>":   PN = "1"  !CDS_PN = "1";
"VDD<0>":   PN = "236"  !CDS_PN = "236";
"VDD<1>":   PN = "233"  !CDS_PN = "233";
"VDD<2>":   PN = "231"  !CDS_PN = "231";
"VDD<3>":   PN = "229"  !CDS_PN = "229";
"VDD<4>":   PN = "226"  !CDS_PN = "226";
"VDD<5>":   PN = "223"  !CDS_PN = "223";
"VDD<6>":   PN = "220"  !CDS_PN = "220";
"VDD<7>":   PN = "217"  !CDS_PN = "217";
"VDD<8>":   PN = "215"  !CDS_PN = "215";
"VDD<9>":   PN = "212"  !CDS_PN = "212";
"VDD<10>":   PN = "209"  !CDS_PN = "209";
"VDD<11>":   PN = "206"  !CDS_PN = "206";
"VDD<12>":   PN = "204"  !CDS_PN = "204";
"VDD<13>":   PN = "92"  !CDS_PN = "92";
"VDD<14>":   PN = "90"  !CDS_PN = "90";
"VDD<15>":   PN = "88"  !CDS_PN = "88";
"VDD<16>":   PN = "85"  !CDS_PN = "85";
"VDD<17>":   PN = "83"  !CDS_PN = "83";
"VDD<18>":   PN = "80"  !CDS_PN = "80";
"VDD<19>":   PN = "76"  !CDS_PN = "76";
"VDD<20>":   PN = "73"  !CDS_PN = "73";
"VDD<21>":   PN = "70"  !CDS_PN = "70";
"VDD<22>":   PN = "67"  !CDS_PN = "67";
"VDD<23>":   PN = "64"  !CDS_PN = "64";
"VDD<24>":   PN = "61"  !CDS_PN = "61";
"VDD<25>":   PN = "59"  !CDS_PN = "59";
"VPP<0>":   PN = "287"  !CDS_PN = "287";
"VPP<1>":   PN = "286"  !CDS_PN = "286";
"VPP<2>":   PN = "288"  !CDS_PN = "288";
"VPP<3>":   PN = "143"  !CDS_PN = "143";
"VPP<4>":   PN = "142"  !CDS_PN = "142";
"VTT<0>":   PN = "221"  !CDS_PN = "221";
"VTT<1>":   PN = "77"  !CDS_PN = "77";
BODY = "CAP_A","I181": #LOCATION = "C9L7" !CDS_LOCATION = "C9L7" &SEC = "1" #&CDS_SEC = "1";
"A":   PN = "1"  !CDS_PN = "1";
"B":   PN = "2"  !CDS_PN = "2";
DRAWING = "@baseboard_fab2_lib.baseboard_fab2(sch_1):page86";
BODY = "SCONN288_H44441003","I12": #LOCATION = "J9L2" !CDS_LOCATION = "J9L2" #SEC = "1" !CDS_SEC = "1";
"A0":   PN = "79"  !CDS_PN = "79";
"A1":   PN = "72"  !CDS_PN = "72";
"A2":   PN = "216"  !CDS_PN = "216";
"A3":   PN = "71"  !CDS_PN = "71";
"A4":   PN = "214"  !CDS_PN = "214";
"A5":   PN = "213"  !CDS_PN = "213";
"A6":   PN = "69"  !CDS_PN = "69";
"A7":   PN = "211"  !CDS_PN = "211";
"A8":   PN = "68"  !CDS_PN = "68";
"A9":   PN = "66"  !CDS_PN = "66";
"A10":   PN = "225"  !CDS_PN = "225";
"A11":   PN = "210"  !CDS_PN = "210";
"A12":   PN = "65"  !CDS_PN = "65";
"A13":   PN = "232"  !CDS_PN = "232";
"A14_WE_N":   PN = "228"  !CDS_PN = "228";
"A15_CAS_N":   PN = "86"  !CDS_PN = "86";
"A16_RAS_N":   PN = "82"  !CDS_PN = "82";
"A17":   PN = "234"  !CDS_PN = "234";
"ACT_N":   PN = "62"  !CDS_PN = "62";
"ALERT_N":   PN = "208"  !CDS_PN = "208";
"BA<0>":   PN = "81"  !CDS_PN = "81";
"BA<1>":   PN = "224"  !CDS_PN = "224";
"BG<0>":   PN = "63"  !CDS_PN = "63";
"BG<1>":   PN = "207"  !CDS_PN = "207";
"C<2>":   PN = "235"  !CDS_PN = "235";
"CB<0>":   PN = "49"  !CDS_PN = "49";
"CB<1>":   PN = "194"  !CDS_PN = "194";
"CB<2>":   PN = "56"  !CDS_PN = "56";
"CB<3>":   PN = "201"  !CDS_PN = "201";
"CB<4>":   PN = "47"  !CDS_PN = "47";
"CB<5>":   PN = "192"  !CDS_PN = "192";
"CB<6>":   PN = "54"  !CDS_PN = "54";
"CB<7>":   PN = "199"  !CDS_PN = "199";
"CK0N":   PN = "75"  !CDS_PN = "75";
"CK0P":   PN = "74"  !CDS_PN = "74";
"CK1N":   PN = "219"  !CDS_PN = "219";
"CK1P":   PN = "218"  !CDS_PN = "218";
"CKE<0>":   PN = "60"  !CDS_PN = "60";
"CKE<1>":   PN = "203"  !CDS_PN = "203";
"DQ<0>":   PN = "5"  !CDS_PN = "5";
"DQ<1>":   PN = "150"  !CDS_PN = "150";
"DQ<2>":   PN = "12"  !CDS_PN = "12";
"DQ<3>":   PN = "157"  !CDS_PN = "157";
"DQ<4>":   PN = "3"  !CDS_PN = "3";
"DQ<5>":   PN = "148"  !CDS_PN = "148";
"DQ<6>":   PN = "10"  !CDS_PN = "10";
"DQ<7>":   PN = "155"  !CDS_PN = "155";
"DQ<8>":   PN = "16"  !CDS_PN = "16";
"DQ<9>":   PN = "161"  !CDS_PN = "161";
"DQ<10>":   PN = "23"  !CDS_PN = "23";
"DQ<11>":   PN = "168"  !CDS_PN = "168";
"DQ<12>":   PN = "14"  !CDS_PN = "14";
"DQ<13>":   PN = "159"  !CDS_PN = "159";
"DQ<14>":   PN = "21"  !CDS_PN = "21";
"DQ<15>":   PN = "166"  !CDS_PN = "166";
"DQ<16>":   PN = "27"  !CDS_PN = "27";
"DQ<17>":   PN = "172"  !CDS_PN = "172";
"DQ<18>":   PN = "34"  !CDS_PN = "34";
"DQ<19>":   PN = "179"  !CDS_PN = "179";
"DQ<20>":   PN = "25"  !CDS_PN = "25";
"DQ<21>":   PN = "170"  !CDS_PN = "170";
"DQ<22>":   PN = "32"  !CDS_PN = "32";
"DQ<23>":   PN = "177"  !CDS_PN = "177";
"DQ<24>":   PN = "38"  !CDS_PN = "38";
"DQ<25>":   PN = "183"  !CDS_PN = "183";
"DQ<26>":   PN = "45"  !CDS_PN = "45";
"DQ<27>":   PN = "190"  !CDS_PN = "190";
"DQ<28>":   PN = "36"  !CDS_PN = "36";
"DQ<29>":   PN = "181"  !CDS_PN = "181";
"DQ<30>":   PN = "43"  !CDS_PN = "43";
"DQ<31>":   PN = "188"  !CDS_PN = "188";
"DQ<32>":   PN = "97"  !CDS_PN = "97";
"DQ<33>":   PN = "242"  !CDS_PN = "242";
"DQ<34>":   PN = "104"  !CDS_PN = "104";
"DQ<35>":   PN = "249"  !CDS_PN = "249";
"DQ<36>":   PN = "95"  !CDS_PN = "95";
"DQ<37>":   PN = "240"  !CDS_PN = "240";
"DQ<38>":   PN = "102"  !CDS_PN = "102";
"DQ<39>":   PN = "247"  !CDS_PN = "247";
"DQ<40>":   PN = "108"  !CDS_PN = "108";
"DQ<41>":   PN = "253"  !CDS_PN = "253";
"DQ<42>":   PN = "115"  !CDS_PN = "115";
"DQ<43>":   PN = "260"  !CDS_PN = "260";
"DQ<44>":   PN = "106"  !CDS_PN = "106";
"DQ<45>":   PN = "251"  !CDS_PN = "251";
"DQ<46>":   PN = "113"  !CDS_PN = "113";
"DQ<47>":   PN = "258"  !CDS_PN = "258";
"DQ<48>":   PN = "119"  !CDS_PN = "119";
"DQ<49>":   PN = "264"  !CDS_PN = "264";
"DQ<50>":   PN = "126"  !CDS_PN = "126";
"DQ<51>":   PN = "271"  !CDS_PN = "271";
"DQ<52>":   PN = "117"  !CDS_PN = "117";
"DQ<53>":   PN = "262"  !CDS_PN = "262";
"DQ<54>":   PN = "124"  !CDS_PN = "124";
"DQ<55>":   PN = "269"  !CDS_PN = "269";
"DQ<56>":   PN = "130"  !CDS_PN = "130";
"DQ<57>":   PN = "275"  !CDS_PN = "275";
"DQ<58>":   PN = "137"  !CDS_PN = "137";
"DQ<59>":   PN = "282"  !CDS_PN = "282";
"DQ<60>":   PN = "128"  !CDS_PN = "128";
"DQ<61>":   PN = "273"  !CDS_PN = "273";
"DQ<62>":   PN = "135"  !CDS_PN = "135";
"DQ<63>":   PN = "280"  !CDS_PN = "280";
"EVENT_N":   PN = "78"  !CDS_PN = "78";
"ODT<0>":   PN = "87"  !CDS_PN = "87";
"ODT<1>":   PN = "91"  !CDS_PN = "91";
"PAR":   PN = "222"  !CDS_PN = "222";
"RESET_N":   PN = "58"  !CDS_PN = "58";
"RFU<0>":   PN = "205"  !CDS_PN = "205";
"RFU<1>":   PN = "227"  !CDS_PN = "227";
"RFU<2>":   PN = "144"  !CDS_PN = "144";
"S0_N":   PN = "84"  !CDS_PN = "84";
"S1_N":   PN = "89"  !CDS_PN = "89";
"S2_N_C<0>":   PN = "93"  !CDS_PN = "93";
"S3_N_C<1>":   PN = "237"  !CDS_PN = "237";
"SA<0>":   PN = "139"  !CDS_PN = "139";
"SA<1>":   PN = "140"  !CDS_PN = "140";
"SA<2>":   PN = "238"  !CDS_PN = "238";
"SAVE_N_NC":   PN = "230"  !CDS_PN = "230";
"SCL":   PN = "141"  !CDS_PN = "141";
"SDA":   PN = "285"  !CDS_PN = "285";
"VDDSPD":   PN = "284"  !CDS_PN = "284";
"VREFCA":   PN = "146"  !CDS_PN = "146";
BODY = "SCONN288_H44441003","I55": #LOCATION = "J9L2" !CDS_LOCATION = "J9L2" #SEC = "4" !CDS_SEC = "4";
"12V<0>":   PN = "145"  !CDS_PN = "145";
"12V<1>":   PN = "1"  !CDS_PN = "1";
"VDD<0>":   PN = "236"  !CDS_PN = "236";
"VDD<1>":   PN = "233"  !CDS_PN = "233";
"VDD<2>":   PN = "231"  !CDS_PN = "231";
"VDD<3>":   PN = "229"  !CDS_PN = "229";
"VDD<4>":   PN = "226"  !CDS_PN = "226";
"VDD<5>":   PN = "223"  !CDS_PN = "223";
"VDD<6>":   PN = "220"  !CDS_PN = "220";
"VDD<7>":   PN = "217"  !CDS_PN = "217";
"VDD<8>":   PN = "215"  !CDS_PN = "215";
"VDD<9>":   PN = "212"  !CDS_PN = "212";
"VDD<10>":   PN = "209"  !CDS_PN = "209";
"VDD<11>":   PN = "206"  !CDS_PN = "206";
"VDD<12>":   PN = "204"  !CDS_PN = "204";
"VDD<13>":   PN = "92"  !CDS_PN = "92";
"VDD<14>":   PN = "90"  !CDS_PN = "90";
"VDD<15>":   PN = "88"  !CDS_PN = "88";
"VDD<16>":   PN = "85"  !CDS_PN = "85";
"VDD<17>":   PN = "83"  !CDS_PN = "83";
"VDD<18>":   PN = "80"  !CDS_PN = "80";
"VDD<19>":   PN = "76"  !CDS_PN = "76";
"VDD<20>":   PN = "73"  !CDS_PN = "73";
"VDD<21>":   PN = "70"  !CDS_PN = "70";
"VDD<22>":   PN = "67"  !CDS_PN = "67";
"VDD<23>":   PN = "64"  !CDS_PN = "64";
"VDD<24>":   PN = "61"  !CDS_PN = "61";
"VDD<25>":   PN = "59"  !CDS_PN = "59";
"VPP<0>":   PN = "287"  !CDS_PN = "287";
"VPP<1>":   PN = "286"  !CDS_PN = "286";
"VPP<2>":   PN = "288"  !CDS_PN = "288";
"VPP<3>":   PN = "143"  !CDS_PN = "143";
"VPP<4>":   PN = "142"  !CDS_PN = "142";
"VTT<0>":   PN = "221"  !CDS_PN = "221";
"VTT<1>":   PN = "77"  !CDS_PN = "77";
BODY = "SCONN288_H44441003","I100": #LOCATION = "J9L2" !CDS_LOCATION = "J9L2" #SEC = "2" !CDS_SEC = "2";
"DQS0N":   PN = "152"  !CDS_PN = "152";
"DQS0P":   PN = "153"  !CDS_PN = "153";
"DQS1N":   PN = "163"  !CDS_PN = "163";
"DQS1P":   PN = "164"  !CDS_PN = "164";
"DQS2N":   PN = "174"  !CDS_PN = "174";
"DQS2P":   PN = "175"  !CDS_PN = "175";
"DQS3N":   PN = "185"  !CDS_PN = "185";
"DQS3P":   PN = "186"  !CDS_PN = "186";
"DQS4N":   PN = "244"  !CDS_PN = "244";
"DQS4P":   PN = "245"  !CDS_PN = "245";
"DQS5N":   PN = "255"  !CDS_PN = "255";
"DQS5P":   PN = "256"  !CDS_PN = "256";
"DQS6N":   PN = "266"  !CDS_PN = "266";
"DQS6P":   PN = "267"  !CDS_PN = "267";
"DQS7N":   PN = "277"  !CDS_PN = "277";
"DQS7P":   PN = "278"  !CDS_PN = "278";
"DQS8N":   PN = "196"  !CDS_PN = "196";
"DQS8P":   PN = "197"  !CDS_PN = "197";
"DQS9N":   PN = "8"  !CDS_PN = "8";
"DQS9P":   PN = "7"  !CDS_PN = "7";
"DQS10N":   PN = "19"  !CDS_PN = "19";
"DQS10P":   PN = "18"  !CDS_PN = "18";
"DQS11N":   PN = "30"  !CDS_PN = "30";
"DQS11P":   PN = "29"  !CDS_PN = "29";
"DQS12N":   PN = "41"  !CDS_PN = "41";
"DQS12P":   PN = "40"  !CDS_PN = "40";
"DQS13N":   PN = "100"  !CDS_PN = "100";
"DQS13P":   PN = "99"  !CDS_PN = "99";
"DQS14N":   PN = "111"  !CDS_PN = "111";
"DQS14P":   PN = "110"  !CDS_PN = "110";
"DQS15N":   PN = "122"  !CDS_PN = "122";
"DQS15P":   PN = "121"  !CDS_PN = "121";
"DQS16N":   PN = "133"  !CDS_PN = "133";
"DQS16P":   PN = "132"  !CDS_PN = "132";
"DQS17N":   PN = "52"  !CDS_PN = "52";
"DQS17P":   PN = "51"  !CDS_PN = "51";
BODY = "SCONN288_H44441003","I138": #LOCATION = "J9L2" !CDS_LOCATION = "J9L2" #SEC = "3" !CDS_SEC = "3";
"VSS<0>":   PN = "283"  !CDS_PN = "283";
"VSS<1>":   PN = "281"  !CDS_PN = "281";
"VSS<2>":   PN = "279"  !CDS_PN = "279";
"VSS<3>":   PN = "276"  !CDS_PN = "276";
"VSS<4>":   PN = "274"  !CDS_PN = "274";
"VSS<5>":   PN = "272"  !CDS_PN = "272";
"VSS<6>":   PN = "270"  !CDS_PN = "270";
"VSS<7>":   PN = "268"  !CDS_PN = "268";
"VSS<8>":   PN = "265"  !CDS_PN = "265";
"VSS<9>":   PN = "263"  !CDS_PN = "263";
"VSS<10>":   PN = "261"  !CDS_PN = "261";
"VSS<11>":   PN = "259"  !CDS_PN = "259";
"VSS<12>":   PN = "257"  !CDS_PN = "257";
"VSS<13>":   PN = "254"  !CDS_PN = "254";
"VSS<14>":   PN = "252"  !CDS_PN = "252";
"VSS<15>":   PN = "250"  !CDS_PN = "250";
"VSS<16>":   PN = "248"  !CDS_PN = "248";
"VSS<17>":   PN = "246"  !CDS_PN = "246";
"VSS<18>":   PN = "243"  !CDS_PN = "243";
"VSS<19>":   PN = "241"  !CDS_PN = "241";
"VSS<20>":   PN = "239"  !CDS_PN = "239";
"VSS<21>":   PN = "202"  !CDS_PN = "202";
"VSS<22>":   PN = "200"  !CDS_PN = "200";
"VSS<23>":   PN = "198"  !CDS_PN = "198";
"VSS<24>":   PN = "195"  !CDS_PN = "195";
"VSS<25>":   PN = "193"  !CDS_PN = "193";
"VSS<26>":   PN = "191"  !CDS_PN = "191";
"VSS<27>":   PN = "189"  !CDS_PN = "189";
"VSS<28>":   PN = "187"  !CDS_PN = "187";
"VSS<29>":   PN = "184"  !CDS_PN = "184";
"VSS<30>":   PN = "182"  !CDS_PN = "182";
"VSS<31>":   PN = "180"  !CDS_PN = "180";
"VSS<32>":   PN = "178"  !CDS_PN = "178";
"VSS<33>":   PN = "176"  !CDS_PN = "176";
"VSS<34>":   PN = "173"  !CDS_PN = "173";
"VSS<35>":   PN = "171"  !CDS_PN = "171";
"VSS<36>":   PN = "169"  !CDS_PN = "169";
"VSS<37>":   PN = "167"  !CDS_PN = "167";
"VSS<38>":   PN = "165"  !CDS_PN = "165";
"VSS<39>":   PN = "162"  !CDS_PN = "162";
"VSS<40>":   PN = "160"  !CDS_PN = "160";
"VSS<41>":   PN = "158"  !CDS_PN = "158";
"VSS<42>":   PN = "156"  !CDS_PN = "156";
"VSS<43>":   PN = "154"  !CDS_PN = "154";
"VSS<44>":   PN = "151"  !CDS_PN = "151";
"VSS<45>":   PN = "149"  !CDS_PN = "149";
"VSS<46>":   PN = "147"  !CDS_PN = "147";
"VSS<47>":   PN = "138"  !CDS_PN = "138";
"VSS<48>":   PN = "136"  !CDS_PN = "136";
"VSS<49>":   PN = "134"  !CDS_PN = "134";
"VSS<50>":   PN = "131"  !CDS_PN = "131";
"VSS<51>":   PN = "129"  !CDS_PN = "129";
"VSS<52>":   PN = "127"  !CDS_PN = "127";
"VSS<53>":   PN = "125"  !CDS_PN = "125";
"VSS<54>":   PN = "123"  !CDS_PN = "123";
"VSS<55>":   PN = "120"  !CDS_PN = "120";
"VSS<56>":   PN = "118"  !CDS_PN = "118";
"VSS<57>":   PN = "116"  !CDS_PN = "116";
"VSS<58>":   PN = "114"  !CDS_PN = "114";
"VSS<59>":   PN = "112"  !CDS_PN = "112";
"VSS<60>":   PN = "109"  !CDS_PN = "109";
"VSS<61>":   PN = "107"  !CDS_PN = "107";
"VSS<62>":   PN = "105"  !CDS_PN = "105";
"VSS<63>":   PN = "103"  !CDS_PN = "103";
"VSS<64>":   PN = "101"  !CDS_PN = "101";
"VSS<65>":   PN = "98"  !CDS_PN = "98";
"VSS<66>":   PN = "96"  !CDS_PN = "96";
"VSS<67>":   PN = "94"  !CDS_PN = "94";
"VSS<68>":   PN = "57"  !CDS_PN = "57";
"VSS<69>":   PN = "55"  !CDS_PN = "55";
"VSS<70>":   PN = "53"  !CDS_PN = "53";
"VSS<71>":   PN = "50"  !CDS_PN = "50";
"VSS<72>":   PN = "48"  !CDS_PN = "48";
"VSS<73>":   PN = "46"  !CDS_PN = "46";
"VSS<74>":   PN = "44"  !CDS_PN = "44";
"VSS<75>":   PN = "42"  !CDS_PN = "42";
"VSS<76>":   PN = "39"  !CDS_PN = "39";
"VSS<77>":   PN = "37"  !CDS_PN = "37";
"VSS<78>":   PN = "35"  !CDS_PN = "35";
"VSS<79>":   PN = "33"  !CDS_PN = "33";
"VSS<80>":   PN = "31"  !CDS_PN = "31";
"VSS<81>":   PN = "28"  !CDS_PN = "28";
"VSS<82>":   PN = "26"  !CDS_PN = "26";
"VSS<83>":   PN = "24"  !CDS_PN = "24";
"VSS<84>":   PN = "22"  !CDS_PN = "22";
"VSS<85>":   PN = "20"  !CDS_PN = "20";
"VSS<86>":   PN = "17"  !CDS_PN = "17";
"VSS<87>":   PN = "15"  !CDS_PN = "15";
"VSS<88>":   PN = "13"  !CDS_PN = "13";
"VSS<89>":   PN = "11"  !CDS_PN = "11";
"VSS<90>":   PN = "9"  !CDS_PN = "9";
"VSS<91>":   PN = "6"  !CDS_PN = "6";
"VSS<92>":   PN = "4"  !CDS_PN = "4";
"VSS<93>":   PN = "2"  !CDS_PN = "2";
BODY = "CAP_A","I182": #LOCATION = "C1A17" !CDS_LOCATION = "C1A17" &SEC = "1" #&CDS_SEC = "1";
"A":   PN = "1"  !CDS_PN = "1";
"B":   PN = "2"  !CDS_PN = "2";
DRAWING = "@baseboard_fab2_lib.baseboard_fab2(sch_1):page87";
BODY = "SCONN288_H44441004","I169": #LOCATION = "J1A1" !CDS_LOCATION = "J1A1" #SEC = "4" !CDS_SEC = "4";
"12V<0>":   PN = "145"  !CDS_PN = "145";
"12V<1>":   PN = "1"  !CDS_PN = "1";
"VDD<0>":   PN = "236"  !CDS_PN = "236";
"VDD<1>":   PN = "233"  !CDS_PN = "233";
"VDD<2>":   PN = "231"  !CDS_PN = "231";
"VDD<3>":   PN = "229"  !CDS_PN = "229";
"VDD<4>":   PN = "226"  !CDS_PN = "226";
"VDD<5>":   PN = "223"  !CDS_PN = "223";
"VDD<6>":   PN = "220"  !CDS_PN = "220";
"VDD<7>":   PN = "217"  !CDS_PN = "217";
"VDD<8>":   PN = "215"  !CDS_PN = "215";
"VDD<9>":   PN = "212"  !CDS_PN = "212";
"VDD<10>":   PN = "209"  !CDS_PN = "209";
"VDD<11>":   PN = "206"  !CDS_PN = "206";
"VDD<12>":   PN = "204"  !CDS_PN = "204";
"VDD<13>":   PN = "92"  !CDS_PN = "92";
"VDD<14>":   PN = "90"  !CDS_PN = "90";
"VDD<15>":   PN = "88"  !CDS_PN = "88";
"VDD<16>":   PN = "85"  !CDS_PN = "85";
"VDD<17>":   PN = "83"  !CDS_PN = "83";
"VDD<18>":   PN = "80"  !CDS_PN = "80";
"VDD<19>":   PN = "76"  !CDS_PN = "76";
"VDD<20>":   PN = "73"  !CDS_PN = "73";
"VDD<21>":   PN = "70"  !CDS_PN = "70";
"VDD<22>":   PN = "67"  !CDS_PN = "67";
"VDD<23>":   PN = "64"  !CDS_PN = "64";
"VDD<24>":   PN = "61"  !CDS_PN = "61";
"VDD<25>":   PN = "59"  !CDS_PN = "59";
"VPP<0>":   PN = "287"  !CDS_PN = "287";
"VPP<1>":   PN = "286"  !CDS_PN = "286";
"VPP<2>":   PN = "288"  !CDS_PN = "288";
"VPP<3>":   PN = "143"  !CDS_PN = "143";
"VPP<4>":   PN = "142"  !CDS_PN = "142";
"VTT<0>":   PN = "221"  !CDS_PN = "221";
"VTT<1>":   PN = "77"  !CDS_PN = "77";
BODY = "CAP_A","I178": #LOCATION = "C1A5" !CDS_LOCATION = "C1A5" #SEC = "1" !CDS_SEC = "1";
"A":   PN = "1"  !CDS_PN = "1";
"B":   PN = "2"  !CDS_PN = "2";
BODY = "SCONN288_H44441004","I185": #LOCATION = "J1A1" !CDS_LOCATION = "J1A1" #SEC = "3" !CDS_SEC = "3";
"VSS<0>":   PN = "283"  !CDS_PN = "283";
"VSS<1>":   PN = "281"  !CDS_PN = "281";
"VSS<2>":   PN = "279"  !CDS_PN = "279";
"VSS<3>":   PN = "276"  !CDS_PN = "276";
"VSS<4>":   PN = "274"  !CDS_PN = "274";
"VSS<5>":   PN = "272"  !CDS_PN = "272";
"VSS<6>":   PN = "270"  !CDS_PN = "270";
"VSS<7>":   PN = "268"  !CDS_PN = "268";
"VSS<8>":   PN = "265"  !CDS_PN = "265";
"VSS<9>":   PN = "263"  !CDS_PN = "263";
"VSS<10>":   PN = "261"  !CDS_PN = "261";
"VSS<11>":   PN = "259"  !CDS_PN = "259";
"VSS<12>":   PN = "257"  !CDS_PN = "257";
"VSS<13>":   PN = "254"  !CDS_PN = "254";
"VSS<14>":   PN = "252"  !CDS_PN = "252";
"VSS<15>":   PN = "250"  !CDS_PN = "250";
"VSS<16>":   PN = "248"  !CDS_PN = "248";
"VSS<17>":   PN = "246"  !CDS_PN = "246";
"VSS<18>":   PN = "243"  !CDS_PN = "243";
"VSS<19>":   PN = "241"  !CDS_PN = "241";
"VSS<20>":   PN = "239"  !CDS_PN = "239";
"VSS<21>":   PN = "202"  !CDS_PN = "202";
"VSS<22>":   PN = "200"  !CDS_PN = "200";
"VSS<23>":   PN = "198"  !CDS_PN = "198";
"VSS<24>":   PN = "195"  !CDS_PN = "195";
"VSS<25>":   PN = "193"  !CDS_PN = "193";
"VSS<26>":   PN = "191"  !CDS_PN = "191";
"VSS<27>":   PN = "189"  !CDS_PN = "189";
"VSS<28>":   PN = "187"  !CDS_PN = "187";
"VSS<29>":   PN = "184"  !CDS_PN = "184";
"VSS<30>":   PN = "182"  !CDS_PN = "182";
"VSS<31>":   PN = "180"  !CDS_PN = "180";
"VSS<32>":   PN = "178"  !CDS_PN = "178";
"VSS<33>":   PN = "176"  !CDS_PN = "176";
"VSS<34>":   PN = "173"  !CDS_PN = "173";
"VSS<35>":   PN = "171"  !CDS_PN = "171";
"VSS<36>":   PN = "169"  !CDS_PN = "169";
"VSS<37>":   PN = "167"  !CDS_PN = "167";
"VSS<38>":   PN = "165"  !CDS_PN = "165";
"VSS<39>":   PN = "162"  !CDS_PN = "162";
"VSS<40>":   PN = "160"  !CDS_PN = "160";
"VSS<41>":   PN = "158"  !CDS_PN = "158";
"VSS<42>":   PN = "156"  !CDS_PN = "156";
"VSS<43>":   PN = "154"  !CDS_PN = "154";
"VSS<44>":   PN = "151"  !CDS_PN = "151";
"VSS<45>":   PN = "149"  !CDS_PN = "149";
"VSS<46>":   PN = "147"  !CDS_PN = "147";
"VSS<47>":   PN = "138"  !CDS_PN = "138";
"VSS<48>":   PN = "136"  !CDS_PN = "136";
"VSS<49>":   PN = "134"  !CDS_PN = "134";
"VSS<50>":   PN = "131"  !CDS_PN = "131";
"VSS<51>":   PN = "129"  !CDS_PN = "129";
"VSS<52>":   PN = "127"  !CDS_PN = "127";
"VSS<53>":   PN = "125"  !CDS_PN = "125";
"VSS<54>":   PN = "123"  !CDS_PN = "123";
"VSS<55>":   PN = "120"  !CDS_PN = "120";
"VSS<56>":   PN = "118"  !CDS_PN = "118";
"VSS<57>":   PN = "116"  !CDS_PN = "116";
"VSS<58>":   PN = "114"  !CDS_PN = "114";
"VSS<59>":   PN = "112"  !CDS_PN = "112";
"VSS<60>":   PN = "109"  !CDS_PN = "109";
"VSS<61>":   PN = "107"  !CDS_PN = "107";
"VSS<62>":   PN = "105"  !CDS_PN = "105";
"VSS<63>":   PN = "103"  !CDS_PN = "103";
"VSS<64>":   PN = "101"  !CDS_PN = "101";
"VSS<65>":   PN = "98"  !CDS_PN = "98";
"VSS<66>":   PN = "96"  !CDS_PN = "96";
"VSS<67>":   PN = "94"  !CDS_PN = "94";
"VSS<68>":   PN = "57"  !CDS_PN = "57";
"VSS<69>":   PN = "55"  !CDS_PN = "55";
"VSS<70>":   PN = "53"  !CDS_PN = "53";
"VSS<71>":   PN = "50"  !CDS_PN = "50";
"VSS<72>":   PN = "48"  !CDS_PN = "48";
"VSS<73>":   PN = "46"  !CDS_PN = "46";
"VSS<74>":   PN = "44"  !CDS_PN = "44";
"VSS<75>":   PN = "42"  !CDS_PN = "42";
"VSS<76>":   PN = "39"  !CDS_PN = "39";
"VSS<77>":   PN = "37"  !CDS_PN = "37";
"VSS<78>":   PN = "35"  !CDS_PN = "35";
"VSS<79>":   PN = "33"  !CDS_PN = "33";
"VSS<80>":   PN = "31"  !CDS_PN = "31";
"VSS<81>":   PN = "28"  !CDS_PN = "28";
"VSS<82>":   PN = "26"  !CDS_PN = "26";
"VSS<83>":   PN = "24"  !CDS_PN = "24";
"VSS<84>":   PN = "22"  !CDS_PN = "22";
"VSS<85>":   PN = "20"  !CDS_PN = "20";
"VSS<86>":   PN = "17"  !CDS_PN = "17";
"VSS<87>":   PN = "15"  !CDS_PN = "15";
"VSS<88>":   PN = "13"  !CDS_PN = "13";
"VSS<89>":   PN = "11"  !CDS_PN = "11";
"VSS<90>":   PN = "9"  !CDS_PN = "9";
"VSS<91>":   PN = "6"  !CDS_PN = "6";
"VSS<92>":   PN = "4"  !CDS_PN = "4";
"VSS<93>":   PN = "2"  !CDS_PN = "2";
BODY = "SCONN288_H44441004","I186": #LOCATION = "J1A1" !CDS_LOCATION = "J1A1" #SEC = "1" !CDS_SEC = "1";
"A0":   PN = "79"  !CDS_PN = "79";
"A1":   PN = "72"  !CDS_PN = "72";
"A2":   PN = "216"  !CDS_PN = "216";
"A3":   PN = "71"  !CDS_PN = "71";
"A4":   PN = "214"  !CDS_PN = "214";
"A5":   PN = "213"  !CDS_PN = "213";
"A6":   PN = "69"  !CDS_PN = "69";
"A7":   PN = "211"  !CDS_PN = "211";
"A8":   PN = "68"  !CDS_PN = "68";
"A9":   PN = "66"  !CDS_PN = "66";
"A10":   PN = "225"  !CDS_PN = "225";
"A11":   PN = "210"  !CDS_PN = "210";
"A12":   PN = "65"  !CDS_PN = "65";
"A13":   PN = "232"  !CDS_PN = "232";
"A14_WE_N":   PN = "228"  !CDS_PN = "228";
"A15_CAS_N":   PN = "86"  !CDS_PN = "86";
"A16_RAS_N":   PN = "82"  !CDS_PN = "82";
"A17":   PN = "234"  !CDS_PN = "234";
"ACT_N":   PN = "62"  !CDS_PN = "62";
"ALERT_N":   PN = "208"  !CDS_PN = "208";
"BA<0>":   PN = "81"  !CDS_PN = "81";
"BA<1>":   PN = "224"  !CDS_PN = "224";
"BG<0>":   PN = "63"  !CDS_PN = "63";
"BG<1>":   PN = "207"  !CDS_PN = "207";
"C<2>":   PN = "235"  !CDS_PN = "235";
"CB<0>":   PN = "49"  !CDS_PN = "49";
"CB<1>":   PN = "194"  !CDS_PN = "194";
"CB<2>":   PN = "56"  !CDS_PN = "56";
"CB<3>":   PN = "201"  !CDS_PN = "201";
"CB<4>":   PN = "47"  !CDS_PN = "47";
"CB<5>":   PN = "192"  !CDS_PN = "192";
"CB<6>":   PN = "54"  !CDS_PN = "54";
"CB<7>":   PN = "199"  !CDS_PN = "199";
"CK0N":   PN = "75"  !CDS_PN = "75";
"CK0P":   PN = "74"  !CDS_PN = "74";
"CK1N":   PN = "219"  !CDS_PN = "219";
"CK1P":   PN = "218"  !CDS_PN = "218";
"CKE<0>":   PN = "60"  !CDS_PN = "60";
"CKE<1>":   PN = "203"  !CDS_PN = "203";
"DQ<0>":   PN = "5"  !CDS_PN = "5";
"DQ<1>":   PN = "150"  !CDS_PN = "150";
"DQ<2>":   PN = "12"  !CDS_PN = "12";
"DQ<3>":   PN = "157"  !CDS_PN = "157";
"DQ<4>":   PN = "3"  !CDS_PN = "3";
"DQ<5>":   PN = "148"  !CDS_PN = "148";
"DQ<6>":   PN = "10"  !CDS_PN = "10";
"DQ<7>":   PN = "155"  !CDS_PN = "155";
"DQ<8>":   PN = "16"  !CDS_PN = "16";
"DQ<9>":   PN = "161"  !CDS_PN = "161";
"DQ<10>":   PN = "23"  !CDS_PN = "23";
"DQ<11>":   PN = "168"  !CDS_PN = "168";
"DQ<12>":   PN = "14"  !CDS_PN = "14";
"DQ<13>":   PN = "159"  !CDS_PN = "159";
"DQ<14>":   PN = "21"  !CDS_PN = "21";
"DQ<15>":   PN = "166"  !CDS_PN = "166";
"DQ<16>":   PN = "27"  !CDS_PN = "27";
"DQ<17>":   PN = "172"  !CDS_PN = "172";
"DQ<18>":   PN = "34"  !CDS_PN = "34";
"DQ<19>":   PN = "179"  !CDS_PN = "179";
"DQ<20>":   PN = "25"  !CDS_PN = "25";
"DQ<21>":   PN = "170"  !CDS_PN = "170";
"DQ<22>":   PN = "32"  !CDS_PN = "32";
"DQ<23>":   PN = "177"  !CDS_PN = "177";
"DQ<24>":   PN = "38"  !CDS_PN = "38";
"DQ<25>":   PN = "183"  !CDS_PN = "183";
"DQ<26>":   PN = "45"  !CDS_PN = "45";
"DQ<27>":   PN = "190"  !CDS_PN = "190";
"DQ<28>":   PN = "36"  !CDS_PN = "36";
"DQ<29>":   PN = "181"  !CDS_PN = "181";
"DQ<30>":   PN = "43"  !CDS_PN = "43";
"DQ<31>":   PN = "188"  !CDS_PN = "188";
"DQ<32>":   PN = "97"  !CDS_PN = "97";
"DQ<33>":   PN = "242"  !CDS_PN = "242";
"DQ<34>":   PN = "104"  !CDS_PN = "104";
"DQ<35>":   PN = "249"  !CDS_PN = "249";
"DQ<36>":   PN = "95"  !CDS_PN = "95";
"DQ<37>":   PN = "240"  !CDS_PN = "240";
"DQ<38>":   PN = "102"  !CDS_PN = "102";
"DQ<39>":   PN = "247"  !CDS_PN = "247";
"DQ<40>":   PN = "108"  !CDS_PN = "108";
"DQ<41>":   PN = "253"  !CDS_PN = "253";
"DQ<42>":   PN = "115"  !CDS_PN = "115";
"DQ<43>":   PN = "260"  !CDS_PN = "260";
"DQ<44>":   PN = "106"  !CDS_PN = "106";
"DQ<45>":   PN = "251"  !CDS_PN = "251";
"DQ<46>":   PN = "113"  !CDS_PN = "113";
"DQ<47>":   PN = "258"  !CDS_PN = "258";
"DQ<48>":   PN = "119"  !CDS_PN = "119";
"DQ<49>":   PN = "264"  !CDS_PN = "264";
"DQ<50>":   PN = "126"  !CDS_PN = "126";
"DQ<51>":   PN = "271"  !CDS_PN = "271";
"DQ<52>":   PN = "117"  !CDS_PN = "117";
"DQ<53>":   PN = "262"  !CDS_PN = "262";
"DQ<54>":   PN = "124"  !CDS_PN = "124";
"DQ<55>":   PN = "269"  !CDS_PN = "269";
"DQ<56>":   PN = "130"  !CDS_PN = "130";
"DQ<57>":   PN = "275"  !CDS_PN = "275";
"DQ<58>":   PN = "137"  !CDS_PN = "137";
"DQ<59>":   PN = "282"  !CDS_PN = "282";
"DQ<60>":   PN = "128"  !CDS_PN = "128";
"DQ<61>":   PN = "273"  !CDS_PN = "273";
"DQ<62>":   PN = "135"  !CDS_PN = "135";
"DQ<63>":   PN = "280"  !CDS_PN = "280";
"EVENT_N":   PN = "78"  !CDS_PN = "78";
"ODT<0>":   PN = "87"  !CDS_PN = "87";
"ODT<1>":   PN = "91"  !CDS_PN = "91";
"PAR":   PN = "222"  !CDS_PN = "222";
"RESET_N":   PN = "58"  !CDS_PN = "58";
"RFU<0>":   PN = "205"  !CDS_PN = "205";
"RFU<1>":   PN = "227"  !CDS_PN = "227";
"RFU<2>":   PN = "144"  !CDS_PN = "144";
"S0_N":   PN = "84"  !CDS_PN = "84";
"S1_N":   PN = "89"  !CDS_PN = "89";
"S2_N_C<0>":   PN = "93"  !CDS_PN = "93";
"S3_N_C<1>":   PN = "237"  !CDS_PN = "237";
"SA<0>":   PN = "139"  !CDS_PN = "139";
"SA<1>":   PN = "140"  !CDS_PN = "140";
"SA<2>":   PN = "238"  !CDS_PN = "238";
"SAVE_N_NC":   PN = "230"  !CDS_PN = "230";
"SCL":   PN = "141"  !CDS_PN = "141";
"SDA":   PN = "285"  !CDS_PN = "285";
"VDDSPD":   PN = "284"  !CDS_PN = "284";
"VREFCA":   PN = "146"  !CDS_PN = "146";
BODY = "SCONN288_H44441004","I187": #LOCATION = "J1A1" !CDS_LOCATION = "J1A1" #SEC = "2" !CDS_SEC = "2";
"DQS0N":   PN = "152"  !CDS_PN = "152";
"DQS0P":   PN = "153"  !CDS_PN = "153";
"DQS1N":   PN = "163"  !CDS_PN = "163";
"DQS1P":   PN = "164"  !CDS_PN = "164";
"DQS2N":   PN = "174"  !CDS_PN = "174";
"DQS2P":   PN = "175"  !CDS_PN = "175";
"DQS3N":   PN = "185"  !CDS_PN = "185";
"DQS3P":   PN = "186"  !CDS_PN = "186";
"DQS4N":   PN = "244"  !CDS_PN = "244";
"DQS4P":   PN = "245"  !CDS_PN = "245";
"DQS5N":   PN = "255"  !CDS_PN = "255";
"DQS5P":   PN = "256"  !CDS_PN = "256";
"DQS6N":   PN = "266"  !CDS_PN = "266";
"DQS6P":   PN = "267"  !CDS_PN = "267";
"DQS7N":   PN = "277"  !CDS_PN = "277";
"DQS7P":   PN = "278"  !CDS_PN = "278";
"DQS8N":   PN = "196"  !CDS_PN = "196";
"DQS8P":   PN = "197"  !CDS_PN = "197";
"DQS9N":   PN = "8"  !CDS_PN = "8";
"DQS9P":   PN = "7"  !CDS_PN = "7";
"DQS10N":   PN = "19"  !CDS_PN = "19";
"DQS10P":   PN = "18"  !CDS_PN = "18";
"DQS11N":   PN = "30"  !CDS_PN = "30";
"DQS11P":   PN = "29"  !CDS_PN = "29";
"DQS12N":   PN = "41"  !CDS_PN = "41";
"DQS12P":   PN = "40"  !CDS_PN = "40";
"DQS13N":   PN = "100"  !CDS_PN = "100";
"DQS13P":   PN = "99"  !CDS_PN = "99";
"DQS14N":   PN = "111"  !CDS_PN = "111";
"DQS14P":   PN = "110"  !CDS_PN = "110";
"DQS15N":   PN = "122"  !CDS_PN = "122";
"DQS15P":   PN = "121"  !CDS_PN = "121";
"DQS16N":   PN = "133"  !CDS_PN = "133";
"DQS16P":   PN = "132"  !CDS_PN = "132";
"DQS17N":   PN = "52"  !CDS_PN = "52";
"DQS17P":   PN = "51"  !CDS_PN = "51";
DRAWING = "@baseboard_fab2_lib.baseboard_fab2(sch_1):page88";
BODY = "SCONN288_H44441003","I25": #LOCATION = "J9L1" !CDS_LOCATION = "J9L1" #SEC = "3" !CDS_SEC = "3";
"VSS<0>":   PN = "283"  !CDS_PN = "283";
"VSS<1>":   PN = "281"  !CDS_PN = "281";
"VSS<2>":   PN = "279"  !CDS_PN = "279";
"VSS<3>":   PN = "276"  !CDS_PN = "276";
"VSS<4>":   PN = "274"  !CDS_PN = "274";
"VSS<5>":   PN = "272"  !CDS_PN = "272";
"VSS<6>":   PN = "270"  !CDS_PN = "270";
"VSS<7>":   PN = "268"  !CDS_PN = "268";
"VSS<8>":   PN = "265"  !CDS_PN = "265";
"VSS<9>":   PN = "263"  !CDS_PN = "263";
"VSS<10>":   PN = "261"  !CDS_PN = "261";
"VSS<11>":   PN = "259"  !CDS_PN = "259";
"VSS<12>":   PN = "257"  !CDS_PN = "257";
"VSS<13>":   PN = "254"  !CDS_PN = "254";
"VSS<14>":   PN = "252"  !CDS_PN = "252";
"VSS<15>":   PN = "250"  !CDS_PN = "250";
"VSS<16>":   PN = "248"  !CDS_PN = "248";
"VSS<17>":   PN = "246"  !CDS_PN = "246";
"VSS<18>":   PN = "243"  !CDS_PN = "243";
"VSS<19>":   PN = "241"  !CDS_PN = "241";
"VSS<20>":   PN = "239"  !CDS_PN = "239";
"VSS<21>":   PN = "202"  !CDS_PN = "202";
"VSS<22>":   PN = "200"  !CDS_PN = "200";
"VSS<23>":   PN = "198"  !CDS_PN = "198";
"VSS<24>":   PN = "195"  !CDS_PN = "195";
"VSS<25>":   PN = "193"  !CDS_PN = "193";
"VSS<26>":   PN = "191"  !CDS_PN = "191";
"VSS<27>":   PN = "189"  !CDS_PN = "189";
"VSS<28>":   PN = "187"  !CDS_PN = "187";
"VSS<29>":   PN = "184"  !CDS_PN = "184";
"VSS<30>":   PN = "182"  !CDS_PN = "182";
"VSS<31>":   PN = "180"  !CDS_PN = "180";
"VSS<32>":   PN = "178"  !CDS_PN = "178";
"VSS<33>":   PN = "176"  !CDS_PN = "176";
"VSS<34>":   PN = "173"  !CDS_PN = "173";
"VSS<35>":   PN = "171"  !CDS_PN = "171";
"VSS<36>":   PN = "169"  !CDS_PN = "169";
"VSS<37>":   PN = "167"  !CDS_PN = "167";
"VSS<38>":   PN = "165"  !CDS_PN = "165";
"VSS<39>":   PN = "162"  !CDS_PN = "162";
"VSS<40>":   PN = "160"  !CDS_PN = "160";
"VSS<41>":   PN = "158"  !CDS_PN = "158";
"VSS<42>":   PN = "156"  !CDS_PN = "156";
"VSS<43>":   PN = "154"  !CDS_PN = "154";
"VSS<44>":   PN = "151"  !CDS_PN = "151";
"VSS<45>":   PN = "149"  !CDS_PN = "149";
"VSS<46>":   PN = "147"  !CDS_PN = "147";
"VSS<47>":   PN = "138"  !CDS_PN = "138";
"VSS<48>":   PN = "136"  !CDS_PN = "136";
"VSS<49>":   PN = "134"  !CDS_PN = "134";
"VSS<50>":   PN = "131"  !CDS_PN = "131";
"VSS<51>":   PN = "129"  !CDS_PN = "129";
"VSS<52>":   PN = "127"  !CDS_PN = "127";
"VSS<53>":   PN = "125"  !CDS_PN = "125";
"VSS<54>":   PN = "123"  !CDS_PN = "123";
"VSS<55>":   PN = "120"  !CDS_PN = "120";
"VSS<56>":   PN = "118"  !CDS_PN = "118";
"VSS<57>":   PN = "116"  !CDS_PN = "116";
"VSS<58>":   PN = "114"  !CDS_PN = "114";
"VSS<59>":   PN = "112"  !CDS_PN = "112";
"VSS<60>":   PN = "109"  !CDS_PN = "109";
"VSS<61>":   PN = "107"  !CDS_PN = "107";
"VSS<62>":   PN = "105"  !CDS_PN = "105";
"VSS<63>":   PN = "103"  !CDS_PN = "103";
"VSS<64>":   PN = "101"  !CDS_PN = "101";
"VSS<65>":   PN = "98"  !CDS_PN = "98";
"VSS<66>":   PN = "96"  !CDS_PN = "96";
"VSS<67>":   PN = "94"  !CDS_PN = "94";
"VSS<68>":   PN = "57"  !CDS_PN = "57";
"VSS<69>":   PN = "55"  !CDS_PN = "55";
"VSS<70>":   PN = "53"  !CDS_PN = "53";
"VSS<71>":   PN = "50"  !CDS_PN = "50";
"VSS<72>":   PN = "48"  !CDS_PN = "48";
"VSS<73>":   PN = "46"  !CDS_PN = "46";
"VSS<74>":   PN = "44"  !CDS_PN = "44";
"VSS<75>":   PN = "42"  !CDS_PN = "42";
"VSS<76>":   PN = "39"  !CDS_PN = "39";
"VSS<77>":   PN = "37"  !CDS_PN = "37";
"VSS<78>":   PN = "35"  !CDS_PN = "35";
"VSS<79>":   PN = "33"  !CDS_PN = "33";
"VSS<80>":   PN = "31"  !CDS_PN = "31";
"VSS<81>":   PN = "28"  !CDS_PN = "28";
"VSS<82>":   PN = "26"  !CDS_PN = "26";
"VSS<83>":   PN = "24"  !CDS_PN = "24";
"VSS<84>":   PN = "22"  !CDS_PN = "22";
"VSS<85>":   PN = "20"  !CDS_PN = "20";
"VSS<86>":   PN = "17"  !CDS_PN = "17";
"VSS<87>":   PN = "15"  !CDS_PN = "15";
"VSS<88>":   PN = "13"  !CDS_PN = "13";
"VSS<89>":   PN = "11"  !CDS_PN = "11";
"VSS<90>":   PN = "9"  !CDS_PN = "9";
"VSS<91>":   PN = "6"  !CDS_PN = "6";
"VSS<92>":   PN = "4"  !CDS_PN = "4";
"VSS<93>":   PN = "2"  !CDS_PN = "2";
BODY = "SCONN288_H44441003","I87": #LOCATION = "J9L1" !CDS_LOCATION = "J9L1" #SEC = "2" !CDS_SEC = "2";
"DQS0N":   PN = "152"  !CDS_PN = "152";
"DQS0P":   PN = "153"  !CDS_PN = "153";
"DQS1N":   PN = "163"  !CDS_PN = "163";
"DQS1P":   PN = "164"  !CDS_PN = "164";
"DQS2N":   PN = "174"  !CDS_PN = "174";
"DQS2P":   PN = "175"  !CDS_PN = "175";
"DQS3N":   PN = "185"  !CDS_PN = "185";
"DQS3P":   PN = "186"  !CDS_PN = "186";
"DQS4N":   PN = "244"  !CDS_PN = "244";
"DQS4P":   PN = "245"  !CDS_PN = "245";
"DQS5N":   PN = "255"  !CDS_PN = "255";
"DQS5P":   PN = "256"  !CDS_PN = "256";
"DQS6N":   PN = "266"  !CDS_PN = "266";
"DQS6P":   PN = "267"  !CDS_PN = "267";
"DQS7N":   PN = "277"  !CDS_PN = "277";
"DQS7P":   PN = "278"  !CDS_PN = "278";
"DQS8N":   PN = "196"  !CDS_PN = "196";
"DQS8P":   PN = "197"  !CDS_PN = "197";
"DQS9N":   PN = "8"  !CDS_PN = "8";
"DQS9P":   PN = "7"  !CDS_PN = "7";
"DQS10N":   PN = "19"  !CDS_PN = "19";
"DQS10P":   PN = "18"  !CDS_PN = "18";
"DQS11N":   PN = "30"  !CDS_PN = "30";
"DQS11P":   PN = "29"  !CDS_PN = "29";
"DQS12N":   PN = "41"  !CDS_PN = "41";
"DQS12P":   PN = "40"  !CDS_PN = "40";
"DQS13N":   PN = "100"  !CDS_PN = "100";
"DQS13P":   PN = "99"  !CDS_PN = "99";
"DQS14N":   PN = "111"  !CDS_PN = "111";
"DQS14P":   PN = "110"  !CDS_PN = "110";
"DQS15N":   PN = "122"  !CDS_PN = "122";
"DQS15P":   PN = "121"  !CDS_PN = "121";
"DQS16N":   PN = "133"  !CDS_PN = "133";
"DQS16P":   PN = "132"  !CDS_PN = "132";
"DQS17N":   PN = "52"  !CDS_PN = "52";
"DQS17P":   PN = "51"  !CDS_PN = "51";
BODY = "SCONN288_H44441003","I111": #LOCATION = "J9L1" !CDS_LOCATION = "J9L1" #SEC = "1" !CDS_SEC = "1";
"A0":   PN = "79"  !CDS_PN = "79";
"A1":   PN = "72"  !CDS_PN = "72";
"A2":   PN = "216"  !CDS_PN = "216";
"A3":   PN = "71"  !CDS_PN = "71";
"A4":   PN = "214"  !CDS_PN = "214";
"A5":   PN = "213"  !CDS_PN = "213";
"A6":   PN = "69"  !CDS_PN = "69";
"A7":   PN = "211"  !CDS_PN = "211";
"A8":   PN = "68"  !CDS_PN = "68";
"A9":   PN = "66"  !CDS_PN = "66";
"A10":   PN = "225"  !CDS_PN = "225";
"A11":   PN = "210"  !CDS_PN = "210";
"A12":   PN = "65"  !CDS_PN = "65";
"A13":   PN = "232"  !CDS_PN = "232";
"A14_WE_N":   PN = "228"  !CDS_PN = "228";
"A15_CAS_N":   PN = "86"  !CDS_PN = "86";
"A16_RAS_N":   PN = "82"  !CDS_PN = "82";
"A17":   PN = "234"  !CDS_PN = "234";
"ACT_N":   PN = "62"  !CDS_PN = "62";
"ALERT_N":   PN = "208"  !CDS_PN = "208";
"BA<0>":   PN = "81"  !CDS_PN = "81";
"BA<1>":   PN = "224"  !CDS_PN = "224";
"BG<0>":   PN = "63"  !CDS_PN = "63";
"BG<1>":   PN = "207"  !CDS_PN = "207";
"C<2>":   PN = "235"  !CDS_PN = "235";
"CB<0>":   PN = "49"  !CDS_PN = "49";
"CB<1>":   PN = "194"  !CDS_PN = "194";
"CB<2>":   PN = "56"  !CDS_PN = "56";
"CB<3>":   PN = "201"  !CDS_PN = "201";
"CB<4>":   PN = "47"  !CDS_PN = "47";
"CB<5>":   PN = "192"  !CDS_PN = "192";
"CB<6>":   PN = "54"  !CDS_PN = "54";
"CB<7>":   PN = "199"  !CDS_PN = "199";
"CK0N":   PN = "75"  !CDS_PN = "75";
"CK0P":   PN = "74"  !CDS_PN = "74";
"CK1N":   PN = "219"  !CDS_PN = "219";
"CK1P":   PN = "218"  !CDS_PN = "218";
"CKE<0>":   PN = "60"  !CDS_PN = "60";
"CKE<1>":   PN = "203"  !CDS_PN = "203";
"DQ<0>":   PN = "5"  !CDS_PN = "5";
"DQ<1>":   PN = "150"  !CDS_PN = "150";
"DQ<2>":   PN = "12"  !CDS_PN = "12";
"DQ<3>":   PN = "157"  !CDS_PN = "157";
"DQ<4>":   PN = "3"  !CDS_PN = "3";
"DQ<5>":   PN = "148"  !CDS_PN = "148";
"DQ<6>":   PN = "10"  !CDS_PN = "10";
"DQ<7>":   PN = "155"  !CDS_PN = "155";
"DQ<8>":   PN = "16"  !CDS_PN = "16";
"DQ<9>":   PN = "161"  !CDS_PN = "161";
"DQ<10>":   PN = "23"  !CDS_PN = "23";
"DQ<11>":   PN = "168"  !CDS_PN = "168";
"DQ<12>":   PN = "14"  !CDS_PN = "14";
"DQ<13>":   PN = "159"  !CDS_PN = "159";
"DQ<14>":   PN = "21"  !CDS_PN = "21";
"DQ<15>":   PN = "166"  !CDS_PN = "166";
"DQ<16>":   PN = "27"  !CDS_PN = "27";
"DQ<17>":   PN = "172"  !CDS_PN = "172";
"DQ<18>":   PN = "34"  !CDS_PN = "34";
"DQ<19>":   PN = "179"  !CDS_PN = "179";
"DQ<20>":   PN = "25"  !CDS_PN = "25";
"DQ<21>":   PN = "170"  !CDS_PN = "170";
"DQ<22>":   PN = "32"  !CDS_PN = "32";
"DQ<23>":   PN = "177"  !CDS_PN = "177";
"DQ<24>":   PN = "38"  !CDS_PN = "38";
"DQ<25>":   PN = "183"  !CDS_PN = "183";
"DQ<26>":   PN = "45"  !CDS_PN = "45";
"DQ<27>":   PN = "190"  !CDS_PN = "190";
"DQ<28>":   PN = "36"  !CDS_PN = "36";
"DQ<29>":   PN = "181"  !CDS_PN = "181";
"DQ<30>":   PN = "43"  !CDS_PN = "43";
"DQ<31>":   PN = "188"  !CDS_PN = "188";
"DQ<32>":   PN = "97"  !CDS_PN = "97";
"DQ<33>":   PN = "242"  !CDS_PN = "242";
"DQ<34>":   PN = "104"  !CDS_PN = "104";
"DQ<35>":   PN = "249"  !CDS_PN = "249";
"DQ<36>":   PN = "95"  !CDS_PN = "95";
"DQ<37>":   PN = "240"  !CDS_PN = "240";
"DQ<38>":   PN = "102"  !CDS_PN = "102";
"DQ<39>":   PN = "247"  !CDS_PN = "247";
"DQ<40>":   PN = "108"  !CDS_PN = "108";
"DQ<41>":   PN = "253"  !CDS_PN = "253";
"DQ<42>":   PN = "115"  !CDS_PN = "115";
"DQ<43>":   PN = "260"  !CDS_PN = "260";
"DQ<44>":   PN = "106"  !CDS_PN = "106";
"DQ<45>":   PN = "251"  !CDS_PN = "251";
"DQ<46>":   PN = "113"  !CDS_PN = "113";
"DQ<47>":   PN = "258"  !CDS_PN = "258";
"DQ<48>":   PN = "119"  !CDS_PN = "119";
"DQ<49>":   PN = "264"  !CDS_PN = "264";
"DQ<50>":   PN = "126"  !CDS_PN = "126";
"DQ<51>":   PN = "271"  !CDS_PN = "271";
"DQ<52>":   PN = "117"  !CDS_PN = "117";
"DQ<53>":   PN = "262"  !CDS_PN = "262";
"DQ<54>":   PN = "124"  !CDS_PN = "124";
"DQ<55>":   PN = "269"  !CDS_PN = "269";
"DQ<56>":   PN = "130"  !CDS_PN = "130";
"DQ<57>":   PN = "275"  !CDS_PN = "275";
"DQ<58>":   PN = "137"  !CDS_PN = "137";
"DQ<59>":   PN = "282"  !CDS_PN = "282";
"DQ<60>":   PN = "128"  !CDS_PN = "128";
"DQ<61>":   PN = "273"  !CDS_PN = "273";
"DQ<62>":   PN = "135"  !CDS_PN = "135";
"DQ<63>":   PN = "280"  !CDS_PN = "280";
"EVENT_N":   PN = "78"  !CDS_PN = "78";
"ODT<0>":   PN = "87"  !CDS_PN = "87";
"ODT<1>":   PN = "91"  !CDS_PN = "91";
"PAR":   PN = "222"  !CDS_PN = "222";
"RESET_N":   PN = "58"  !CDS_PN = "58";
"RFU<0>":   PN = "205"  !CDS_PN = "205";
"RFU<1>":   PN = "227"  !CDS_PN = "227";
"RFU<2>":   PN = "144"  !CDS_PN = "144";
"S0_N":   PN = "84"  !CDS_PN = "84";
"S1_N":   PN = "89"  !CDS_PN = "89";
"S2_N_C<0>":   PN = "93"  !CDS_PN = "93";
"S3_N_C<1>":   PN = "237"  !CDS_PN = "237";
"SA<0>":   PN = "139"  !CDS_PN = "139";
"SA<1>":   PN = "140"  !CDS_PN = "140";
"SA<2>":   PN = "238"  !CDS_PN = "238";
"SAVE_N_NC":   PN = "230"  !CDS_PN = "230";
"SCL":   PN = "141"  !CDS_PN = "141";
"SDA":   PN = "285"  !CDS_PN = "285";
"VDDSPD":   PN = "284"  !CDS_PN = "284";
"VREFCA":   PN = "146"  !CDS_PN = "146";
BODY = "SCONN288_H44441003","I168": #LOCATION = "J9L1" !CDS_LOCATION = "J9L1" #SEC = "4" !CDS_SEC = "4";
"12V<0>":   PN = "145"  !CDS_PN = "145";
"12V<1>":   PN = "1"  !CDS_PN = "1";
"VDD<0>":   PN = "236"  !CDS_PN = "236";
"VDD<1>":   PN = "233"  !CDS_PN = "233";
"VDD<2>":   PN = "231"  !CDS_PN = "231";
"VDD<3>":   PN = "229"  !CDS_PN = "229";
"VDD<4>":   PN = "226"  !CDS_PN = "226";
"VDD<5>":   PN = "223"  !CDS_PN = "223";
"VDD<6>":   PN = "220"  !CDS_PN = "220";
"VDD<7>":   PN = "217"  !CDS_PN = "217";
"VDD<8>":   PN = "215"  !CDS_PN = "215";
"VDD<9>":   PN = "212"  !CDS_PN = "212";
"VDD<10>":   PN = "209"  !CDS_PN = "209";
"VDD<11>":   PN = "206"  !CDS_PN = "206";
"VDD<12>":   PN = "204"  !CDS_PN = "204";
"VDD<13>":   PN = "92"  !CDS_PN = "92";
"VDD<14>":   PN = "90"  !CDS_PN = "90";
"VDD<15>":   PN = "88"  !CDS_PN = "88";
"VDD<16>":   PN = "85"  !CDS_PN = "85";
"VDD<17>":   PN = "83"  !CDS_PN = "83";
"VDD<18>":   PN = "80"  !CDS_PN = "80";
"VDD<19>":   PN = "76"  !CDS_PN = "76";
"VDD<20>":   PN = "73"  !CDS_PN = "73";
"VDD<21>":   PN = "70"  !CDS_PN = "70";
"VDD<22>":   PN = "67"  !CDS_PN = "67";
"VDD<23>":   PN = "64"  !CDS_PN = "64";
"VDD<24>":   PN = "61"  !CDS_PN = "61";
"VDD<25>":   PN = "59"  !CDS_PN = "59";
"VPP<0>":   PN = "287"  !CDS_PN = "287";
"VPP<1>":   PN = "286"  !CDS_PN = "286";
"VPP<2>":   PN = "288"  !CDS_PN = "288";
"VPP<3>":   PN = "143"  !CDS_PN = "143";
"VPP<4>":   PN = "142"  !CDS_PN = "142";
"VTT<0>":   PN = "221"  !CDS_PN = "221";
"VTT<1>":   PN = "77"  !CDS_PN = "77";
BODY = "CAP_A","I177": #LOCATION = "C9L1" !CDS_LOCATION = "C9L1" #SEC = "1" !CDS_SEC = "1";
"A":   PN = "1"  !CDS_PN = "1";
"B":   PN = "2"  !CDS_PN = "2";
DRAWING = "@baseboard_fab2_lib.baseboard_fab2(sch_1):page89";
BODY = "RES","I1": #LOCATION = "R4T2" !CDS_LOCATION = "R4T2" #SEC = "1" !CDS_SEC = "1";
"A":   PN = "1"  !CDS_PN = "1";
"B":   PN = "2"  !CDS_PN = "2";
BODY = "RES","I2": #LOCATION = "R4T1" !CDS_LOCATION = "R4T1" #SEC = "1" !CDS_SEC = "1";
"A":   PN = "1"  !CDS_PN = "1";
"B":   PN = "2"  !CDS_PN = "2";
BODY = "RES","I3": #LOCATION = "R6F4" !CDS_LOCATION = "R6F4" #SEC = "1" !CDS_SEC = "1";
"A":   PN = "1"  !CDS_PN = "1";
"B":   PN = "2"  !CDS_PN = "2";
BODY = "RES","I4": #LOCATION = "R6F1" !CDS_LOCATION = "R6F1" #SEC = "1" !CDS_SEC = "1";
"A":   PN = "1"  !CDS_PN = "1";
"B":   PN = "2"  !CDS_PN = "2";
BODY = "RES","I5": #LOCATION = "R6F5" !CDS_LOCATION = "R6F5" #SEC = "1" !CDS_SEC = "1";
"A":   PN = "1"  !CDS_PN = "1";
"B":   PN = "2"  !CDS_PN = "2";
BODY = "RES","I6": #LOCATION = "R6F2" !CDS_LOCATION = "R6F2" #SEC = "1" !CDS_SEC = "1";
"A":   PN = "1"  !CDS_PN = "1";
"B":   PN = "2"  !CDS_PN = "2";
BODY = "RES","I7": #LOCATION = "R6F3" !CDS_LOCATION = "R6F3" #SEC = "1" !CDS_SEC = "1";
"A":   PN = "1"  !CDS_PN = "1";
"B":   PN = "2"  !CDS_PN = "2";
BODY = "RES","I23": #LOCATION = "R2P12" !CDS_LOCATION = "R2P12" &SEC = "1" #&CDS_SEC = "1";
"A":   PN = "1"  !CDS_PN = "1";
"B":   PN = "2"  !CDS_PN = "2";
BODY = "RES","I26": #LOCATION = "R8D29" !CDS_LOCATION = "R8D29" &SEC = "1" #&CDS_SEC = "1";
"A":   PN = "1"  !CDS_PN = "1";
"B":   PN = "2"  !CDS_PN = "2";
BODY = "RES","I27": #LOCATION = "R8D31" !CDS_LOCATION = "R8D31" &SEC = "1" #&CDS_SEC = "1";
"A":   PN = "1"  !CDS_PN = "1";
"B":   PN = "2"  !CDS_PN = "2";
BODY = "RES","I34": #LOCATION = "R8D30" !CDS_LOCATION = "R8D30" #SEC = "1" !CDS_SEC = "1";
"A":   PN = "1"  !CDS_PN = "1";
"B":   PN = "2"  !CDS_PN = "2";
BODY = "NPN_DUAL","I35": #LOCATION = "Q8D1" !CDS_LOCATION = "Q8D1" #SEC = "1" !CDS_SEC = "1";
"B<0>":   PN = "5"  !CDS_PN = "5";
"C<0>":   PN = "3"  !CDS_PN = "3";
"E<0>":   PN = "4"  !CDS_PN = "4";
BODY = "RES","I40": #LOCATION = "R6W29" !CDS_LOCATION = "R6W29" #SEC = "1" !CDS_SEC = "1";
"A":   PN = "1"  !CDS_PN = "1";
"B":   PN = "2"  !CDS_PN = "2";
BODY = "RES","I45": #LOCATION = "WR8D30" !CDS_LOCATION = "WR8D30" #SEC = "1" !CDS_SEC = "1";
"A":   PN = "1"  !CDS_PN = "1";
"B":   PN = "2"  !CDS_PN = "2";
BODY = "NPN_DUAL","I46": #LOCATION = "Q8D1" !CDS_LOCATION = "Q8D1" #SEC = "2" !CDS_SEC = "2";
"B<0>":   PN = "2"  !CDS_PN = "2";
"C<0>":   PN = "6"  !CDS_PN = "6";
"E<0>":   PN = "1"  !CDS_PN = "1";
BODY = "RES","I49": #LOCATION = "R8W9" !CDS_LOCATION = "R8W9" #SEC = "1" !CDS_SEC = "1";
"A":   PN = "1"  !CDS_PN = "1";
"B":   PN = "2"  !CDS_PN = "2";
BODY = "NPN_DUAL","I51": #LOCATION = "Q8W1" !CDS_LOCATION = "Q8W1" #SEC = "2" !CDS_SEC = "2";
"B<0>":   PN = "2"  !CDS_PN = "2";
"C<0>":   PN = "6"  !CDS_PN = "6";
"E<0>":   PN = "1"  !CDS_PN = "1";
BODY = "NPN_DUAL","I52": #LOCATION = "Q8W1" !CDS_LOCATION = "Q8W1" #SEC = "1" !CDS_SEC = "1";
"B<0>":   PN = "5"  !CDS_PN = "5";
"C<0>":   PN = "3"  !CDS_PN = "3";
"E<0>":   PN = "4"  !CDS_PN = "4";
BODY = "NPN","I53": #LOCATION = "Q1F1" !CDS_LOCATION = "Q1F1" #SEC = "1" !CDS_SEC = "1";
"B":   PN = "1"  !CDS_PN = "1";
"C":   PN = "3"  !CDS_PN = "3";
"E":   PN = "2"  !CDS_PN = "2";
BODY = "RES","I54": #LOCATION = "R1W32" !CDS_LOCATION = "R1W32" #SEC = "1" !CDS_SEC = "1";
"A":   PN = "1"  !CDS_PN = "1";
"B":   PN = "2"  !CDS_PN = "2";
BODY = "NPN","I55": #LOCATION = "Q1W6" !CDS_LOCATION = "Q1W6" #SEC = "1" !CDS_SEC = "1";
"B":   PN = "1"  !CDS_PN = "1";
"C":   PN = "3"  !CDS_PN = "3";
"E":   PN = "2"  !CDS_PN = "2";
BODY = "RES","I56": #LOCATION = "R1W31" !CDS_LOCATION = "R1W31" #SEC = "1" !CDS_SEC = "1";
"A":   PN = "1"  !CDS_PN = "1";
"B":   PN = "2"  !CDS_PN = "2";
DRAWING = "@baseboard_fab2_lib.baseboard_fab2(sch_1):page90";
BODY = "RES","I17": #LOCATION = "R3D22" !CDS_LOCATION = "R3D22" #SEC = "1" !CDS_SEC = "1";
"A":   PN = "1"  !CDS_PN = "1";
"B":   PN = "2"  !CDS_PN = "2";
BODY = "RES","I24": #LOCATION = "R3D16" !CDS_LOCATION = "R3D16" #SEC = "1" !CDS_SEC = "1";
"A":   PN = "1"  !CDS_PN = "1";
"B":   PN = "2"  !CDS_PN = "2";
BODY = "RES","I25": #LOCATION = "R3D23" !CDS_LOCATION = "R3D23" &SEC = "1" #&CDS_SEC = "1";
"A":   PN = "1"  !CDS_PN = "1";
"B":   PN = "2"  !CDS_PN = "2";
BODY = "RES","I28": #LOCATION = "R3D26" !CDS_LOCATION = "R3D26" #SEC = "1" !CDS_SEC = "1";
"A":   PN = "1"  !CDS_PN = "1";
"B":   PN = "2"  !CDS_PN = "2";
BODY = "RES","I29": #LOCATION = "R5D3" !CDS_LOCATION = "R5D3" #SEC = "1" !CDS_SEC = "1";
"A":   PN = "1"  !CDS_PN = "1";
"B":   PN = "2"  !CDS_PN = "2";
BODY = "RES","I31": #LOCATION = "R6D7" !CDS_LOCATION = "R6D7" #SEC = "1" !CDS_SEC = "1";
"A":   PN = "1"  !CDS_PN = "1";
"B":   PN = "2"  !CDS_PN = "2";
BODY = "RES","I33": #LOCATION = "R6D13" !CDS_LOCATION = "R6D13" #SEC = "1" !CDS_SEC = "1";
"A":   PN = "1"  !CDS_PN = "1";
"B":   PN = "2"  !CDS_PN = "2";
BODY = "RES","I48": #LOCATION = "R6D15" !CDS_LOCATION = "R6D15" #SEC = "1" !CDS_SEC = "1";
"A":   PN = "1"  !CDS_PN = "1";
"B":   PN = "2"  !CDS_PN = "2";
BODY = "RES","I49": #LOCATION = "R6D10" !CDS_LOCATION = "R6D10" #SEC = "1" !CDS_SEC = "1";
"A":   PN = "1"  !CDS_PN = "1";
"B":   PN = "2"  !CDS_PN = "2";
BODY = "RES","I52": #LOCATION = "R6D14" !CDS_LOCATION = "R6D14" #SEC = "1" !CDS_SEC = "1";
"A":   PN = "1"  !CDS_PN = "1";
"B":   PN = "2"  !CDS_PN = "2";
BODY = "RES","I53": #LOCATION = "R4P14" !CDS_LOCATION = "R4P14" #SEC = "1" !CDS_SEC = "1";
"A":   PN = "1"  !CDS_PN = "1";
"B":   PN = "2"  !CDS_PN = "2";
BODY = "RES","I59": #LOCATION = "R3D24" !CDS_LOCATION = "R3D24" #SEC = "1" !CDS_SEC = "1";
"A":   PN = "1"  !CDS_PN = "1";
"B":   PN = "2"  !CDS_PN = "2";
BODY = "RES","I60": #LOCATION = "R3D17" !CDS_LOCATION = "R3D17" #SEC = "1" !CDS_SEC = "1";
"A":   PN = "1"  !CDS_PN = "1";
"B":   PN = "2"  !CDS_PN = "2";
BODY = "RES","I66": #LOCATION = "R3D25" !CDS_LOCATION = "R3D25" #SEC = "1" !CDS_SEC = "1";
"A":   PN = "1"  !CDS_PN = "1";
"B":   PN = "2"  !CDS_PN = "2";
BODY = "RES","I68": #LOCATION = "R4P6" !CDS_LOCATION = "R4P6" #SEC = "1" !CDS_SEC = "1";
"A":   PN = "1"  !CDS_PN = "1";
"B":   PN = "2"  !CDS_PN = "2";
BODY = "RES","I72": #LOCATION = "R4P7" !CDS_LOCATION = "R4P7" #SEC = "1" !CDS_SEC = "1";
"A":   PN = "1"  !CDS_PN = "1";
"B":   PN = "2"  !CDS_PN = "2";
BODY = "RES","I74": #LOCATION = "R7P15" !CDS_LOCATION = "R7P15" #SEC = "1" !CDS_SEC = "1";
"A":   PN = "1"  !CDS_PN = "1";
"B":   PN = "2"  !CDS_PN = "2";
BODY = "RES","I76": #LOCATION = "R7P22" !CDS_LOCATION = "R7P22" #SEC = "1" !CDS_SEC = "1";
"A":   PN = "1"  !CDS_PN = "1";
"B":   PN = "2"  !CDS_PN = "2";
BODY = "RES","I79": #LOCATION = "R5P2" !CDS_LOCATION = "R5P2" #SEC = "1" !CDS_SEC = "1";
"A":   PN = "1"  !CDS_PN = "1";
"B":   PN = "2"  !CDS_PN = "2";
BODY = "RES","I80": #LOCATION = "R5P3" !CDS_LOCATION = "R5P3" #SEC = "1" !CDS_SEC = "1";
"A":   PN = "1"  !CDS_PN = "1";
"B":   PN = "2"  !CDS_PN = "2";
BODY = "RES","I81": #LOCATION = "R6D5" !CDS_LOCATION = "R6D5" #SEC = "1" !CDS_SEC = "1";
"A":   PN = "1"  !CDS_PN = "1";
"B":   PN = "2"  !CDS_PN = "2";
BODY = "RES","I85": #LOCATION = "R8P1" !CDS_LOCATION = "R8P1" #SEC = "1" !CDS_SEC = "1";
"A":   PN = "1"  !CDS_PN = "1";
"B":   PN = "2"  !CDS_PN = "2";
BODY = "RES","I86": #LOCATION = "R8P2" !CDS_LOCATION = "R8P2" #SEC = "1" !CDS_SEC = "1";
"A":   PN = "1"  !CDS_PN = "1";
"B":   PN = "2"  !CDS_PN = "2";
BODY = "RES","I88": #LOCATION = "R3D9" !CDS_LOCATION = "R3D9" #SEC = "1" !CDS_SEC = "1";
"A":   PN = "1"  !CDS_PN = "1";
"B":   PN = "2"  !CDS_PN = "2";
BODY = "RES","I96": #LOCATION = "R5D4" !CDS_LOCATION = "R5D4" #SEC = "1" !CDS_SEC = "1";
"A":   PN = "1"  !CDS_PN = "1";
"B":   PN = "2"  !CDS_PN = "2";
BODY = "RES","I98": #LOCATION = "R4P1" !CDS_LOCATION = "R4P1" #SEC = "1" !CDS_SEC = "1";
"A":   PN = "1"  !CDS_PN = "1";
"B":   PN = "2"  !CDS_PN = "2";
BODY = "RES","I99": #LOCATION = "R3D13" !CDS_LOCATION = "R3D13" #SEC = "1" !CDS_SEC = "1";
"A":   PN = "1"  !CDS_PN = "1";
"B":   PN = "2"  !CDS_PN = "2";
BODY = "RES","I100": #LOCATION = "R7P14" !CDS_LOCATION = "R7P14" #SEC = "1" !CDS_SEC = "1";
"A":   PN = "1"  !CDS_PN = "1";
"B":   PN = "2"  !CDS_PN = "2";
BODY = "RES","I101": #LOCATION = "R6D6" !CDS_LOCATION = "R6D6" #SEC = "1" !CDS_SEC = "1";
"A":   PN = "1"  !CDS_PN = "1";
"B":   PN = "2"  !CDS_PN = "2";
BODY = "RES","I102": #LOCATION = "R3D12" !CDS_LOCATION = "R3D12" #SEC = "1" !CDS_SEC = "1";
"A":   PN = "1"  !CDS_PN = "1";
"B":   PN = "2"  !CDS_PN = "2";
DRAWING = "@baseboard_fab2_lib.baseboard_fab2(sch_1):page91";
BODY = "SCONN24_H46321001","I1": #LOCATION = "J8B1" !CDS_LOCATION = "J8B1" &SEC = "1" #&CDS_SEC = "1";
"IO1":   PN = "1"  !CDS_PN = "1";
"IO2":   PN = "2"  !CDS_PN = "2";
"IO3":   PN = "3"  !CDS_PN = "3";
"IO4":   PN = "4"  !CDS_PN = "4";
"IO5":   PN = "5"  !CDS_PN = "5";
"IO6":   PN = "6"  !CDS_PN = "6";
"IO7":   PN = "7"  !CDS_PN = "7";
"IO8":   PN = "8"  !CDS_PN = "8";
"IO9":   PN = "9"  !CDS_PN = "9";
"IO10":   PN = "10"  !CDS_PN = "10";
"IO11":   PN = "11"  !CDS_PN = "11";
"IO12":   PN = "12"  !CDS_PN = "12";
"IO13":   PN = "13"  !CDS_PN = "13";
"IO14":   PN = "14"  !CDS_PN = "14";
"IO15":   PN = "15"  !CDS_PN = "15";
"IO16":   PN = "16"  !CDS_PN = "16";
"IO17":   PN = "17"  !CDS_PN = "17";
"IO18":   PN = "18"  !CDS_PN = "18";
"IO19":   PN = "19"  !CDS_PN = "19";
"IO20":   PN = "20"  !CDS_PN = "20";
"IO21":   PN = "21"  !CDS_PN = "21";
"IO22":   PN = "22"  !CDS_PN = "22";
"IO23":   PN = "23"  !CDS_PN = "23";
"IO24":   PN = "24"  !CDS_PN = "24";
"MP1":   PN = "MP1"  !CDS_PN = "MP1";
"MP2":   PN = "MP2"  !CDS_PN = "MP2";
BODY = "RES","I14": #LOCATION = "R8B8" !CDS_LOCATION = "R8B8" #SEC = "1" !CDS_SEC = "1";
"A":   PN = "1"  !CDS_PN = "1";
"B":   PN = "2"  !CDS_PN = "2";
BODY = "RES","I16": #LOCATION = "R8B10" !CDS_LOCATION = "R8B10" #SEC = "1" !CDS_SEC = "1";
"A":   PN = "1"  !CDS_PN = "1";
"B":   PN = "2"  !CDS_PN = "2";
BODY = "RES","I17": #LOCATION = "R8B16" !CDS_LOCATION = "R8B16" #SEC = "1" !CDS_SEC = "1";
"A":   PN = "1"  !CDS_PN = "1";
"B":   PN = "2"  !CDS_PN = "2";
BODY = "RES","I18": #LOCATION = "R8B17" !CDS_LOCATION = "R8B17" #SEC = "1" !CDS_SEC = "1";
"A":   PN = "1"  !CDS_PN = "1";
"B":   PN = "2"  !CDS_PN = "2";
BODY = "RES","I20": #LOCATION = "R8B18" !CDS_LOCATION = "R8B18" #SEC = "1" !CDS_SEC = "1";
"A":   PN = "1"  !CDS_PN = "1";
"B":   PN = "2"  !CDS_PN = "2";
BODY = "RES","I21": #LOCATION = "R8B19" !CDS_LOCATION = "R8B19" #SEC = "1" !CDS_SEC = "1";
"A":   PN = "1"  !CDS_PN = "1";
"B":   PN = "2"  !CDS_PN = "2";
BODY = "RES","I22": #LOCATION = "R8B5" !CDS_LOCATION = "R8B5" #SEC = "1" !CDS_SEC = "1";
"A":   PN = "1"  !CDS_PN = "1";
"B":   PN = "2"  !CDS_PN = "2";
BODY = "RES","I24": #LOCATION = "R8B3" !CDS_LOCATION = "R8B3" #SEC = "1" !CDS_SEC = "1";
"A":   PN = "1"  !CDS_PN = "1";
"B":   PN = "2"  !CDS_PN = "2";
BODY = "RES","I34": #LOCATION = "R8B13" !CDS_LOCATION = "R8B13" #SEC = "1" !CDS_SEC = "1";
"A":   PN = "1"  !CDS_PN = "1";
"B":   PN = "2"  !CDS_PN = "2";
BODY = "RES","I35": #LOCATION = "R8B11" !CDS_LOCATION = "R8B11" #SEC = "1" !CDS_SEC = "1";
"A":   PN = "1"  !CDS_PN = "1";
"B":   PN = "2"  !CDS_PN = "2";
BODY = "RES","I36": #LOCATION = "R8B7" !CDS_LOCATION = "R8B7" #SEC = "1" !CDS_SEC = "1";
"A":   PN = "1"  !CDS_PN = "1";
"B":   PN = "2"  !CDS_PN = "2";
BODY = "RES","I37": #LOCATION = "R8B6" !CDS_LOCATION = "R8B6" #SEC = "1" !CDS_SEC = "1";
"A":   PN = "1"  !CDS_PN = "1";
"B":   PN = "2"  !CDS_PN = "2";
DRAWING = "@baseboard_fab2_lib.baseboard_fab2(sch_1):page92";
BODY = "GTL2014","I1": #LOCATION = "U3P2" !CDS_LOCATION = "U3P2" #SEC = "1" !CDS_SEC = "1";
"A0":   PN = "13"  !CDS_PN = "13";
"A1":   PN = "12"  !CDS_PN = "12";
"A2":   PN = "10"  !CDS_PN = "10";
"A3":   PN = "9"  !CDS_PN = "9";
"B0":   PN = "2"  !CDS_PN = "2";
"B1":   PN = "3"  !CDS_PN = "3";
"B2":   PN = "5"  !CDS_PN = "5";
"B3":   PN = "6"  !CDS_PN = "6";
"DIR":   PN = "1"  !CDS_PN = "1";
"GND<0>":   PN = "7"  !CDS_PN = "7";
"GND<1>":   PN = "8"  !CDS_PN = "8";
"GND<2>":   PN = "11"  !CDS_PN = "11";
"VCC":   PN = "14"  !CDS_PN = "14";
"VREF":   PN = "4"  !CDS_PN = "4";
BODY = "RES","I9": #LOCATION = "R3P41" !CDS_LOCATION = "R3P41" #SEC = "1" !CDS_SEC = "1";
"A":   PN = "1"  !CDS_PN = "1";
"B":   PN = "2"  !CDS_PN = "2";
BODY = "RES","I12": #LOCATION = "R3P46" !CDS_LOCATION = "R3P46" #SEC = "1" !CDS_SEC = "1";
"A":   PN = "1"  !CDS_PN = "1";
"B":   PN = "2"  !CDS_PN = "2";
BODY = "RES","I13": #LOCATION = "R3P43" !CDS_LOCATION = "R3P43" #SEC = "1" !CDS_SEC = "1";
"A":   PN = "1"  !CDS_PN = "1";
"B":   PN = "2"  !CDS_PN = "2";
BODY = "RES","I14": #LOCATION = "R3P42" !CDS_LOCATION = "R3P42" #SEC = "1" !CDS_SEC = "1";
"A":   PN = "1"  !CDS_PN = "1";
"B":   PN = "2"  !CDS_PN = "2";
BODY = "RES","I19": #LOCATION = "R7E2" !CDS_LOCATION = "R7E2" #SEC = "1" !CDS_SEC = "1";
"A":   PN = "1"  !CDS_PN = "1";
"B":   PN = "2"  !CDS_PN = "2";
BODY = "RES","I24": #LOCATION = "R7D34" !CDS_LOCATION = "R7D34" #SEC = "1" !CDS_SEC = "1";
"A":   PN = "1"  !CDS_PN = "1";
"B":   PN = "2"  !CDS_PN = "2";
BODY = "RES","I29": #LOCATION = "R7D31" !CDS_LOCATION = "R7D31" #SEC = "1" !CDS_SEC = "1";
"A":   PN = "1"  !CDS_PN = "1";
"B":   PN = "2"  !CDS_PN = "2";
BODY = "RES","I30": #LOCATION = "R7D29" !CDS_LOCATION = "R7D29" #SEC = "1" !CDS_SEC = "1";
"A":   PN = "1"  !CDS_PN = "1";
"B":   PN = "2"  !CDS_PN = "2";
BODY = "GTL2014","I32": #LOCATION = "U7D2" !CDS_LOCATION = "U7D2" #SEC = "1" !CDS_SEC = "1";
"A0":   PN = "13"  !CDS_PN = "13";
"A1":   PN = "12"  !CDS_PN = "12";
"A2":   PN = "10"  !CDS_PN = "10";
"A3":   PN = "9"  !CDS_PN = "9";
"B0":   PN = "2"  !CDS_PN = "2";
"B1":   PN = "3"  !CDS_PN = "3";
"B2":   PN = "5"  !CDS_PN = "5";
"B3":   PN = "6"  !CDS_PN = "6";
"DIR":   PN = "1"  !CDS_PN = "1";
"GND<0>":   PN = "7"  !CDS_PN = "7";
"GND<1>":   PN = "8"  !CDS_PN = "8";
"GND<2>":   PN = "11"  !CDS_PN = "11";
"VCC":   PN = "14"  !CDS_PN = "14";
"VREF":   PN = "4"  !CDS_PN = "4";
BODY = "CAP_A","I37": #LOCATION = "C3P49" !CDS_LOCATION = "C3P49" #SEC = "1" !CDS_SEC = "1";
"A":   PN = "1"  !CDS_PN = "1";
"B":   PN = "2"  !CDS_PN = "2";
BODY = "RES","I38": #LOCATION = "R3P49" !CDS_LOCATION = "R3P49" #SEC = "1" !CDS_SEC = "1";
"A":   PN = "1"  !CDS_PN = "1";
"B":   PN = "2"  !CDS_PN = "2";
BODY = "RES","I46": #LOCATION = "R3R1" !CDS_LOCATION = "R3R1" #SEC = "1" !CDS_SEC = "1";
"A":   PN = "1"  !CDS_PN = "1";
"B":   PN = "2"  !CDS_PN = "2";
BODY = "RES","I48": #LOCATION = "R7D32" !CDS_LOCATION = "R7D32" #SEC = "1" !CDS_SEC = "1";
"A":   PN = "1"  !CDS_PN = "1";
"B":   PN = "2"  !CDS_PN = "2";
BODY = "CAP_A","I52": #LOCATION = "C7D5" !CDS_LOCATION = "C7D5" #SEC = "1" !CDS_SEC = "1";
"A":   PN = "1"  !CDS_PN = "1";
"B":   PN = "2"  !CDS_PN = "2";
BODY = "RES","I54": #LOCATION = "R7D26" !CDS_LOCATION = "R7D26" #SEC = "1" !CDS_SEC = "1";
"A":   PN = "1"  !CDS_PN = "1";
"B":   PN = "2"  !CDS_PN = "2";
BODY = "RES","I61": #LOCATION = "R3R3" !CDS_LOCATION = "R3R3" #SEC = "1" !CDS_SEC = "1";
"A":   PN = "1"  !CDS_PN = "1";
"B":   PN = "2"  !CDS_PN = "2";
BODY = "RES","I64": #LOCATION = "R6D9" !CDS_LOCATION = "R6D9" #SEC = "1" !CDS_SEC = "1";
"A":   PN = "1"  !CDS_PN = "1";
"B":   PN = "2"  !CDS_PN = "2";
BODY = "RES","I65": #LOCATION = "R7P27" !CDS_LOCATION = "R7P27" #SEC = "1" !CDS_SEC = "1";
"A":   PN = "1"  !CDS_PN = "1";
"B":   PN = "2"  !CDS_PN = "2";
BODY = "RES","I67": #LOCATION = "R7D28" !CDS_LOCATION = "R7D28" #SEC = "1" !CDS_SEC = "1";
"A":   PN = "1"  !CDS_PN = "1";
"B":   PN = "2"  !CDS_PN = "2";
BODY = "RES","I68": #LOCATION = "R7D27" !CDS_LOCATION = "R7D27" #SEC = "1" !CDS_SEC = "1";
"A":   PN = "1"  !CDS_PN = "1";
"B":   PN = "2"  !CDS_PN = "2";
BODY = "RES","I70": #LOCATION = "R7D25" !CDS_LOCATION = "R7D25" #SEC = "1" !CDS_SEC = "1";
"A":   PN = "1"  !CDS_PN = "1";
"B":   PN = "2"  !CDS_PN = "2";
BODY = "RES","I75": #LOCATION = "R3R2" !CDS_LOCATION = "R3R2" #SEC = "1" !CDS_SEC = "1";
"A":   PN = "1"  !CDS_PN = "1";
"B":   PN = "2"  !CDS_PN = "2";
BODY = "CAP","I79": #LOCATION = "C7D4" !CDS_LOCATION = "C7D4" #SEC = "1" !CDS_SEC = "1";
"A":   PN = "1"  !CDS_PN = "1";
"B":   PN = "2"  !CDS_PN = "2";
BODY = "CAP","I84": #LOCATION = "C3P50" !CDS_LOCATION = "C3P50" #SEC = "1" !CDS_SEC = "1";
"A":   PN = "1"  !CDS_PN = "1";
"B":   PN = "2"  !CDS_PN = "2";
BODY = "RES","I92": #LOCATION = "R2T44" !CDS_LOCATION = "R2T44" &SEC = "1" #&CDS_SEC = "1";
"A":   PN = "1"  !CDS_PN = "1";
"B":   PN = "2"  !CDS_PN = "2";
BODY = "RES","I93": #LOCATION = "R2T40" !CDS_LOCATION = "R2T40" &SEC = "1" #&CDS_SEC = "1";
"A":   PN = "1"  !CDS_PN = "1";
"B":   PN = "2"  !CDS_PN = "2";
BODY = "RES","I94": #LOCATION = "R2T37" !CDS_LOCATION = "R2T37" &SEC = "1" #&CDS_SEC = "1";
"A":   PN = "1"  !CDS_PN = "1";
"B":   PN = "2"  !CDS_PN = "2";
BODY = "RES","I96": #LOCATION = "R2T43" !CDS_LOCATION = "R2T43" &SEC = "1" #&CDS_SEC = "1";
"A":   PN = "1"  !CDS_PN = "1";
"B":   PN = "2"  !CDS_PN = "2";
BODY = "RES","I97": #LOCATION = "R3P59" !CDS_LOCATION = "R3P59" #SEC = "1" !CDS_SEC = "1";
"A":   PN = "1"  !CDS_PN = "1";
"B":   PN = "2"  !CDS_PN = "2";
BODY = "RES","I98": #LOCATION = "R3P58" !CDS_LOCATION = "R3P58" #SEC = "1" !CDS_SEC = "1";
"A":   PN = "1"  !CDS_PN = "1";
"B":   PN = "2"  !CDS_PN = "2";
BODY = "RES","I100": #LOCATION = "R7P18" !CDS_LOCATION = "R7P18" #SEC = "1" !CDS_SEC = "1";
"A":   PN = "1"  !CDS_PN = "1";
"B":   PN = "2"  !CDS_PN = "2";
BODY = "RES","I101": #LOCATION = "R4R2" !CDS_LOCATION = "R4R2" #SEC = "1" !CDS_SEC = "1";
"A":   PN = "1"  !CDS_PN = "1";
"B":   PN = "2"  !CDS_PN = "2";
BODY = "RES","I106": #LOCATION = "R7W4" !CDS_LOCATION = "R7W4" #SEC = "1" !CDS_SEC = "1";
"A":   PN = "1"  !CDS_PN = "1";
"B":   PN = "2"  !CDS_PN = "2";
BODY = "RES","I108": #LOCATION = "R3W10" !CDS_LOCATION = "R3W10" #SEC = "1" !CDS_SEC = "1";
"A":   PN = "1"  !CDS_PN = "1";
"B":   PN = "2"  !CDS_PN = "2";
BODY = "374R2F-1-GP","I110": #LOCATION = "R3P45" !CDS_LOCATION = "R3P45" &SEC = "1" #&CDS_SEC = "1";
"1":   PN = "1"  !CDS_PN = "1";
"2":   PN = "2"  !CDS_PN = "2";
BODY = "374R2F-1-GP","I111": #LOCATION = "R7D33" !CDS_LOCATION = "R7D33" &SEC = "1" #&CDS_SEC = "1";
"1":   PN = "1"  !CDS_PN = "1";
"2":   PN = "2"  !CDS_PN = "2";
DRAWING = "@baseboard_fab2_lib.baseboard_fab2(sch_1):page93";
BODY = "RES","I13": #LOCATION = "R2T27" !CDS_LOCATION = "R2T27" #SEC = "1" !CDS_SEC = "1";
"A":   PN = "1"  !CDS_PN = "1";
"B":   PN = "2"  !CDS_PN = "2";
BODY = "RES","I15": #LOCATION = "R2T32" !CDS_LOCATION = "R2T32" #SEC = "1" !CDS_SEC = "1";
"A":   PN = "1"  !CDS_PN = "1";
"B":   PN = "2"  !CDS_PN = "2";
BODY = "RES","I16": #LOCATION = "R2T20" !CDS_LOCATION = "R2T20" #SEC = "1" !CDS_SEC = "1";
"A":   PN = "1"  !CDS_PN = "1";
"B":   PN = "2"  !CDS_PN = "2";
BODY = "RES","I23": #LOCATION = "R2T17" !CDS_LOCATION = "R2T17" #SEC = "1" !CDS_SEC = "1";
"A":   PN = "1"  !CDS_PN = "1";
"B":   PN = "2"  !CDS_PN = "2";
BODY = "GTL2014","I30": #LOCATION = "U2T4" !CDS_LOCATION = "U2T4" #SEC = "1" !CDS_SEC = "1";
"A0":   PN = "13"  !CDS_PN = "13";
"A1":   PN = "12"  !CDS_PN = "12";
"A2":   PN = "10"  !CDS_PN = "10";
"A3":   PN = "9"  !CDS_PN = "9";
"B0":   PN = "2"  !CDS_PN = "2";
"B1":   PN = "3"  !CDS_PN = "3";
"B2":   PN = "5"  !CDS_PN = "5";
"B3":   PN = "6"  !CDS_PN = "6";
"DIR":   PN = "1"  !CDS_PN = "1";
"GND<0>":   PN = "7"  !CDS_PN = "7";
"GND<1>":   PN = "8"  !CDS_PN = "8";
"GND<2>":   PN = "11"  !CDS_PN = "11";
"VCC":   PN = "14"  !CDS_PN = "14";
"VREF":   PN = "4"  !CDS_PN = "4";
BODY = "RES","I39": #LOCATION = "R2T38" !CDS_LOCATION = "R2T38" #SEC = "1" !CDS_SEC = "1";
"A":   PN = "1"  !CDS_PN = "1";
"B":   PN = "2"  !CDS_PN = "2";
BODY = "RES","I40": #LOCATION = "R2T33" !CDS_LOCATION = "R2T33" #SEC = "1" !CDS_SEC = "1";
"A":   PN = "1"  !CDS_PN = "1";
"B":   PN = "2"  !CDS_PN = "2";
BODY = "RES","I42": #LOCATION = "R2T30" !CDS_LOCATION = "R2T30" #SEC = "1" !CDS_SEC = "1";
"A":   PN = "1"  !CDS_PN = "1";
"B":   PN = "2"  !CDS_PN = "2";
BODY = "RES","I62": #LOCATION = "R7D24" !CDS_LOCATION = "R7D24" #SEC = "1" !CDS_SEC = "1";
"A":   PN = "1"  !CDS_PN = "1";
"B":   PN = "2"  !CDS_PN = "2";
BODY = "RES","I63": #LOCATION = "R2T19" !CDS_LOCATION = "R2T19" #SEC = "1" !CDS_SEC = "1";
"A":   PN = "1"  !CDS_PN = "1";
"B":   PN = "2"  !CDS_PN = "2";
BODY = "RES","I67": #LOCATION = "R2T16" !CDS_LOCATION = "R2T16" #SEC = "1" !CDS_SEC = "1";
"A":   PN = "1"  !CDS_PN = "1";
"B":   PN = "2"  !CDS_PN = "2";
BODY = "RES","I68": #LOCATION = "R2T31" !CDS_LOCATION = "R2T31" #SEC = "1" !CDS_SEC = "1";
"A":   PN = "1"  !CDS_PN = "1";
"B":   PN = "2"  !CDS_PN = "2";
BODY = "CAP_A","I72": #LOCATION = "C2T33" !CDS_LOCATION = "C2T33" #SEC = "1" !CDS_SEC = "1";
"A":   PN = "1"  !CDS_PN = "1";
"B":   PN = "2"  !CDS_PN = "2";
BODY = "RES","I79": #LOCATION = "R4R3" !CDS_LOCATION = "R4R3" #SEC = "1" !CDS_SEC = "1";
"A":   PN = "1"  !CDS_PN = "1";
"B":   PN = "2"  !CDS_PN = "2";
BODY = "RES","I87": #LOCATION = "R2T26" !CDS_LOCATION = "R2T26" #SEC = "1" !CDS_SEC = "1";
"A":   PN = "1"  !CDS_PN = "1";
"B":   PN = "2"  !CDS_PN = "2";
BODY = "RES","I88": #LOCATION = "R2T57" !CDS_LOCATION = "R2T57" #SEC = "1" !CDS_SEC = "1";
"A":   PN = "1"  !CDS_PN = "1";
"B":   PN = "2"  !CDS_PN = "2";
BODY = "RES","I89": #LOCATION = "R2T61" !CDS_LOCATION = "R2T61" #SEC = "1" !CDS_SEC = "1";
"A":   PN = "1"  !CDS_PN = "1";
"B":   PN = "2"  !CDS_PN = "2";
BODY = "RES","I93": #LOCATION = "R2T62" !CDS_LOCATION = "R2T62" #SEC = "1" !CDS_SEC = "1";
"A":   PN = "1"  !CDS_PN = "1";
"B":   PN = "2"  !CDS_PN = "2";
BODY = "RES","I94": #LOCATION = "R2T58" !CDS_LOCATION = "R2T58" #SEC = "1" !CDS_SEC = "1";
"A":   PN = "1"  !CDS_PN = "1";
"B":   PN = "2"  !CDS_PN = "2";
BODY = "CAP_A","I95": #LOCATION = "C2T32" !CDS_LOCATION = "C2T32" #SEC = "1" !CDS_SEC = "1";
"A":   PN = "1"  !CDS_PN = "1";
"B":   PN = "2"  !CDS_PN = "2";
BODY = "RES","I98": #LOCATION = "R2T39" !CDS_LOCATION = "R2T39" #SEC = "1" !CDS_SEC = "1";
"A":   PN = "1"  !CDS_PN = "1";
"B":   PN = "2"  !CDS_PN = "2";
BODY = "RES","I102": #LOCATION = "R2T68" !CDS_LOCATION = "R2T68" #SEC = "1" !CDS_SEC = "1";
"A":   PN = "1"  !CDS_PN = "1";
"B":   PN = "2"  !CDS_PN = "2";
BODY = "RES","I103": #LOCATION = "R2T60" !CDS_LOCATION = "R2T60" #SEC = "1" !CDS_SEC = "1";
"A":   PN = "1"  !CDS_PN = "1";
"B":   PN = "2"  !CDS_PN = "2";
BODY = "RES","I106": #LOCATION = "R7P28" !CDS_LOCATION = "R7P28" #SEC = "1" !CDS_SEC = "1";
"A":   PN = "1"  !CDS_PN = "1";
"B":   PN = "2"  !CDS_PN = "2";
BODY = "RES","I107": #LOCATION = "R2T59" !CDS_LOCATION = "R2T59" #SEC = "1" !CDS_SEC = "1";
"A":   PN = "1"  !CDS_PN = "1";
"B":   PN = "2"  !CDS_PN = "2";
BODY = "RES","I108": #LOCATION = "R2T69" !CDS_LOCATION = "R2T69" #SEC = "1" !CDS_SEC = "1";
"A":   PN = "1"  !CDS_PN = "1";
"B":   PN = "2"  !CDS_PN = "2";
BODY = "RES","I109": #LOCATION = "R2T71" !CDS_LOCATION = "R2T71" #SEC = "1" !CDS_SEC = "1";
"A":   PN = "1"  !CDS_PN = "1";
"B":   PN = "2"  !CDS_PN = "2";
BODY = "RES","I110": #LOCATION = "R7D43" !CDS_LOCATION = "R7D43" #SEC = "1" !CDS_SEC = "1";
"A":   PN = "1"  !CDS_PN = "1";
"B":   PN = "2"  !CDS_PN = "2";
BODY = "RES","I111": #LOCATION = "R2T65" !CDS_LOCATION = "R2T65" #SEC = "1" !CDS_SEC = "1";
"A":   PN = "1"  !CDS_PN = "1";
"B":   PN = "2"  !CDS_PN = "2";
BODY = "RES","I112": #LOCATION = "R2T66" !CDS_LOCATION = "R2T66" #SEC = "1" !CDS_SEC = "1";
"A":   PN = "1"  !CDS_PN = "1";
"B":   PN = "2"  !CDS_PN = "2";
BODY = "RES","I113": #LOCATION = "R2T67" !CDS_LOCATION = "R2T67" #SEC = "1" !CDS_SEC = "1";
"A":   PN = "1"  !CDS_PN = "1";
"B":   PN = "2"  !CDS_PN = "2";
BODY = "RES","I114": #LOCATION = "R7D41" !CDS_LOCATION = "R7D41" #SEC = "1" !CDS_SEC = "1";
"A":   PN = "1"  !CDS_PN = "1";
"B":   PN = "2"  !CDS_PN = "2";
BODY = "RES","I119": #LOCATION = "R8F38" !CDS_LOCATION = "R8F38" #SEC = "1" !CDS_SEC = "1";
"A":   PN = "1"  !CDS_PN = "1";
"B":   PN = "2"  !CDS_PN = "2";
BODY = "RES","I121": #LOCATION = "R2T64" !CDS_LOCATION = "R2T64" #SEC = "1" !CDS_SEC = "1";
"A":   PN = "1"  !CDS_PN = "1";
"B":   PN = "2"  !CDS_PN = "2";
BODY = "RES","I122": #LOCATION = "R1T36" !CDS_LOCATION = "R1T36" #SEC = "1" !CDS_SEC = "1";
"A":   PN = "1"  !CDS_PN = "1";
"B":   PN = "2"  !CDS_PN = "2";
BODY = "RES","I123": #LOCATION = "R1T37" !CDS_LOCATION = "R1T37" #SEC = "1" !CDS_SEC = "1";
"A":   PN = "1"  !CDS_PN = "1";
"B":   PN = "2"  !CDS_PN = "2";
BODY = "RES","I127": #LOCATION = "R2T50" !CDS_LOCATION = "R2T50" #SEC = "1" !CDS_SEC = "1";
"A":   PN = "1"  !CDS_PN = "1";
"B":   PN = "2"  !CDS_PN = "2";
BODY = "RES","I131": #LOCATION = "R8F37" !CDS_LOCATION = "R8F37" #SEC = "1" !CDS_SEC = "1";
"A":   PN = "1"  !CDS_PN = "1";
"B":   PN = "2"  !CDS_PN = "2";
BODY = "RES","I133": #LOCATION = "R2T63" !CDS_LOCATION = "R2T63" #SEC = "1" !CDS_SEC = "1";
"A":   PN = "1"  !CDS_PN = "1";
"B":   PN = "2"  !CDS_PN = "2";
BODY = "RES","I135": #LOCATION = "R1T35" !CDS_LOCATION = "R1T35" #SEC = "1" !CDS_SEC = "1";
"A":   PN = "1"  !CDS_PN = "1";
"B":   PN = "2"  !CDS_PN = "2";
BODY = "RES","I137": #LOCATION = "R1T38" !CDS_LOCATION = "R1T38" #SEC = "1" !CDS_SEC = "1";
"A":   PN = "1"  !CDS_PN = "1";
"B":   PN = "2"  !CDS_PN = "2";
BODY = "RES","I143": #LOCATION = "R2T72" !CDS_LOCATION = "R2T72" #SEC = "1" !CDS_SEC = "1";
"A":   PN = "1"  !CDS_PN = "1";
"B":   PN = "2"  !CDS_PN = "2";
BODY = "RES","I144": #LOCATION = "R2T73" !CDS_LOCATION = "R2T73" #SEC = "1" !CDS_SEC = "1";
"A":   PN = "1"  !CDS_PN = "1";
"B":   PN = "2"  !CDS_PN = "2";
BODY = "RES","I147": #LOCATION = "R2W2" !CDS_LOCATION = "R2W2" #SEC = "1" !CDS_SEC = "1";
"A":   PN = "1"  !CDS_PN = "1";
"B":   PN = "2"  !CDS_PN = "2";
BODY = "374R2F-1-GP","I148": #LOCATION = "R2T36" !CDS_LOCATION = "R2T36" &SEC = "1" #&CDS_SEC = "1";
"1":   PN = "1"  !CDS_PN = "1";
"2":   PN = "2"  !CDS_PN = "2";
DRAWING = "@baseboard_fab2_lib.baseboard_fab2(sch_1):page94";
BODY = "FET_N_DUAL","I49": #LOCATION = "Q3U1" !CDS_LOCATION = "Q3U1" #SEC = "1" !CDS_SEC = "1";
"DRAIN<0>":   PN = "6"  !CDS_PN = "6";
"GATE<0>":   PN = "2"  !CDS_PN = "2";
"SOURCE<0>":   PN = "1"  !CDS_PN = "1";
BODY = "RES","I51": #LOCATION = "R7G7" !CDS_LOCATION = "R7G7" &SEC = "1" #&CDS_SEC = "1";
"A":   PN = "1"  !CDS_PN = "1";
"B":   PN = "2"  !CDS_PN = "2";
BODY = "FET_N_DUAL","I60": #LOCATION = "Q7E1" !CDS_LOCATION = "Q7E1" #SEC = "1" !CDS_SEC = "1";
"DRAIN<0>":   PN = "6"  !CDS_PN = "6";
"GATE<0>":   PN = "2"  !CDS_PN = "2";
"SOURCE<0>":   PN = "1"  !CDS_PN = "1";
BODY = "FET_N_DUAL","I64": #LOCATION = "Q7E1" !CDS_LOCATION = "Q7E1" #SEC = "2" !CDS_SEC = "2";
"DRAIN<0>":   PN = "3"  !CDS_PN = "3";
"GATE<0>":   PN = "5"  !CDS_PN = "5";
"SOURCE<0>":   PN = "4"  !CDS_PN = "4";
BODY = "RES","I66": #LOCATION = "R3R4" !CDS_LOCATION = "R3R4" &SEC = "1" #&CDS_SEC = "1";
"A":   PN = "1"  !CDS_PN = "1";
"B":   PN = "2"  !CDS_PN = "2";
BODY = "FET_N_DUAL","I69": #LOCATION = "Q7E2" !CDS_LOCATION = "Q7E2" #SEC = "1" !CDS_SEC = "1";
"DRAIN<0>":   PN = "6"  !CDS_PN = "6";
"GATE<0>":   PN = "2"  !CDS_PN = "2";
"SOURCE<0>":   PN = "1"  !CDS_PN = "1";
BODY = "FET_N_DUAL","I75": #LOCATION = "Q7E2" !CDS_LOCATION = "Q7E2" #SEC = "2" !CDS_SEC = "2";
"DRAIN<0>":   PN = "3"  !CDS_PN = "3";
"GATE<0>":   PN = "5"  !CDS_PN = "5";
"SOURCE<0>":   PN = "4"  !CDS_PN = "4";
BODY = "FET_N_DUAL","I77": #LOCATION = "Q4B1" !CDS_LOCATION = "Q4B1" #SEC = "2" !CDS_SEC = "2";
"DRAIN<0>":   PN = "3"  !CDS_PN = "3";
"GATE<0>":   PN = "5"  !CDS_PN = "5";
"SOURCE<0>":   PN = "4"  !CDS_PN = "4";
BODY = "RES","I79": #LOCATION = "R3R10" !CDS_LOCATION = "R3R10" &SEC = "1" #&CDS_SEC = "1";
"A":   PN = "1"  !CDS_PN = "1";
"B":   PN = "2"  !CDS_PN = "2";
BODY = "RES","I82": #LOCATION = "R6M4" !CDS_LOCATION = "R6M4" &SEC = "1" #&CDS_SEC = "1";
"A":   PN = "1"  !CDS_PN = "1";
"B":   PN = "2"  !CDS_PN = "2";
BODY = "FET_N_DUAL","I84": #LOCATION = "Q4B1" !CDS_LOCATION = "Q4B1" #SEC = "1" !CDS_SEC = "1";
"DRAIN<0>":   PN = "6"  !CDS_PN = "6";
"GATE<0>":   PN = "2"  !CDS_PN = "2";
"SOURCE<0>":   PN = "1"  !CDS_PN = "1";
BODY = "FET_N_DUAL","I89": #LOCATION = "Q3U1" !CDS_LOCATION = "Q3U1" #SEC = "2" !CDS_SEC = "2";
"DRAIN<0>":   PN = "3"  !CDS_PN = "3";
"GATE<0>":   PN = "5"  !CDS_PN = "5";
"SOURCE<0>":   PN = "4"  !CDS_PN = "4";
BODY = "RES","I91": #LOCATION = "R4U1" !CDS_LOCATION = "R4U1" #SEC = "1" !CDS_SEC = "1";
"A":   PN = "1"  !CDS_PN = "1";
"B":   PN = "2"  !CDS_PN = "2";
BODY = "RES","I94": #LOCATION = "R4U3" !CDS_LOCATION = "R4U3" #SEC = "1" !CDS_SEC = "1";
"A":   PN = "1"  !CDS_PN = "1";
"B":   PN = "2"  !CDS_PN = "2";
BODY = "FET_N_DUAL","I98": #LOCATION = "Q4U1" !CDS_LOCATION = "Q4U1" #SEC = "1" !CDS_SEC = "1";
"DRAIN<0>":   PN = "6"  !CDS_PN = "6";
"GATE<0>":   PN = "2"  !CDS_PN = "2";
"SOURCE<0>":   PN = "1"  !CDS_PN = "1";
BODY = "RES","I100": #LOCATION = "R4U2" !CDS_LOCATION = "R4U2" #SEC = "1" !CDS_SEC = "1";
"A":   PN = "1"  !CDS_PN = "1";
"B":   PN = "2"  !CDS_PN = "2";
BODY = "FET_N_DUAL","I102": #LOCATION = "Q4U1" !CDS_LOCATION = "Q4U1" #SEC = "2" !CDS_SEC = "2";
"DRAIN<0>":   PN = "3"  !CDS_PN = "3";
"GATE<0>":   PN = "5"  !CDS_PN = "5";
"SOURCE<0>":   PN = "4"  !CDS_PN = "4";
BODY = "RES","I104": #LOCATION = "R4U4" !CDS_LOCATION = "R4U4" #SEC = "1" !CDS_SEC = "1";
"A":   PN = "1"  !CDS_PN = "1";
"B":   PN = "2"  !CDS_PN = "2";
DRAWING = "@baseboard_fab2_lib.baseboard_fab2(sch_1):page95";
BODY = "FET_N_DUAL","I28": #LOCATION = "Q2U1" !CDS_LOCATION = "Q2U1" #SEC = "1" !CDS_SEC = "1";
"DRAIN<0>":   PN = "6"  !CDS_PN = "6";
"GATE<0>":   PN = "2"  !CDS_PN = "2";
"SOURCE<0>":   PN = "1"  !CDS_PN = "1";
BODY = "FET_N_DUAL","I32": #LOCATION = "Q4B2" !CDS_LOCATION = "Q4B2" #SEC = "1" !CDS_SEC = "1";
"DRAIN<0>":   PN = "6"  !CDS_PN = "6";
"GATE<0>":   PN = "2"  !CDS_PN = "2";
"SOURCE<0>":   PN = "1"  !CDS_PN = "1";
BODY = "FET_N_DUAL","I33": #LOCATION = "Q4B2" !CDS_LOCATION = "Q4B2" #SEC = "2" !CDS_SEC = "2";
"DRAIN<0>":   PN = "3"  !CDS_PN = "3";
"GATE<0>":   PN = "5"  !CDS_PN = "5";
"SOURCE<0>":   PN = "4"  !CDS_PN = "4";
BODY = "FET_N_DUAL","I51": #LOCATION = "Q7E3" !CDS_LOCATION = "Q7E3" #SEC = "2" !CDS_SEC = "2";
"DRAIN<0>":   PN = "3"  !CDS_PN = "3";
"GATE<0>":   PN = "5"  !CDS_PN = "5";
"SOURCE<0>":   PN = "4"  !CDS_PN = "4";
BODY = "FET_N_DUAL","I52": #LOCATION = "Q7E3" !CDS_LOCATION = "Q7E3" #SEC = "1" !CDS_SEC = "1";
"DRAIN<0>":   PN = "6"  !CDS_PN = "6";
"GATE<0>":   PN = "2"  !CDS_PN = "2";
"SOURCE<0>":   PN = "1"  !CDS_PN = "1";
BODY = "FET_N_DUAL","I59": #LOCATION = "Q7E5" !CDS_LOCATION = "Q7E5" #SEC = "2" !CDS_SEC = "2";
"DRAIN<0>":   PN = "3"  !CDS_PN = "3";
"GATE<0>":   PN = "5"  !CDS_PN = "5";
"SOURCE<0>":   PN = "4"  !CDS_PN = "4";
BODY = "RES","I62": #LOCATION = "R7E10" !CDS_LOCATION = "R7E10" &SEC = "1" #&CDS_SEC = "1";
"A":   PN = "1"  !CDS_PN = "1";
"B":   PN = "2"  !CDS_PN = "2";
BODY = "FET_N_DUAL","I69": #LOCATION = "Q7E6" !CDS_LOCATION = "Q7E6" #SEC = "2" !CDS_SEC = "2";
"DRAIN<0>":   PN = "3"  !CDS_PN = "3";
"GATE<0>":   PN = "5"  !CDS_PN = "5";
"SOURCE<0>":   PN = "4"  !CDS_PN = "4";
BODY = "RES","I72": #LOCATION = "R7E11" !CDS_LOCATION = "R7E11" &SEC = "1" #&CDS_SEC = "1";
"A":   PN = "1"  !CDS_PN = "1";
"B":   PN = "2"  !CDS_PN = "2";
BODY = "CAP_A","I92": #LOCATION = "C7E3" !CDS_LOCATION = "C7E3" #SEC = "1" !CDS_SEC = "1";
"A":   PN = "1"  !CDS_PN = "1";
"B":   PN = "2"  !CDS_PN = "2";
BODY = "RES","I106": #LOCATION = "R7E7" !CDS_LOCATION = "R7E7" #SEC = "1" !CDS_SEC = "1";
"A":   PN = "1"  !CDS_PN = "1";
"B":   PN = "2"  !CDS_PN = "2";
BODY = "RES","I108": #LOCATION = "R7E9" !CDS_LOCATION = "R7E9" #SEC = "1" !CDS_SEC = "1";
"A":   PN = "1"  !CDS_PN = "1";
"B":   PN = "2"  !CDS_PN = "2";
BODY = "FET_N_DUAL","I111": #LOCATION = "Q7E5" !CDS_LOCATION = "Q7E5" #SEC = "1" !CDS_SEC = "1";
"DRAIN<0>":   PN = "6"  !CDS_PN = "6";
"GATE<0>":   PN = "2"  !CDS_PN = "2";
"SOURCE<0>":   PN = "1"  !CDS_PN = "1";
BODY = "FET_N_DUAL","I112": #LOCATION = "Q7E6" !CDS_LOCATION = "Q7E6" #SEC = "1" !CDS_SEC = "1";
"DRAIN<0>":   PN = "6"  !CDS_PN = "6";
"GATE<0>":   PN = "2"  !CDS_PN = "2";
"SOURCE<0>":   PN = "1"  !CDS_PN = "1";
BODY = "FET_N_DUAL","I113": #LOCATION = "Q2U1" !CDS_LOCATION = "Q2U1" #SEC = "2" !CDS_SEC = "2";
"DRAIN<0>":   PN = "3"  !CDS_PN = "3";
"GATE<0>":   PN = "5"  !CDS_PN = "5";
"SOURCE<0>":   PN = "4"  !CDS_PN = "4";
BODY = "CAP_A","I115": #LOCATION = "C7E4" !CDS_LOCATION = "C7E4" #SEC = "1" !CDS_SEC = "1";
"A":   PN = "1"  !CDS_PN = "1";
"B":   PN = "2"  !CDS_PN = "2";
BODY = "TTL1G08","I117": #LOCATION = "U7E2" !CDS_LOCATION = "U7E2" #SEC = "1" !CDS_SEC = "1";
"A<0>":   PN = "1"  !CDS_PN = "1";
"B<0>":   PN = "2"  !CDS_PN = "2";
"Y<0>":   PN = "4"  !CDS_PN = "4";
BODY = "TTL1G08","I118": #LOCATION = "U7E3" !CDS_LOCATION = "U7E3" #SEC = "1" !CDS_SEC = "1";
"A<0>":   PN = "1"  !CDS_PN = "1";
"B<0>":   PN = "2"  !CDS_PN = "2";
"Y<0>":   PN = "4"  !CDS_PN = "4";
BODY = "FET_N","I122": #LOCATION = "Q7E4" !CDS_LOCATION = "Q7E4" &SEC = "1" #&CDS_SEC = "1";
"DRN":   PN = "3"  !CDS_PN = "3";
"GATE":   PN = "1"  !CDS_PN = "1";
"SRC":   PN = "2"  !CDS_PN = "2";
BODY = "FET_N","I123": #LOCATION = "Q7E8" !CDS_LOCATION = "Q7E8" &SEC = "1" #&CDS_SEC = "1";
"DRN":   PN = "3"  !CDS_PN = "3";
"GATE":   PN = "1"  !CDS_PN = "1";
"SRC":   PN = "2"  !CDS_PN = "2";
DRAWING = "@baseboard_fab2_lib.baseboard_fab2(sch_1):page96";
BODY = "RES","I2": #LOCATION = "R6D12" !CDS_LOCATION = "R6D12" #SEC = "1" !CDS_SEC = "1";
"A":   PN = "1"  !CDS_PN = "1";
"B":   PN = "2"  !CDS_PN = "2";
BODY = "RES","I3": #LOCATION = "R6D8" !CDS_LOCATION = "R6D8" #SEC = "1" !CDS_SEC = "1";
"A":   PN = "1"  !CDS_PN = "1";
"B":   PN = "2"  !CDS_PN = "2";
BODY = "RES","I5": #LOCATION = "R3P29" !CDS_LOCATION = "R3P29" &SEC = "1" #&CDS_SEC = "1";
"A":   PN = "1"  !CDS_PN = "1";
"B":   PN = "2"  !CDS_PN = "2";
BODY = "RES","I7": #LOCATION = "R3P38" !CDS_LOCATION = "R3P38" &SEC = "1" #&CDS_SEC = "1";
"A":   PN = "1"  !CDS_PN = "1";
"B":   PN = "2"  !CDS_PN = "2";
BODY = "RES","I25": #LOCATION = "R3D20" !CDS_LOCATION = "R3D20" #SEC = "1" !CDS_SEC = "1";
"A":   PN = "1"  !CDS_PN = "1";
"B":   PN = "2"  !CDS_PN = "2";
BODY = "RES","I26": #LOCATION = "R3D15" !CDS_LOCATION = "R3D15" #SEC = "1" !CDS_SEC = "1";
"A":   PN = "1"  !CDS_PN = "1";
"B":   PN = "2"  !CDS_PN = "2";
BODY = "RES","I28": #LOCATION = "R7M9" !CDS_LOCATION = "R7M9" &SEC = "1" #&CDS_SEC = "1";
"A":   PN = "1"  !CDS_PN = "1";
"B":   PN = "2"  !CDS_PN = "2";
BODY = "RES","I30": #LOCATION = "R3D21" !CDS_LOCATION = "R3D21" &SEC = "1" #&CDS_SEC = "1";
"A":   PN = "1"  !CDS_PN = "1";
"B":   PN = "2"  !CDS_PN = "2";
BODY = "RES","I36": #LOCATION = "R3P36" !CDS_LOCATION = "R3P36" &SEC = "1" #&CDS_SEC = "1";
"A":   PN = "1"  !CDS_PN = "1";
"B":   PN = "2"  !CDS_PN = "2";
BODY = "GTL2014","I42": #LOCATION = "U3P1" !CDS_LOCATION = "U3P1" &SEC = "1" #&CDS_SEC = "1";
"A0":   PN = "13"  !CDS_PN = "13";
"A1":   PN = "12"  !CDS_PN = "12";
"A2":   PN = "10"  !CDS_PN = "10";
"A3":   PN = "9"  !CDS_PN = "9";
"B0":   PN = "2"  !CDS_PN = "2";
"B1":   PN = "3"  !CDS_PN = "3";
"B2":   PN = "5"  !CDS_PN = "5";
"B3":   PN = "6"  !CDS_PN = "6";
"DIR":   PN = "1"  !CDS_PN = "1";
"GND<0>":   PN = "7"  !CDS_PN = "7";
"GND<1>":   PN = "8"  !CDS_PN = "8";
"GND<2>":   PN = "11"  !CDS_PN = "11";
"VCC":   PN = "14"  !CDS_PN = "14";
"VREF":   PN = "4"  !CDS_PN = "4";
BODY = "GTL2014","I46": #LOCATION = "U4C2" !CDS_LOCATION = "U4C2" &SEC = "1" #&CDS_SEC = "1";
"A0":   PN = "13"  !CDS_PN = "13";
"A1":   PN = "12"  !CDS_PN = "12";
"A2":   PN = "10"  !CDS_PN = "10";
"A3":   PN = "9"  !CDS_PN = "9";
"B0":   PN = "2"  !CDS_PN = "2";
"B1":   PN = "3"  !CDS_PN = "3";
"B2":   PN = "5"  !CDS_PN = "5";
"B3":   PN = "6"  !CDS_PN = "6";
"DIR":   PN = "1"  !CDS_PN = "1";
"GND<0>":   PN = "7"  !CDS_PN = "7";
"GND<1>":   PN = "8"  !CDS_PN = "8";
"GND<2>":   PN = "11"  !CDS_PN = "11";
"VCC":   PN = "14"  !CDS_PN = "14";
"VREF":   PN = "4"  !CDS_PN = "4";
BODY = "RES","I55": #LOCATION = "R4C8" !CDS_LOCATION = "R4C8" &SEC = "1" #&CDS_SEC = "1";
"A":   PN = "1"  !CDS_PN = "1";
"B":   PN = "2"  !CDS_PN = "2";
BODY = "RES","I69": #LOCATION = "R4C9" !CDS_LOCATION = "R4C9" #SEC = "1" !CDS_SEC = "1";
"A":   PN = "1"  !CDS_PN = "1";
"B":   PN = "2"  !CDS_PN = "2";
BODY = "RES","I71": #LOCATION = "R3P32" !CDS_LOCATION = "R3P32" #SEC = "1" !CDS_SEC = "1";
"A":   PN = "1"  !CDS_PN = "1";
"B":   PN = "2"  !CDS_PN = "2";
BODY = "CAP_A","I73": #LOCATION = "C3P42" !CDS_LOCATION = "C3P42" #SEC = "1" !CDS_SEC = "1";
"A":   PN = "1"  !CDS_PN = "1";
"B":   PN = "2"  !CDS_PN = "2";
BODY = "CAP_A","I75": #LOCATION = "C4C3" !CDS_LOCATION = "C4C3" #SEC = "1" !CDS_SEC = "1";
"A":   PN = "1"  !CDS_PN = "1";
"B":   PN = "2"  !CDS_PN = "2";
DRAWING = "@baseboard_fab2_lib.baseboard_fab2(sch_1):page97";
BODY = "RES","I33": #LOCATION = "R3D18" !CDS_LOCATION = "R3D18" &SEC = "1" #&CDS_SEC = "1";
"A":   PN = "1"  !CDS_PN = "1";
"B":   PN = "2"  !CDS_PN = "2";
BODY = "RES","I42": #LOCATION = "R4R4" !CDS_LOCATION = "R4R4" &SEC = "1" #&CDS_SEC = "1";
"A":   PN = "1"  !CDS_PN = "1";
"B":   PN = "2"  !CDS_PN = "2";
BODY = "RES","I44": #LOCATION = "R7P20" !CDS_LOCATION = "R7P20" &SEC = "1" #&CDS_SEC = "1";
"A":   PN = "1"  !CDS_PN = "1";
"B":   PN = "2"  !CDS_PN = "2";
BODY = "RES","I72": #LOCATION = "R4P21" !CDS_LOCATION = "R4P21" #SEC = "1" !CDS_SEC = "1";
"A":   PN = "1"  !CDS_PN = "1";
"B":   PN = "2"  !CDS_PN = "2";
BODY = "RES","I76": #LOCATION = "R4C10" !CDS_LOCATION = "R4C10" #SEC = "1" !CDS_SEC = "1";
"A":   PN = "1"  !CDS_PN = "1";
"B":   PN = "2"  !CDS_PN = "2";
BODY = "RES","I80": #LOCATION = "R4P5" !CDS_LOCATION = "R4P5" #SEC = "1" !CDS_SEC = "1";
"A":   PN = "1"  !CDS_PN = "1";
"B":   PN = "2"  !CDS_PN = "2";
BODY = "RES","I81": #LOCATION = "R7P13" !CDS_LOCATION = "R7P13" #SEC = "1" !CDS_SEC = "1";
"A":   PN = "1"  !CDS_PN = "1";
"B":   PN = "2"  !CDS_PN = "2";
DRAWING = "@baseboard_fab2_lib.baseboard_fab2(sch_1):page98";
BODY = "RES","I4": #LOCATION = "R4F5" !CDS_LOCATION = "R4F5" #SEC = "1" !CDS_SEC = "1";
"A":   PN = "1"  !CDS_PN = "1";
"B":   PN = "2"  !CDS_PN = "2";
BODY = "RES","I5": #LOCATION = "R4F3" !CDS_LOCATION = "R4F3" #SEC = "1" !CDS_SEC = "1";
"A":   PN = "1"  !CDS_PN = "1";
"B":   PN = "2"  !CDS_PN = "2";
BODY = "CAP_A","I7": #LOCATION = "C4F9" !CDS_LOCATION = "C4F9" #SEC = "1" !CDS_SEC = "1";
"A":   PN = "1"  !CDS_PN = "1";
"B":   PN = "2"  !CDS_PN = "2";
BODY = "RES","I9": #LOCATION = "R6M1" !CDS_LOCATION = "R6M1" #SEC = "1" !CDS_SEC = "1";
"A":   PN = "1"  !CDS_PN = "1";
"B":   PN = "2"  !CDS_PN = "2";
BODY = "RES","I12": #LOCATION = "R6L16" !CDS_LOCATION = "R6L16" #SEC = "1" !CDS_SEC = "1";
"A":   PN = "1"  !CDS_PN = "1";
"B":   PN = "2"  !CDS_PN = "2";
BODY = "RES","I14": #LOCATION = "R6M2" !CDS_LOCATION = "R6M2" #SEC = "1" !CDS_SEC = "1";
"A":   PN = "1"  !CDS_PN = "1";
"B":   PN = "2"  !CDS_PN = "2";
BODY = "CAP_A","I33": #LOCATION = "C6M2" !CDS_LOCATION = "C6M2" #SEC = "1" !CDS_SEC = "1";
"A":   PN = "1"  !CDS_PN = "1";
"B":   PN = "2"  !CDS_PN = "2";
BODY = "RES","I36": #LOCATION = "R4F4" !CDS_LOCATION = "R4F4" #SEC = "1" !CDS_SEC = "1";
"A":   PN = "1"  !CDS_PN = "1";
"B":   PN = "2"  !CDS_PN = "2";
BODY = "RES","I38": #LOCATION = "R4G2" !CDS_LOCATION = "R4G2" #SEC = "1" !CDS_SEC = "1";
"A":   PN = "1"  !CDS_PN = "1";
"B":   PN = "2"  !CDS_PN = "2";
BODY = "RES","I40": #LOCATION = "R4G3" !CDS_LOCATION = "R4G3" #SEC = "1" !CDS_SEC = "1";
"A":   PN = "1"  !CDS_PN = "1";
"B":   PN = "2"  !CDS_PN = "2";
BODY = "RES","I42": #LOCATION = "R4G1" !CDS_LOCATION = "R4G1" #SEC = "1" !CDS_SEC = "1";
"A":   PN = "1"  !CDS_PN = "1";
"B":   PN = "2"  !CDS_PN = "2";
BODY = "CAP_A","I43": #LOCATION = "C4G1" !CDS_LOCATION = "C4G1" #SEC = "1" !CDS_SEC = "1";
"A":   PN = "1"  !CDS_PN = "1";
"B":   PN = "2"  !CDS_PN = "2";
BODY = "RES","I46": #LOCATION = "R4G21" !CDS_LOCATION = "R4G21" #SEC = "1" !CDS_SEC = "1";
"A":   PN = "1"  !CDS_PN = "1";
"B":   PN = "2"  !CDS_PN = "2";
BODY = "RES","I48": #LOCATION = "R4G22" !CDS_LOCATION = "R4G22" #SEC = "1" !CDS_SEC = "1";
"A":   PN = "1"  !CDS_PN = "1";
"B":   PN = "2"  !CDS_PN = "2";
BODY = "RES","I50": #LOCATION = "R4G20" !CDS_LOCATION = "R4G20" #SEC = "1" !CDS_SEC = "1";
"A":   PN = "1"  !CDS_PN = "1";
"B":   PN = "2"  !CDS_PN = "2";
BODY = "CAP_A","I51": #LOCATION = "C4G17" !CDS_LOCATION = "C4G17" #SEC = "1" !CDS_SEC = "1";
"A":   PN = "1"  !CDS_PN = "1";
"B":   PN = "2"  !CDS_PN = "2";
BODY = "RES","I54": #LOCATION = "R6L13" !CDS_LOCATION = "R6L13" #SEC = "1" !CDS_SEC = "1";
"A":   PN = "1"  !CDS_PN = "1";
"B":   PN = "2"  !CDS_PN = "2";
BODY = "RES","I56": #LOCATION = "R6L12" !CDS_LOCATION = "R6L12" #SEC = "1" !CDS_SEC = "1";
"A":   PN = "1"  !CDS_PN = "1";
"B":   PN = "2"  !CDS_PN = "2";
BODY = "RES","I58": #LOCATION = "R6L14" !CDS_LOCATION = "R6L14" #SEC = "1" !CDS_SEC = "1";
"A":   PN = "1"  !CDS_PN = "1";
"B":   PN = "2"  !CDS_PN = "2";
BODY = "CAP_A","I59": #LOCATION = "C6L7" !CDS_LOCATION = "C6L7" #SEC = "1" !CDS_SEC = "1";
"A":   PN = "1"  !CDS_PN = "1";
"B":   PN = "2"  !CDS_PN = "2";
BODY = "RES","I62": #LOCATION = "R6L2" !CDS_LOCATION = "R6L2" #SEC = "1" !CDS_SEC = "1";
"A":   PN = "1"  !CDS_PN = "1";
"B":   PN = "2"  !CDS_PN = "2";
BODY = "RES","I64": #LOCATION = "R6L1" !CDS_LOCATION = "R6L1" #SEC = "1" !CDS_SEC = "1";
"A":   PN = "1"  !CDS_PN = "1";
"B":   PN = "2"  !CDS_PN = "2";
BODY = "RES","I66": #LOCATION = "R6L3" !CDS_LOCATION = "R6L3" #SEC = "1" !CDS_SEC = "1";
"A":   PN = "1"  !CDS_PN = "1";
"B":   PN = "2"  !CDS_PN = "2";
BODY = "CAP_A","I67": #LOCATION = "C6L2" !CDS_LOCATION = "C6L2" #SEC = "1" !CDS_SEC = "1";
"A":   PN = "1"  !CDS_PN = "1";
"B":   PN = "2"  !CDS_PN = "2";
DRAWING = "@baseboard_fab2_lib.baseboard_fab2(sch_1):page99";
BODY = "CAP_A","I2": #LOCATION = "C6F2" !CDS_LOCATION = "C6F2" &SEC = "1" #&CDS_SEC = "1";
"A":   PN = "1"  !CDS_PN = "1";
"B":   PN = "2"  !CDS_PN = "2";
BODY = "CAP_A","I7": #LOCATION = "C6F3" !CDS_LOCATION = "C6F3" &SEC = "1" #&CDS_SEC = "1";
"A":   PN = "1"  !CDS_PN = "1";
"B":   PN = "2"  !CDS_PN = "2";
BODY = "RES","I9": #LOCATION = "R4T9" !CDS_LOCATION = "R4T9" &SEC = "1" #&CDS_SEC = "1";
"A":   PN = "1"  !CDS_PN = "1";
"B":   PN = "2"  !CDS_PN = "2";
BODY = "RES","I10": #LOCATION = "R4T10" !CDS_LOCATION = "R4T10" &SEC = "1" #&CDS_SEC = "1";
"A":   PN = "1"  !CDS_PN = "1";
"B":   PN = "2"  !CDS_PN = "2";
BODY = "RES","I11": #LOCATION = "R4T8" !CDS_LOCATION = "R4T8" #SEC = "1" !CDS_SEC = "1";
"A":   PN = "1"  !CDS_PN = "1";
"B":   PN = "2"  !CDS_PN = "2";
BODY = "RES","I13": #LOCATION = "R4T7" !CDS_LOCATION = "R4T7" #SEC = "1" !CDS_SEC = "1";
"A":   PN = "1"  !CDS_PN = "1";
"B":   PN = "2"  !CDS_PN = "2";
BODY = "PCA9617","I15": #LOCATION = "U6F1" !CDS_LOCATION = "U6F1" &SEC = "1" #&CDS_SEC = "1";
"EN":   PN = "5"  !CDS_PN = "5";
"SCLA":   PN = "2"  !CDS_PN = "2";
"SCLB":   PN = "7"  !CDS_PN = "7";
"SDAA":   PN = "3"  !CDS_PN = "3";
"SDAB":   PN = "6"  !CDS_PN = "6";
"VCCA":   PN = "1"  !CDS_PN = "1";
"VCCB":   PN = "8"  !CDS_PN = "8";
BODY = "RES","I17": #LOCATION = "R4T6" !CDS_LOCATION = "R4T6" &SEC = "1" #&CDS_SEC = "1";
"A":   PN = "1"  !CDS_PN = "1";
"B":   PN = "2"  !CDS_PN = "2";
BODY = "RES","I19": #LOCATION = "R4T5" !CDS_LOCATION = "R4T5" &SEC = "1" #&CDS_SEC = "1";
"A":   PN = "1"  !CDS_PN = "1";
"B":   PN = "2"  !CDS_PN = "2";
BODY = "RES","I20": #LOCATION = "R4T4" !CDS_LOCATION = "R4T4" &SEC = "1" #&CDS_SEC = "1";
"A":   PN = "1"  !CDS_PN = "1";
"B":   PN = "2"  !CDS_PN = "2";
BODY = "CAP_A","I23": #LOCATION = "C7E1" !CDS_LOCATION = "C7E1" &SEC = "1" #&CDS_SEC = "1";
"A":   PN = "1"  !CDS_PN = "1";
"B":   PN = "2"  !CDS_PN = "2";
BODY = "CAP_A","I27": #LOCATION = "C4G22" !CDS_LOCATION = "C4G22" &SEC = "1" #&CDS_SEC = "1";
"A":   PN = "1"  !CDS_PN = "1";
"B":   PN = "2"  !CDS_PN = "2";
BODY = "CAP_A","I32": #LOCATION = "C7E2" !CDS_LOCATION = "C7E2" &SEC = "1" #&CDS_SEC = "1";
"A":   PN = "1"  !CDS_PN = "1";
"B":   PN = "2"  !CDS_PN = "2";
BODY = "RES","I34": #LOCATION = "R3R9" !CDS_LOCATION = "R3R9" &SEC = "1" #&CDS_SEC = "1";
"A":   PN = "1"  !CDS_PN = "1";
"B":   PN = "2"  !CDS_PN = "2";
BODY = "RES","I35": #LOCATION = "R3R8" !CDS_LOCATION = "R3R8" &SEC = "1" #&CDS_SEC = "1";
"A":   PN = "1"  !CDS_PN = "1";
"B":   PN = "2"  !CDS_PN = "2";
BODY = "CAP_A","I41": #LOCATION = "C4G25" !CDS_LOCATION = "C4G25" &SEC = "1" #&CDS_SEC = "1";
"A":   PN = "1"  !CDS_PN = "1";
"B":   PN = "2"  !CDS_PN = "2";
BODY = "RES","I42": #LOCATION = "R6U13" !CDS_LOCATION = "R6U13" &SEC = "1" #&CDS_SEC = "1";
"A":   PN = "1"  !CDS_PN = "1";
"B":   PN = "2"  !CDS_PN = "2";
BODY = "CAP_A","I47": #LOCATION = "C3B4" !CDS_LOCATION = "C3B4" &SEC = "1" #&CDS_SEC = "1";
"A":   PN = "1"  !CDS_PN = "1";
"B":   PN = "2"  !CDS_PN = "2";
BODY = "CAP_A","I53": #LOCATION = "C3B5" !CDS_LOCATION = "C3B5" &SEC = "1" #&CDS_SEC = "1";
"A":   PN = "1"  !CDS_PN = "1";
"B":   PN = "2"  !CDS_PN = "2";
BODY = "RES","I55": #LOCATION = "R7M5" !CDS_LOCATION = "R7M5" &SEC = "1" #&CDS_SEC = "1";
"A":   PN = "1"  !CDS_PN = "1";
"B":   PN = "2"  !CDS_PN = "2";
BODY = "RES","I56": #LOCATION = "R7M4" !CDS_LOCATION = "R7M4" &SEC = "1" #&CDS_SEC = "1";
"A":   PN = "1"  !CDS_PN = "1";
"B":   PN = "2"  !CDS_PN = "2";
BODY = "PCA9617","I61": #LOCATION = "U7E1" !CDS_LOCATION = "U7E1" &SEC = "1" #&CDS_SEC = "1";
"EN":   PN = "5"  !CDS_PN = "5";
"SCLA":   PN = "2"  !CDS_PN = "2";
"SCLB":   PN = "7"  !CDS_PN = "7";
"SDAA":   PN = "3"  !CDS_PN = "3";
"SDAB":   PN = "6"  !CDS_PN = "6";
"VCCA":   PN = "1"  !CDS_PN = "1";
"VCCB":   PN = "8"  !CDS_PN = "8";
BODY = "PCA9617","I63": #LOCATION = "U4G1" !CDS_LOCATION = "U4G1" &SEC = "1" #&CDS_SEC = "1";
"EN":   PN = "5"  !CDS_PN = "5";
"SCLA":   PN = "2"  !CDS_PN = "2";
"SCLB":   PN = "7"  !CDS_PN = "7";
"SDAA":   PN = "3"  !CDS_PN = "3";
"SDAB":   PN = "6"  !CDS_PN = "6";
"VCCA":   PN = "1"  !CDS_PN = "1";
"VCCB":   PN = "8"  !CDS_PN = "8";
BODY = "RES","I65": #LOCATION = "R3R13" !CDS_LOCATION = "R3R13" &SEC = "1" #&CDS_SEC = "1";
"A":   PN = "1"  !CDS_PN = "1";
"B":   PN = "2"  !CDS_PN = "2";
BODY = "RES","I67": #LOCATION = "R3P60" !CDS_LOCATION = "R3P60" &SEC = "1" #&CDS_SEC = "1";
"A":   PN = "1"  !CDS_PN = "1";
"B":   PN = "2"  !CDS_PN = "2";
BODY = "RES","I70": #LOCATION = "R6T1" !CDS_LOCATION = "R6T1" &SEC = "1" #&CDS_SEC = "1";
"A":   PN = "1"  !CDS_PN = "1";
"B":   PN = "2"  !CDS_PN = "2";
BODY = "RES","I72": #LOCATION = "R6T2" !CDS_LOCATION = "R6T2" &SEC = "1" #&CDS_SEC = "1";
"A":   PN = "1"  !CDS_PN = "1";
"B":   PN = "2"  !CDS_PN = "2";
BODY = "PCA9617","I75": #LOCATION = "U3B1" !CDS_LOCATION = "U3B1" &SEC = "1" #&CDS_SEC = "1";
"EN":   PN = "5"  !CDS_PN = "5";
"SCLA":   PN = "2"  !CDS_PN = "2";
"SCLB":   PN = "7"  !CDS_PN = "7";
"SDAA":   PN = "3"  !CDS_PN = "3";
"SDAB":   PN = "6"  !CDS_PN = "6";
"VCCA":   PN = "1"  !CDS_PN = "1";
"VCCB":   PN = "8"  !CDS_PN = "8";
BODY = "RES","I77": #LOCATION = "R7M7" !CDS_LOCATION = "R7M7" &SEC = "1" #&CDS_SEC = "1";
"A":   PN = "1"  !CDS_PN = "1";
"B":   PN = "2"  !CDS_PN = "2";
BODY = "RES","I79": #LOCATION = "R7M2" !CDS_LOCATION = "R7M2" &SEC = "1" #&CDS_SEC = "1";
"A":   PN = "1"  !CDS_PN = "1";
"B":   PN = "2"  !CDS_PN = "2";
BODY = "RES","I83": #LOCATION = "R4T3" !CDS_LOCATION = "R4T3" &SEC = "1" #&CDS_SEC = "1";
"A":   PN = "1"  !CDS_PN = "1";
"B":   PN = "2"  !CDS_PN = "2";
BODY = "RES","I88": #LOCATION = "R3R7" !CDS_LOCATION = "R3R7" &SEC = "1" #&CDS_SEC = "1";
"A":   PN = "1"  !CDS_PN = "1";
"B":   PN = "2"  !CDS_PN = "2";
BODY = "RES","I92": #LOCATION = "R6T3" !CDS_LOCATION = "R6T3" &SEC = "1" #&CDS_SEC = "1";
"A":   PN = "1"  !CDS_PN = "1";
"B":   PN = "2"  !CDS_PN = "2";
BODY = "RES","I98": #LOCATION = "R7M3" !CDS_LOCATION = "R7M3" &SEC = "1" #&CDS_SEC = "1";
"A":   PN = "1"  !CDS_PN = "1";
"B":   PN = "2"  !CDS_PN = "2";
BODY = "RES","I101": #LOCATION = "R3R12" !CDS_LOCATION = "R3R12" #SEC = "1" !CDS_SEC = "1";
"A":   PN = "1"  !CDS_PN = "1";
"B":   PN = "2"  !CDS_PN = "2";
BODY = "RES","I103": #LOCATION = "R3R5" !CDS_LOCATION = "R3R5" #SEC = "1" !CDS_SEC = "1";
"A":   PN = "1"  !CDS_PN = "1";
"B":   PN = "2"  !CDS_PN = "2";
BODY = "RES","I104": #LOCATION = "R6U18" !CDS_LOCATION = "R6U18" #SEC = "1" !CDS_SEC = "1";
"A":   PN = "1"  !CDS_PN = "1";
"B":   PN = "2"  !CDS_PN = "2";
BODY = "RES","I106": #LOCATION = "R6U17" !CDS_LOCATION = "R6U17" #SEC = "1" !CDS_SEC = "1";
"A":   PN = "1"  !CDS_PN = "1";
"B":   PN = "2"  !CDS_PN = "2";
BODY = "RES","I107": #LOCATION = "R7M6" !CDS_LOCATION = "R7M6" #SEC = "1" !CDS_SEC = "1";
"A":   PN = "1"  !CDS_PN = "1";
"B":   PN = "2"  !CDS_PN = "2";
BODY = "RES","I109": #LOCATION = "R7M1" !CDS_LOCATION = "R7M1" #SEC = "1" !CDS_SEC = "1";
"A":   PN = "1"  !CDS_PN = "1";
"B":   PN = "2"  !CDS_PN = "2";
BODY = "RES","I110": #LOCATION = "R3R14" !CDS_LOCATION = "R3R14" &SEC = "1" #&CDS_SEC = "1";
"A":   PN = "1"  !CDS_PN = "1";
"B":   PN = "2"  !CDS_PN = "2";
BODY = "RES","I111": #LOCATION = "R6T4" !CDS_LOCATION = "R6T4" &SEC = "1" #&CDS_SEC = "1";
"A":   PN = "1"  !CDS_PN = "1";
"B":   PN = "2"  !CDS_PN = "2";
BODY = "RES","I112": #LOCATION = "R7M8" !CDS_LOCATION = "R7M8" &SEC = "1" #&CDS_SEC = "1";
"A":   PN = "1"  !CDS_PN = "1";
"B":   PN = "2"  !CDS_PN = "2";
BODY = "RES","I115": #LOCATION = "R6U14" !CDS_LOCATION = "R6U14" &SEC = "1" #&CDS_SEC = "1";
"A":   PN = "1"  !CDS_PN = "1";
"B":   PN = "2"  !CDS_PN = "2";
DRAWING = "@baseboard_fab2_lib.baseboard_fab2(sch_1):page100";
BODY = "RES","I2": #LOCATION = "R1F6" !CDS_LOCATION = "R1F6" #SEC = "1" !CDS_SEC = "1";
"A":   PN = "1"  !CDS_PN = "1";
"B":   PN = "2"  !CDS_PN = "2";
BODY = "RES","I4": #LOCATION = "R9L11" !CDS_LOCATION = "R9L11" #SEC = "1" !CDS_SEC = "1";
"A":   PN = "1"  !CDS_PN = "1";
"B":   PN = "2"  !CDS_PN = "2";
BODY = "RES","I6": #LOCATION = "R1F5" !CDS_LOCATION = "R1F5" #SEC = "1" !CDS_SEC = "1";
"A":   PN = "1"  !CDS_PN = "1";
"B":   PN = "2"  !CDS_PN = "2";
BODY = "RES","I7": #LOCATION = "R1F4" !CDS_LOCATION = "R1F4" #SEC = "1" !CDS_SEC = "1";
"A":   PN = "1"  !CDS_PN = "1";
"B":   PN = "2"  !CDS_PN = "2";
BODY = "CAP_A","I8": #LOCATION = "C1F19" !CDS_LOCATION = "C1F19" #SEC = "1" !CDS_SEC = "1";
"A":   PN = "1"  !CDS_PN = "1";
"B":   PN = "2"  !CDS_PN = "2";
BODY = "RES","I11": #LOCATION = "R9M1" !CDS_LOCATION = "R9M1" #SEC = "1" !CDS_SEC = "1";
"A":   PN = "1"  !CDS_PN = "1";
"B":   PN = "2"  !CDS_PN = "2";
BODY = "RES","I13": #LOCATION = "R9M2" !CDS_LOCATION = "R9M2" #SEC = "1" !CDS_SEC = "1";
"A":   PN = "1"  !CDS_PN = "1";
"B":   PN = "2"  !CDS_PN = "2";
BODY = "CAP_A","I15": #LOCATION = "C9M2" !CDS_LOCATION = "C9M2" #SEC = "1" !CDS_SEC = "1";
"A":   PN = "1"  !CDS_PN = "1";
"B":   PN = "2"  !CDS_PN = "2";
BODY = "RES","I19": #LOCATION = "R1G2" !CDS_LOCATION = "R1G2" #SEC = "1" !CDS_SEC = "1";
"A":   PN = "1"  !CDS_PN = "1";
"B":   PN = "2"  !CDS_PN = "2";
BODY = "RES","I20": #LOCATION = "R1G3" !CDS_LOCATION = "R1G3" #SEC = "1" !CDS_SEC = "1";
"A":   PN = "1"  !CDS_PN = "1";
"B":   PN = "2"  !CDS_PN = "2";
BODY = "RES","I22": #LOCATION = "R9L7" !CDS_LOCATION = "R9L7" #SEC = "1" !CDS_SEC = "1";
"A":   PN = "1"  !CDS_PN = "1";
"B":   PN = "2"  !CDS_PN = "2";
BODY = "RES","I24": #LOCATION = "R9L6" !CDS_LOCATION = "R9L6" #SEC = "1" !CDS_SEC = "1";
"A":   PN = "1"  !CDS_PN = "1";
"B":   PN = "2"  !CDS_PN = "2";
BODY = "RES","I25": #LOCATION = "R1G1" !CDS_LOCATION = "R1G1" #SEC = "1" !CDS_SEC = "1";
"A":   PN = "1"  !CDS_PN = "1";
"B":   PN = "2"  !CDS_PN = "2";
BODY = "CAP_A","I26": #LOCATION = "C1G8" !CDS_LOCATION = "C1G8" #SEC = "1" !CDS_SEC = "1";
"A":   PN = "1"  !CDS_PN = "1";
"B":   PN = "2"  !CDS_PN = "2";
BODY = "RES","I29": #LOCATION = "R9L8" !CDS_LOCATION = "R9L8" #SEC = "1" !CDS_SEC = "1";
"A":   PN = "1"  !CDS_PN = "1";
"B":   PN = "2"  !CDS_PN = "2";
BODY = "CAP_A","I30": #LOCATION = "C9L8" !CDS_LOCATION = "C9L8" #SEC = "1" !CDS_SEC = "1";
"A":   PN = "1"  !CDS_PN = "1";
"B":   PN = "2"  !CDS_PN = "2";
BODY = "RES","I35": #LOCATION = "R1G15" !CDS_LOCATION = "R1G15" #SEC = "1" !CDS_SEC = "1";
"A":   PN = "1"  !CDS_PN = "1";
"B":   PN = "2"  !CDS_PN = "2";
BODY = "RES","I36": #LOCATION = "R1G17" !CDS_LOCATION = "R1G17" #SEC = "1" !CDS_SEC = "1";
"A":   PN = "1"  !CDS_PN = "1";
"B":   PN = "2"  !CDS_PN = "2";
BODY = "RES","I38": #LOCATION = "R9L2" !CDS_LOCATION = "R9L2" #SEC = "1" !CDS_SEC = "1";
"A":   PN = "1"  !CDS_PN = "1";
"B":   PN = "2"  !CDS_PN = "2";
BODY = "RES","I40": #LOCATION = "R9L1" !CDS_LOCATION = "R9L1" #SEC = "1" !CDS_SEC = "1";
"A":   PN = "1"  !CDS_PN = "1";
"B":   PN = "2"  !CDS_PN = "2";
BODY = "RES","I41": #LOCATION = "R1G14" !CDS_LOCATION = "R1G14" #SEC = "1" !CDS_SEC = "1";
"A":   PN = "1"  !CDS_PN = "1";
"B":   PN = "2"  !CDS_PN = "2";
BODY = "CAP_A","I42": #LOCATION = "C1G18" !CDS_LOCATION = "C1G18" #SEC = "1" !CDS_SEC = "1";
"A":   PN = "1"  !CDS_PN = "1";
"B":   PN = "2"  !CDS_PN = "2";
BODY = "RES","I45": #LOCATION = "R9L3" !CDS_LOCATION = "R9L3" #SEC = "1" !CDS_SEC = "1";
"A":   PN = "1"  !CDS_PN = "1";
"B":   PN = "2"  !CDS_PN = "2";
BODY = "CAP_A","I46": #LOCATION = "C9L3" !CDS_LOCATION = "C9L3" #SEC = "1" !CDS_SEC = "1";
"A":   PN = "1"  !CDS_PN = "1";
"B":   PN = "2"  !CDS_PN = "2";
DRAWING = "@baseboard_fab2_lib.baseboard_fab2(sch_1):page101";
BODY = "RES","I20": #LOCATION = "R8F29" !CDS_LOCATION = "R8F29" #SEC = "1" !CDS_SEC = "1";
"A":   PN = "1"  !CDS_PN = "1";
"B":   PN = "2"  !CDS_PN = "2";
BODY = "RES","I28": #LOCATION = "R8F25" !CDS_LOCATION = "R8F25" &SEC = "1" #&CDS_SEC = "1";
"A":   PN = "1"  !CDS_PN = "1";
"B":   PN = "2"  !CDS_PN = "2";
BODY = "ICS9FGP204","I34": #LOCATION = "EU8F2" !CDS_LOCATION = "EU8F2" #SEC = "1" !CDS_SEC = "1";
"25MHZ_0":   PN = "16"  !CDS_PN = "16";
"25MHZ_1":   PN = "17"  !CDS_PN = "17";
"32KHZ":   PN = "13"  !CDS_PN = "13";
"33MHZ_SMBADR":   PN = "22"  !CDS_PN = "22";
"CPUCLKC0":   PN = "8"  !CDS_PN = "8";
"CPUCLKT0":   PN = "7"  !CDS_PN = "7";
"DOT96SSC":   PN = "4"  !CDS_PN = "4";
"DOT96SST":   PN = "3"  !CDS_PN = "3";
"GND<0>":   PN = "1"  !CDS_PN = "1";
"GND<1>":   PN = "41"  !CDS_PN = "41";
"GND32K":   PN = "14"  !CDS_PN = "14";
"GND33":   PN = "21"  !CDS_PN = "21";
"GND_RGMII":   PN = "35"  !CDS_PN = "35";
"GNDCPU":   PN = "10"  !CDS_PN = "10";
"GNDREF":   PN = "18"  !CDS_PN = "18";
"GNDRMII<0>":   PN = "27"  !CDS_PN = "27";
"GNDRMII<1>":   PN = "30"  !CDS_PN = "30";
"IREF":   PN = "11"  !CDS_PN = "11";
"OE_96":   PN = "5"  !CDS_PN = "5";
"OE_CPU":   PN = "6"  !CDS_PN = "6";
"RGMII<0>":   PN = "37"  !CDS_PN = "37";
"RGMII<1>":   PN = "36"  !CDS_PN = "36";
"RMII<0>":   PN = "33"  !CDS_PN = "33";
"RMII<1>":   PN = "32"  !CDS_PN = "32";
"RMII<2>":   PN = "29"  !CDS_PN = "29";
"RMII<3>":   PN = "28"  !CDS_PN = "28";
"RMII<4>":   PN = "25"  !CDS_PN = "25";
"RMII<5>":   PN = "24"  !CDS_PN = "24";
"SMBCLK":   PN = "38"  !CDS_PN = "38";
"SMBDAT":   PN = "39"  !CDS_PN = "39";
"VDD32K":   PN = "12"  !CDS_PN = "12";
"VDD33":   PN = "23"  !CDS_PN = "23";
"VDD96":   PN = "2"  !CDS_PN = "2";
"VDD_RGMII":   PN = "34"  !CDS_PN = "34";
"VDDCPU":   PN = "9"  !CDS_PN = "9";
"VDDREF":   PN = "15"  !CDS_PN = "15";
"VDDRMII<0>":   PN = "26"  !CDS_PN = "26";
"VDDRMII<1>":   PN = "31"  !CDS_PN = "31";
"VTTPWR_GD_PD_N":   PN = "40"  !CDS_PN = "40";
"X1_25":   PN = "19"  !CDS_PN = "19";
"X2_25":   PN = "20"  !CDS_PN = "20";
BODY = "RES","I48": #LOCATION = "R2T25" !CDS_LOCATION = "R2T25" #SEC = "1" !CDS_SEC = "1";
"A":   PN = "1"  !CDS_PN = "1";
"B":   PN = "2"  !CDS_PN = "2";
BODY = "CRYSTAL","I52": #LOCATION = "Y8F1" !CDS_LOCATION = "Y8F1" &SEC = "1" #&CDS_SEC = "1";
"A":   PN = "1"  !CDS_PN = "1";
"B":   PN = "3"  !CDS_PN = "3";
BODY = "CAP_A","I89": #LOCATION = "C2T31" !CDS_LOCATION = "C2T31" &SEC = "1" #&CDS_SEC = "1";
"A":   PN = "1"  !CDS_PN = "1";
"B":   PN = "2"  !CDS_PN = "2";
BODY = "CAP_A","I90": #LOCATION = "C2T27" !CDS_LOCATION = "C2T27" &SEC = "1" #&CDS_SEC = "1";
"A":   PN = "1"  !CDS_PN = "1";
"B":   PN = "2"  !CDS_PN = "2";
BODY = "RES","I94": #LOCATION = "R2T23" !CDS_LOCATION = "R2T23" &SEC = "1" #&CDS_SEC = "1";
"A":   PN = "1"  !CDS_PN = "1";
"B":   PN = "2"  !CDS_PN = "2";
BODY = "RES","I95": #LOCATION = "R2T52" !CDS_LOCATION = "R2T52" &SEC = "1" #&CDS_SEC = "1";
"A":   PN = "1"  !CDS_PN = "1";
"B":   PN = "2"  !CDS_PN = "2";
BODY = "CAP_A","I97": #LOCATION = "C2T38" !CDS_LOCATION = "C2T38" &SEC = "1" #&CDS_SEC = "1";
"A":   PN = "1"  !CDS_PN = "1";
"B":   PN = "2"  !CDS_PN = "2";
BODY = "CAP_A","I99": #LOCATION = "C2T37" !CDS_LOCATION = "C2T37" &SEC = "1" #&CDS_SEC = "1";
"A":   PN = "1"  !CDS_PN = "1";
"B":   PN = "2"  !CDS_PN = "2";
BODY = "CAP_A","I104": #LOCATION = "C2T18" !CDS_LOCATION = "C2T18" &SEC = "1" #&CDS_SEC = "1";
"A":   PN = "1"  !CDS_PN = "1";
"B":   PN = "2"  !CDS_PN = "2";
BODY = "RES","I105": #LOCATION = "R2T21" !CDS_LOCATION = "R2T21" #SEC = "1" !CDS_SEC = "1";
"A":   PN = "1"  !CDS_PN = "1";
"B":   PN = "2"  !CDS_PN = "2";
BODY = "CAP_A","I106": #LOCATION = "C2T19" !CDS_LOCATION = "C2T19" &SEC = "1" #&CDS_SEC = "1";
"A":   PN = "1"  !CDS_PN = "1";
"B":   PN = "2"  !CDS_PN = "2";
BODY = "CAP_A","I109": #LOCATION = "C2T34" !CDS_LOCATION = "C2T34" #SEC = "1" !CDS_SEC = "1";
"A":   PN = "1"  !CDS_PN = "1";
"B":   PN = "2"  !CDS_PN = "2";
BODY = "CAP_A","I110": #LOCATION = "C2T30" !CDS_LOCATION = "C2T30" &SEC = "1" #&CDS_SEC = "1";
"A":   PN = "1"  !CDS_PN = "1";
"B":   PN = "2"  !CDS_PN = "2";
BODY = "CAP_A","I111": #LOCATION = "C2T25" !CDS_LOCATION = "C2T25" &SEC = "1" #&CDS_SEC = "1";
"A":   PN = "1"  !CDS_PN = "1";
"B":   PN = "2"  !CDS_PN = "2";
BODY = "CAP_A","I112": #LOCATION = "C2T17" !CDS_LOCATION = "C2T17" &SEC = "1" #&CDS_SEC = "1";
"A":   PN = "1"  !CDS_PN = "1";
"B":   PN = "2"  !CDS_PN = "2";
BODY = "CAP","I113": #LOCATION = "C2T22" !CDS_LOCATION = "C2T22" #SEC = "1" !CDS_SEC = "1";
"A":   PN = "1"  !CDS_PN = "1";
"B":   PN = "2"  !CDS_PN = "2";
BODY = "FERRITE","I114": #LOCATION = "FB2T2" !CDS_LOCATION = "FB2T2" &SEC = "1" #&CDS_SEC = "1";
"A":   PN = "1"  !CDS_PN = "1";
"B":   PN = "2"  !CDS_PN = "2";
BODY = "CAP_A","I116": #LOCATION = "C2T28" !CDS_LOCATION = "C2T28" &SEC = "1" #&CDS_SEC = "1";
"A":   PN = "1"  !CDS_PN = "1";
"B":   PN = "2"  !CDS_PN = "2";
BODY = "RES","I124": #LOCATION = "R2T42" !CDS_LOCATION = "R2T42" #SEC = "1" !CDS_SEC = "1";
"A":   PN = "1"  !CDS_PN = "1";
"B":   PN = "2"  !CDS_PN = "2";
BODY = "RES","I125": #LOCATION = "R2T46" !CDS_LOCATION = "R2T46" #SEC = "1" !CDS_SEC = "1";
"A":   PN = "1"  !CDS_PN = "1";
"B":   PN = "2"  !CDS_PN = "2";
BODY = "RES","I130": #LOCATION = "R2T47" !CDS_LOCATION = "R2T47" #SEC = "1" !CDS_SEC = "1";
"A":   PN = "1"  !CDS_PN = "1";
"B":   PN = "2"  !CDS_PN = "2";
BODY = "RES","I134": #LOCATION = "R1W22" !CDS_LOCATION = "R1W22" #SEC = "1" !CDS_SEC = "1";
"A":   PN = "1"  !CDS_PN = "1";
"B":   PN = "2"  !CDS_PN = "2";
BODY = "RES","I135": #LOCATION = "R1W23" !CDS_LOCATION = "R1W23" #SEC = "1" !CDS_SEC = "1";
"A":   PN = "1"  !CDS_PN = "1";
"B":   PN = "2"  !CDS_PN = "2";
BODY = "RES","I138": #LOCATION = "R1W24" !CDS_LOCATION = "R1W24" #SEC = "1" !CDS_SEC = "1";
"A":   PN = "1"  !CDS_PN = "1";
"B":   PN = "2"  !CDS_PN = "2";
BODY = "CAP","I139": #LOCATION = "C1W17" !CDS_LOCATION = "C1W17" #SEC = "1" !CDS_SEC = "1";
"A":   PN = "1"  !CDS_PN = "1";
"B":   PN = "2"  !CDS_PN = "2";
BODY = "RES","I140": #LOCATION = "R1W25" !CDS_LOCATION = "R1W25" #SEC = "1" !CDS_SEC = "1";
"A":   PN = "1"  !CDS_PN = "1";
"B":   PN = "2"  !CDS_PN = "2";
BODY = "RES","I142": #LOCATION = "R8F27" !CDS_LOCATION = "R8F27" #SEC = "1" !CDS_SEC = "1";
"A":   PN = "1"  !CDS_PN = "1";
"B":   PN = "2"  !CDS_PN = "2";
BODY = "RES","I143": #LOCATION = "R8G24" !CDS_LOCATION = "R8G24" #SEC = "1" !CDS_SEC = "1";
"A":   PN = "1"  !CDS_PN = "1";
"B":   PN = "2"  !CDS_PN = "2";
BODY = "RES","I144": #LOCATION = "R8G25" !CDS_LOCATION = "R8G25" #SEC = "1" !CDS_SEC = "1";
"A":   PN = "1"  !CDS_PN = "1";
"B":   PN = "2"  !CDS_PN = "2";
BODY = "RES","I145": #LOCATION = "R8G1" !CDS_LOCATION = "R8G1" #SEC = "1" !CDS_SEC = "1";
"A":   PN = "1"  !CDS_PN = "1";
"B":   PN = "2"  !CDS_PN = "2";
BODY = "CAP","I146": #LOCATION = "C8F19" !CDS_LOCATION = "C8F19" #SEC = "1" !CDS_SEC = "1";
"A":   PN = "1"  !CDS_PN = "1";
"B":   PN = "2"  !CDS_PN = "2";
BODY = "CAP","I147": #LOCATION = "C8F18" !CDS_LOCATION = "C8F18" #SEC = "1" !CDS_SEC = "1";
"A":   PN = "1"  !CDS_PN = "1";
"B":   PN = "2"  !CDS_PN = "2";
DRAWING = "@baseboard_fab2_lib.baseboard_fab2(sch_1):page102";
BODY = "NB3W1200L","I1": #LOCATION = "EU4D2" !CDS_LOCATION = "EU4D2" #SEC = "1" !CDS_SEC = "1";
"100M_133M_N":   PN = "4"  !CDS_PN = "4";
"CLK_INN":   PN = "10"  !CDS_PN = "10";
"CLK_INP":   PN = "9"  !CDS_PN = "9";
"DIF_0N":   PN = "18"  !CDS_PN = "18";
"DIF_0P":   PN = "17"  !CDS_PN = "17";
"DIF_1N":   PN = "22"  !CDS_PN = "22";
"DIF_1P":   PN = "21"  !CDS_PN = "21";
"DIF_2N":   PN = "27"  !CDS_PN = "27";
"DIF_2P":   PN = "26"  !CDS_PN = "26";
"DIF_3N":   PN = "31"  !CDS_PN = "31";
"DIF_3P":   PN = "30"  !CDS_PN = "30";
"DIF_4N":   PN = "35"  !CDS_PN = "35";
"DIF_4P":   PN = "34"  !CDS_PN = "34";
"DIF_5N":   PN = "39"  !CDS_PN = "39";
"DIF_5P":   PN = "38"  !CDS_PN = "38";
"DIF_6N":   PN = "43"  !CDS_PN = "43";
"DIF_6P":   PN = "42"  !CDS_PN = "42";
"DIF_7N":   PN = "47"  !CDS_PN = "47";
"DIF_7P":   PN = "46"  !CDS_PN = "46";
"DIF_8N":   PN = "51"  !CDS_PN = "51";
"DIF_8P":   PN = "50"  !CDS_PN = "50";
"DIF_9N":   PN = "55"  !CDS_PN = "55";
"DIF_9P":   PN = "54"  !CDS_PN = "54";
"DIF_10N":   PN = "60"  !CDS_PN = "60";
"DIF_10P":   PN = "59"  !CDS_PN = "59";
"DIF_11N":   PN = "64"  !CDS_PN = "64";
"DIF_11P":   PN = "63"  !CDS_PN = "63";
"GND<0>":   PN = "7"  !CDS_PN = "7";
"GND<1>":   PN = "23"  !CDS_PN = "23";
"GND<2>":   PN = "33"  !CDS_PN = "33";
"GND<3>":   PN = "41"  !CDS_PN = "41";
"GND<4>":   PN = "48"  !CDS_PN = "48";
"GND<5>":   PN = "58"  !CDS_PN = "58";
"GNDA":   PN = "2"  !CDS_PN = "2";
"HBW_BYPASS_LOBW_N":   PN = "5"  !CDS_PN = "5";
"NC<0>":   PN = "3"  !CDS_PN = "3";
"NC<1>":   PN = "16"  !CDS_PN = "16";
"NC<2>":   PN = "15"  !CDS_PN = "15";
"OE_0_N":   PN = "19"  !CDS_PN = "19";
"OE_1_N":   PN = "20"  !CDS_PN = "20";
"OE_2_N":   PN = "28"  !CDS_PN = "28";
"OE_3_N":   PN = "29"  !CDS_PN = "29";
"OE_4_N":   PN = "36"  !CDS_PN = "36";
"OE_5_N":   PN = "37"  !CDS_PN = "37";
"OE_6_N":   PN = "44"  !CDS_PN = "44";
"OE_7_N":   PN = "45"  !CDS_PN = "45";
"OE_8_N":   PN = "52"  !CDS_PN = "52";
"OE_9_N":   PN = "53"  !CDS_PN = "53";
"OE_10_N":   PN = "61"  !CDS_PN = "61";
"OE_11_N":   PN = "62"  !CDS_PN = "62";
"PWRGD_PWRDN_N":   PN = "6"  !CDS_PN = "6";
"SA_0":   PN = "11"  !CDS_PN = "11";
"SA_1":   PN = "14"  !CDS_PN = "14";
"SCL":   PN = "13"  !CDS_PN = "13";
"SDA":   PN = "12"  !CDS_PN = "12";
"THPAD":   PN = "65"  !CDS_PN = "65";
"VDD<0>":   PN = "24"  !CDS_PN = "24";
"VDD<1>":   PN = "40"  !CDS_PN = "40";
"VDD<2>":   PN = "57"  !CDS_PN = "57";
"VDDA":   PN = "1"  !CDS_PN = "1";
"VDDIO<0>":   PN = "25"  !CDS_PN = "25";
"VDDIO<1>":   PN = "32"  !CDS_PN = "32";
"VDDIO<2>":   PN = "49"  !CDS_PN = "49";
"VDDIO<3>":   PN = "56"  !CDS_PN = "56";
"VDDR":   PN = "8"  !CDS_PN = "8";
BODY = "FERRITE","I8": #LOCATION = "FB6P1" !CDS_LOCATION = "FB6P1" #SEC = "1" !CDS_SEC = "1";
"A":   PN = "1"  !CDS_PN = "1";
"B":   PN = "2"  !CDS_PN = "2";
BODY = "CAP","I10": #LOCATION = "C3D22" !CDS_LOCATION = "C3D22" #SEC = "1" !CDS_SEC = "1";
"A":   PN = "1"  !CDS_PN = "1";
"B":   PN = "2"  !CDS_PN = "2";
BODY = "CAP_A","I11": #LOCATION = "C6P4" !CDS_LOCATION = "C6P4" #SEC = "1" !CDS_SEC = "1";
"A":   PN = "1"  !CDS_PN = "1";
"B":   PN = "2"  !CDS_PN = "2";
BODY = "CAP_A","I12": #LOCATION = "C6P6" !CDS_LOCATION = "C6P6" #SEC = "1" !CDS_SEC = "1";
"A":   PN = "1"  !CDS_PN = "1";
"B":   PN = "2"  !CDS_PN = "2";
BODY = "CAP_A","I13": #LOCATION = "C6P10" !CDS_LOCATION = "C6P10" #SEC = "1" !CDS_SEC = "1";
"A":   PN = "1"  !CDS_PN = "1";
"B":   PN = "2"  !CDS_PN = "2";
BODY = "CAP_A","I14": #LOCATION = "C6P5" !CDS_LOCATION = "C6P5" #SEC = "1" !CDS_SEC = "1";
"A":   PN = "1"  !CDS_PN = "1";
"B":   PN = "2"  !CDS_PN = "2";
BODY = "CAP_A","I15": #LOCATION = "C6P12" !CDS_LOCATION = "C6P12" #SEC = "1" !CDS_SEC = "1";
"A":   PN = "1"  !CDS_PN = "1";
"B":   PN = "2"  !CDS_PN = "2";
BODY = "CAP_A","I16": #LOCATION = "C6P11" !CDS_LOCATION = "C6P11" #SEC = "1" !CDS_SEC = "1";
"A":   PN = "1"  !CDS_PN = "1";
"B":   PN = "2"  !CDS_PN = "2";
BODY = "CAP_A","I18": #LOCATION = "C4D24" !CDS_LOCATION = "C4D24" #SEC = "1" !CDS_SEC = "1";
"A":   PN = "1"  !CDS_PN = "1";
"B":   PN = "2"  !CDS_PN = "2";
BODY = "CAP_A","I19": #LOCATION = "C4D23" !CDS_LOCATION = "C4D23" #SEC = "1" !CDS_SEC = "1";
"A":   PN = "1"  !CDS_PN = "1";
"B":   PN = "2"  !CDS_PN = "2";
BODY = "RES","I21": #LOCATION = "R3D14" !CDS_LOCATION = "R3D14" #SEC = "1" !CDS_SEC = "1";
"A":   PN = "1"  !CDS_PN = "1";
"B":   PN = "2"  !CDS_PN = "2";
BODY = "RES","I26": #LOCATION = "R6P25" !CDS_LOCATION = "R6P25" #SEC = "1" !CDS_SEC = "1";
"A":   PN = "1"  !CDS_PN = "1";
"B":   PN = "2"  !CDS_PN = "2";
BODY = "CAP_A","I28": #LOCATION = "C4D22" !CDS_LOCATION = "C4D22" #SEC = "1" !CDS_SEC = "1";
"A":   PN = "1"  !CDS_PN = "1";
"B":   PN = "2"  !CDS_PN = "2";
BODY = "CAP_A","I30": #LOCATION = "C4D27" !CDS_LOCATION = "C4D27" #SEC = "1" !CDS_SEC = "1";
"A":   PN = "1"  !CDS_PN = "1";
"B":   PN = "2"  !CDS_PN = "2";
BODY = "RES","I37": #LOCATION = "R4D38" !CDS_LOCATION = "R4D38" #SEC = "1" !CDS_SEC = "1";
"A":   PN = "1"  !CDS_PN = "1";
"B":   PN = "2"  !CDS_PN = "2";
BODY = "RES","I38": #LOCATION = "R4D35" !CDS_LOCATION = "R4D35" #SEC = "1" !CDS_SEC = "1";
"A":   PN = "1"  !CDS_PN = "1";
"B":   PN = "2"  !CDS_PN = "2";
BODY = "RES","I45": #LOCATION = "R4D40" !CDS_LOCATION = "R4D40" #SEC = "1" !CDS_SEC = "1";
"A":   PN = "1"  !CDS_PN = "1";
"B":   PN = "2"  !CDS_PN = "2";
BODY = "RES","I46": #LOCATION = "R6P23" !CDS_LOCATION = "R6P23" #SEC = "1" !CDS_SEC = "1";
"A":   PN = "1"  !CDS_PN = "1";
"B":   PN = "2"  !CDS_PN = "2";
BODY = "RES","I47": #LOCATION = "R6P22" !CDS_LOCATION = "R6P22" #SEC = "1" !CDS_SEC = "1";
"A":   PN = "1"  !CDS_PN = "1";
"B":   PN = "2"  !CDS_PN = "2";
BODY = "RES","I53": #LOCATION = "R4D41" !CDS_LOCATION = "R4D41" #SEC = "1" !CDS_SEC = "1";
"A":   PN = "1"  !CDS_PN = "1";
"B":   PN = "2"  !CDS_PN = "2";
BODY = "CAP_A","I79": #LOCATION = "C6P9" !CDS_LOCATION = "C6P9" #SEC = "1" !CDS_SEC = "1";
"A":   PN = "1"  !CDS_PN = "1";
"B":   PN = "2"  !CDS_PN = "2";
BODY = "RES","I80": #LOCATION = "R6P21" !CDS_LOCATION = "R6P21" #SEC = "1" !CDS_SEC = "1";
"A":   PN = "1"  !CDS_PN = "1";
"B":   PN = "2"  !CDS_PN = "2";
BODY = "RES","I81": #LOCATION = "R6P20" !CDS_LOCATION = "R6P20" #SEC = "1" !CDS_SEC = "1";
"A":   PN = "1"  !CDS_PN = "1";
"B":   PN = "2"  !CDS_PN = "2";
BODY = "RES","I93": #LOCATION = "R4D69" !CDS_LOCATION = "R4D69" #SEC = "1" !CDS_SEC = "1";
"A":   PN = "1"  !CDS_PN = "1";
"B":   PN = "2"  !CDS_PN = "2";
BODY = "RES","I94": #LOCATION = "R4D70" !CDS_LOCATION = "R4D70" #SEC = "1" !CDS_SEC = "1";
"A":   PN = "1"  !CDS_PN = "1";
"B":   PN = "2"  !CDS_PN = "2";
BODY = "FET_N_DUAL","I101": #LOCATION = "Q4W1" !CDS_LOCATION = "Q4W1" #SEC = "2" !CDS_SEC = "2";
"DRAIN<0>":   PN = "3"  !CDS_PN = "3";
"GATE<0>":   PN = "5"  !CDS_PN = "5";
"SOURCE<0>":   PN = "4"  !CDS_PN = "4";
BODY = "FET_N_DUAL","I102": #LOCATION = "Q4W1" !CDS_LOCATION = "Q4W1" #SEC = "1" !CDS_SEC = "1";
"DRAIN<0>":   PN = "6"  !CDS_PN = "6";
"GATE<0>":   PN = "2"  !CDS_PN = "2";
"SOURCE<0>":   PN = "1"  !CDS_PN = "1";
BODY = "RES","I103": #LOCATION = "R4W2" !CDS_LOCATION = "R4W2" #SEC = "1" !CDS_SEC = "1";
"A":   PN = "1"  !CDS_PN = "1";
"B":   PN = "2"  !CDS_PN = "2";
BODY = "RES","I105": #LOCATION = "R4W3" !CDS_LOCATION = "R4W3" #SEC = "1" !CDS_SEC = "1";
"A":   PN = "1"  !CDS_PN = "1";
"B":   PN = "2"  !CDS_PN = "2";
BODY = "RES","I106": #LOCATION = "R4W4" !CDS_LOCATION = "R4W4" #SEC = "1" !CDS_SEC = "1";
"A":   PN = "1"  !CDS_PN = "1";
"B":   PN = "2"  !CDS_PN = "2";
BODY = "RES","I109": #LOCATION = "R4W6" !CDS_LOCATION = "R4W6" #SEC = "1" !CDS_SEC = "1";
"A":   PN = "1"  !CDS_PN = "1";
"B":   PN = "2"  !CDS_PN = "2";
BODY = "FET_N","I112": #LOCATION = "Q4W2" !CDS_LOCATION = "Q4W2" #SEC = "1" !CDS_SEC = "1";
"DRN":   PN = "3"  !CDS_PN = "3";
"GATE":   PN = "1"  !CDS_PN = "1";
"SRC":   PN = "2"  !CDS_PN = "2";
BODY = "RES","I114": #LOCATION = "R4W5" !CDS_LOCATION = "R4W5" #SEC = "1" !CDS_SEC = "1";
"A":   PN = "1"  !CDS_PN = "1";
"B":   PN = "2"  !CDS_PN = "2";
BODY = "RES","I115": #LOCATION = "R6P48" !CDS_LOCATION = "R6P48" #SEC = "1" !CDS_SEC = "1";
"A":   PN = "1"  !CDS_PN = "1";
"B":   PN = "2"  !CDS_PN = "2";
DRAWING = "@baseboard_fab2_lib.baseboard_fab2(sch_1):page103";
BODY = "RES","I1": #LOCATION = "R4D25" !CDS_LOCATION = "R4D25" #SEC = "1" !CDS_SEC = "1";
"A":   PN = "1"  !CDS_PN = "1";
"B":   PN = "2"  !CDS_PN = "2";
BODY = "RES","I9": #LOCATION = "R4D23" !CDS_LOCATION = "R4D23" #SEC = "1" !CDS_SEC = "1";
"A":   PN = "1"  !CDS_PN = "1";
"B":   PN = "2"  !CDS_PN = "2";
BODY = "RES","I14": #LOCATION = "R4D28" !CDS_LOCATION = "R4D28" #SEC = "1" !CDS_SEC = "1";
"A":   PN = "1"  !CDS_PN = "1";
"B":   PN = "2"  !CDS_PN = "2";
BODY = "RES","I19": #LOCATION = "R4D19" !CDS_LOCATION = "R4D19" #SEC = "1" !CDS_SEC = "1";
"A":   PN = "1"  !CDS_PN = "1";
"B":   PN = "2"  !CDS_PN = "2";
BODY = "RES","I24": #LOCATION = "R4D21" !CDS_LOCATION = "R4D21" #SEC = "1" !CDS_SEC = "1";
"A":   PN = "1"  !CDS_PN = "1";
"B":   PN = "2"  !CDS_PN = "2";
BODY = "RES","I29": #LOCATION = "R4D13" !CDS_LOCATION = "R4D13" #SEC = "1" !CDS_SEC = "1";
"A":   PN = "1"  !CDS_PN = "1";
"B":   PN = "2"  !CDS_PN = "2";
BODY = "RES","I34": #LOCATION = "R4D16" !CDS_LOCATION = "R4D16" #SEC = "1" !CDS_SEC = "1";
"A":   PN = "1"  !CDS_PN = "1";
"B":   PN = "2"  !CDS_PN = "2";
BODY = "RES","I39": #LOCATION = "R4D9" !CDS_LOCATION = "R4D9" #SEC = "1" !CDS_SEC = "1";
"A":   PN = "1"  !CDS_PN = "1";
"B":   PN = "2"  !CDS_PN = "2";
BODY = "RES","I44": #LOCATION = "R4D11" !CDS_LOCATION = "R4D11" #SEC = "1" !CDS_SEC = "1";
"A":   PN = "1"  !CDS_PN = "1";
"B":   PN = "2"  !CDS_PN = "2";
BODY = "RES","I49": #LOCATION = "R4D2" !CDS_LOCATION = "R4D2" &SEC = "1" #&CDS_SEC = "1";
"A":   PN = "1"  !CDS_PN = "1";
"B":   PN = "2"  !CDS_PN = "2";
BODY = "RES","I54": #LOCATION = "R4D1" !CDS_LOCATION = "R4D1" #SEC = "1" !CDS_SEC = "1";
"A":   PN = "1"  !CDS_PN = "1";
"B":   PN = "2"  !CDS_PN = "2";
BODY = "RES","I59": #LOCATION = "R4D4" !CDS_LOCATION = "R4D4" #SEC = "1" !CDS_SEC = "1";
"A":   PN = "1"  !CDS_PN = "1";
"B":   PN = "2"  !CDS_PN = "2";
BODY = "RES","I64": #LOCATION = "R4D3" !CDS_LOCATION = "R4D3" #SEC = "1" !CDS_SEC = "1";
"A":   PN = "1"  !CDS_PN = "1";
"B":   PN = "2"  !CDS_PN = "2";
BODY = "RES","I69": #LOCATION = "R4D29" !CDS_LOCATION = "R4D29" #SEC = "1" !CDS_SEC = "1";
"A":   PN = "1"  !CDS_PN = "1";
"B":   PN = "2"  !CDS_PN = "2";
BODY = "RES","I74": #LOCATION = "R4D6" !CDS_LOCATION = "R4D6" #SEC = "1" !CDS_SEC = "1";
"A":   PN = "1"  !CDS_PN = "1";
"B":   PN = "2"  !CDS_PN = "2";
BODY = "RES","I79": #LOCATION = "R4D5" !CDS_LOCATION = "R4D5" #SEC = "1" !CDS_SEC = "1";
"A":   PN = "1"  !CDS_PN = "1";
"B":   PN = "2"  !CDS_PN = "2";
BODY = "RES","I84": #LOCATION = "R4D8" !CDS_LOCATION = "R4D8" #SEC = "1" !CDS_SEC = "1";
"A":   PN = "1"  !CDS_PN = "1";
"B":   PN = "2"  !CDS_PN = "2";
BODY = "RES","I89": #LOCATION = "R4D7" !CDS_LOCATION = "R4D7" #SEC = "1" !CDS_SEC = "1";
"A":   PN = "1"  !CDS_PN = "1";
"B":   PN = "2"  !CDS_PN = "2";
BODY = "RES","I94": #LOCATION = "R4D12" !CDS_LOCATION = "R4D12" #SEC = "1" !CDS_SEC = "1";
"A":   PN = "1"  !CDS_PN = "1";
"B":   PN = "2"  !CDS_PN = "2";
BODY = "RES","I99": #LOCATION = "R4D10" !CDS_LOCATION = "R4D10" #SEC = "1" !CDS_SEC = "1";
"A":   PN = "1"  !CDS_PN = "1";
"B":   PN = "2"  !CDS_PN = "2";
BODY = "RES","I104": #LOCATION = "R4D17" !CDS_LOCATION = "R4D17" #SEC = "1" !CDS_SEC = "1";
"A":   PN = "1"  !CDS_PN = "1";
"B":   PN = "2"  !CDS_PN = "2";
BODY = "RES","I109": #LOCATION = "R4D14" !CDS_LOCATION = "R4D14" #SEC = "1" !CDS_SEC = "1";
"A":   PN = "1"  !CDS_PN = "1";
"B":   PN = "2"  !CDS_PN = "2";
BODY = "RES","I114": #LOCATION = "R4D22" !CDS_LOCATION = "R4D22" #SEC = "1" !CDS_SEC = "1";
"A":   PN = "1"  !CDS_PN = "1";
"B":   PN = "2"  !CDS_PN = "2";
BODY = "RES","I119": #LOCATION = "R4D20" !CDS_LOCATION = "R4D20" #SEC = "1" !CDS_SEC = "1";
"A":   PN = "1"  !CDS_PN = "1";
"B":   PN = "2"  !CDS_PN = "2";
BODY = "RES","I121": #LOCATION = "R7P9" !CDS_LOCATION = "R7P9" #SEC = "1" !CDS_SEC = "1";
"A":   PN = "1"  !CDS_PN = "1";
"B":   PN = "2"  !CDS_PN = "2";
BODY = "RES","I123": #LOCATION = "R7P12" !CDS_LOCATION = "R7P12" #SEC = "1" !CDS_SEC = "1";
"A":   PN = "1"  !CDS_PN = "1";
"B":   PN = "2"  !CDS_PN = "2";
BODY = "RES","I125": #LOCATION = "R7P6" !CDS_LOCATION = "R7P6" #SEC = "1" !CDS_SEC = "1";
"A":   PN = "1"  !CDS_PN = "1";
"B":   PN = "2"  !CDS_PN = "2";
BODY = "RES","I127": #LOCATION = "R7P7" !CDS_LOCATION = "R7P7" &SEC = "1" #&CDS_SEC = "1";
"A":   PN = "1"  !CDS_PN = "1";
"B":   PN = "2"  !CDS_PN = "2";
BODY = "RES","I129": #LOCATION = "R7P3" !CDS_LOCATION = "R7P3" #SEC = "1" !CDS_SEC = "1";
"A":   PN = "1"  !CDS_PN = "1";
"B":   PN = "2"  !CDS_PN = "2";
BODY = "RES","I131": #LOCATION = "R7P4" !CDS_LOCATION = "R7P4" #SEC = "1" !CDS_SEC = "1";
"A":   PN = "1"  !CDS_PN = "1";
"B":   PN = "2"  !CDS_PN = "2";
BODY = "RES","I133": #LOCATION = "R7P1" !CDS_LOCATION = "R7P1" #SEC = "1" !CDS_SEC = "1";
"A":   PN = "1"  !CDS_PN = "1";
"B":   PN = "2"  !CDS_PN = "2";
BODY = "RES","I135": #LOCATION = "R7P2" !CDS_LOCATION = "R7P2" #SEC = "1" !CDS_SEC = "1";
"A":   PN = "1"  !CDS_PN = "1";
"B":   PN = "2"  !CDS_PN = "2";
BODY = "RES","I137": #LOCATION = "R6P7" !CDS_LOCATION = "R6P7" #SEC = "1" !CDS_SEC = "1";
"A":   PN = "1"  !CDS_PN = "1";
"B":   PN = "2"  !CDS_PN = "2";
BODY = "RES","I139": #LOCATION = "R6P8" !CDS_LOCATION = "R6P8" #SEC = "1" !CDS_SEC = "1";
"A":   PN = "1"  !CDS_PN = "1";
"B":   PN = "2"  !CDS_PN = "2";
BODY = "RES","I141": #LOCATION = "R6P5" !CDS_LOCATION = "R6P5" #SEC = "1" !CDS_SEC = "1";
"A":   PN = "1"  !CDS_PN = "1";
"B":   PN = "2"  !CDS_PN = "2";
BODY = "RES","I143": #LOCATION = "R6P6" !CDS_LOCATION = "R6P6" #SEC = "1" !CDS_SEC = "1";
"A":   PN = "1"  !CDS_PN = "1";
"B":   PN = "2"  !CDS_PN = "2";
BODY = "RES","I145": #LOCATION = "R6P3" !CDS_LOCATION = "R6P3" #SEC = "1" !CDS_SEC = "1";
"A":   PN = "1"  !CDS_PN = "1";
"B":   PN = "2"  !CDS_PN = "2";
BODY = "RES","I147": #LOCATION = "R6P4" !CDS_LOCATION = "R6P4" #SEC = "1" !CDS_SEC = "1";
"A":   PN = "1"  !CDS_PN = "1";
"B":   PN = "2"  !CDS_PN = "2";
BODY = "RES","I149": #LOCATION = "R6P1" !CDS_LOCATION = "R6P1" #SEC = "1" !CDS_SEC = "1";
"A":   PN = "1"  !CDS_PN = "1";
"B":   PN = "2"  !CDS_PN = "2";
BODY = "RES","I151": #LOCATION = "R6P2" !CDS_LOCATION = "R6P2" #SEC = "1" !CDS_SEC = "1";
"A":   PN = "1"  !CDS_PN = "1";
"B":   PN = "2"  !CDS_PN = "2";
BODY = "RES","I153": #LOCATION = "R6P11" !CDS_LOCATION = "R6P11" #SEC = "1" !CDS_SEC = "1";
"A":   PN = "1"  !CDS_PN = "1";
"B":   PN = "2"  !CDS_PN = "2";
BODY = "RES","I155": #LOCATION = "R6P9" !CDS_LOCATION = "R6P9" #SEC = "1" !CDS_SEC = "1";
"A":   PN = "1"  !CDS_PN = "1";
"B":   PN = "2"  !CDS_PN = "2";
BODY = "RES","I157": #LOCATION = "R6P13" !CDS_LOCATION = "R6P13" #SEC = "1" !CDS_SEC = "1";
"A":   PN = "1"  !CDS_PN = "1";
"B":   PN = "2"  !CDS_PN = "2";
BODY = "RES","I159": #LOCATION = "R6P12" !CDS_LOCATION = "R6P12" #SEC = "1" !CDS_SEC = "1";
"A":   PN = "1"  !CDS_PN = "1";
"B":   PN = "2"  !CDS_PN = "2";
BODY = "RES","I161": #LOCATION = "R4D24" !CDS_LOCATION = "R4D24" #SEC = "1" !CDS_SEC = "1";
"A":   PN = "1"  !CDS_PN = "1";
"B":   PN = "2"  !CDS_PN = "2";
BODY = "RES","I163": #LOCATION = "R4D18" !CDS_LOCATION = "R4D18" #SEC = "1" !CDS_SEC = "1";
"A":   PN = "1"  !CDS_PN = "1";
"B":   PN = "2"  !CDS_PN = "2";
BODY = "RES","I165": #LOCATION = "R6P17" !CDS_LOCATION = "R6P17" #SEC = "1" !CDS_SEC = "1";
"A":   PN = "1"  !CDS_PN = "1";
"B":   PN = "2"  !CDS_PN = "2";
BODY = "RES","I167": #LOCATION = "R6P15" !CDS_LOCATION = "R6P15" #SEC = "1" !CDS_SEC = "1";
"A":   PN = "1"  !CDS_PN = "1";
"B":   PN = "2"  !CDS_PN = "2";
DRAWING = "@baseboard_fab2_lib.baseboard_fab2(sch_1):page104";
BODY = "CAP_A","I25": #LOCATION = "C6F1" !CDS_LOCATION = "C6F1" #SEC = "1" !CDS_SEC = "1";
"A":   PN = "1"  !CDS_PN = "1";
"B":   PN = "2"  !CDS_PN = "2";
BODY = "CAP_A","I34": #LOCATION = "C3F2" !CDS_LOCATION = "C3F2" #SEC = "1" !CDS_SEC = "1";
"A":   PN = "1"  !CDS_PN = "1";
"B":   PN = "2"  !CDS_PN = "2";
BODY = "RES","I37": #LOCATION = "R6F8" !CDS_LOCATION = "R6F8" #SEC = "1" !CDS_SEC = "1";
"A":   PN = "1"  !CDS_PN = "1";
"B":   PN = "2"  !CDS_PN = "2";
BODY = "RES","I41": #LOCATION = "R6F6" !CDS_LOCATION = "R6F6" #SEC = "1" !CDS_SEC = "1";
"A":   PN = "1"  !CDS_PN = "1";
"B":   PN = "2"  !CDS_PN = "2";
BODY = "RES","I51": #LOCATION = "R3F1" !CDS_LOCATION = "R3F1" #SEC = "1" !CDS_SEC = "1";
"A":   PN = "1"  !CDS_PN = "1";
"B":   PN = "2"  !CDS_PN = "2";
BODY = "RES","I53": #LOCATION = "R3F3" !CDS_LOCATION = "R3F3" #SEC = "1" !CDS_SEC = "1";
"A":   PN = "1"  !CDS_PN = "1";
"B":   PN = "2"  !CDS_PN = "2";
BODY = "RES","I67": #LOCATION = "R6F7" !CDS_LOCATION = "R6F7" #SEC = "1" !CDS_SEC = "1";
"A":   PN = "1"  !CDS_PN = "1";
"B":   PN = "2"  !CDS_PN = "2";
BODY = "RES","I68": #LOCATION = "R6F9" !CDS_LOCATION = "R6F9" #SEC = "1" !CDS_SEC = "1";
"A":   PN = "1"  !CDS_PN = "1";
"B":   PN = "2"  !CDS_PN = "2";
BODY = "RES","I69": #LOCATION = "R3F2" !CDS_LOCATION = "R3F2" #SEC = "1" !CDS_SEC = "1";
"A":   PN = "1"  !CDS_PN = "1";
"B":   PN = "2"  !CDS_PN = "2";
BODY = "RES","I70": #LOCATION = "R3F4" !CDS_LOCATION = "R3F4" #SEC = "1" !CDS_SEC = "1";
"A":   PN = "1"  !CDS_PN = "1";
"B":   PN = "2"  !CDS_PN = "2";
BODY = "OSC_C","I71": #LOCATION = "Y6F1" !CDS_LOCATION = "Y6F1" #SEC = "1" !CDS_SEC = "1";
"ENABLE_DISABLE":   PN = "1"  !CDS_PN = "1";
"GND":   PN = "3"  !CDS_PN = "3";
"NC_GND":   PN = "2"  !CDS_PN = "2";
"OUT":   PN = "4"  !CDS_PN = "4";
"OUT_N":   PN = "5"  !CDS_PN = "5";
"VCC":   PN = "6"  !CDS_PN = "6";
BODY = "OSC_C","I72": #LOCATION = "Y3F1" !CDS_LOCATION = "Y3F1" #SEC = "1" !CDS_SEC = "1";
"ENABLE_DISABLE":   PN = "1"  !CDS_PN = "1";
"GND":   PN = "3"  !CDS_PN = "3";
"NC_GND":   PN = "2"  !CDS_PN = "2";
"OUT":   PN = "4"  !CDS_PN = "4";
"OUT_N":   PN = "5"  !CDS_PN = "5";
"VCC":   PN = "6"  !CDS_PN = "6";
BODY = "RES","I78": #LOCATION = "R6F10" !CDS_LOCATION = "R6F10" #SEC = "1" !CDS_SEC = "1";
"A":   PN = "1"  !CDS_PN = "1";
"B":   PN = "2"  !CDS_PN = "2";
BODY = "RES","I79": #LOCATION = "R6F11" !CDS_LOCATION = "R6F11" #SEC = "1" !CDS_SEC = "1";
"A":   PN = "1"  !CDS_PN = "1";
"B":   PN = "2"  !CDS_PN = "2";
BODY = "RES","I84": #LOCATION = "R3F5" !CDS_LOCATION = "R3F5" #SEC = "1" !CDS_SEC = "1";
"A":   PN = "1"  !CDS_PN = "1";
"B":   PN = "2"  !CDS_PN = "2";
BODY = "RES","I88": #LOCATION = "R3F6" !CDS_LOCATION = "R3F6" #SEC = "1" !CDS_SEC = "1";
"A":   PN = "1"  !CDS_PN = "1";
"B":   PN = "2"  !CDS_PN = "2";
BODY = "RES","I93": #LOCATION = "R8D43" !CDS_LOCATION = "R8D43" #SEC = "1" !CDS_SEC = "1";
"A":   PN = "1"  !CDS_PN = "1";
"B":   PN = "2"  !CDS_PN = "2";
BODY = "RES","I94": #LOCATION = "R7D40" !CDS_LOCATION = "R7D40" #SEC = "1" !CDS_SEC = "1";
"A":   PN = "1"  !CDS_PN = "1";
"B":   PN = "2"  !CDS_PN = "2";
BODY = "RES","I96": #LOCATION = "R7D36" !CDS_LOCATION = "R7D36" #SEC = "1" !CDS_SEC = "1";
"A":   PN = "1"  !CDS_PN = "1";
"B":   PN = "2"  !CDS_PN = "2";
BODY = "RES","I97": #LOCATION = "R7D38" !CDS_LOCATION = "R7D38" #SEC = "1" !CDS_SEC = "1";
"A":   PN = "1"  !CDS_PN = "1";
"B":   PN = "2"  !CDS_PN = "2";
BODY = "RES","I103": #LOCATION = "R7D39" !CDS_LOCATION = "R7D39" #SEC = "1" !CDS_SEC = "1";
"A":   PN = "1"  !CDS_PN = "1";
"B":   PN = "2"  !CDS_PN = "2";
BODY = "RES","I104": #LOCATION = "R7D37" !CDS_LOCATION = "R7D37" #SEC = "1" !CDS_SEC = "1";
"A":   PN = "1"  !CDS_PN = "1";
"B":   PN = "2"  !CDS_PN = "2";
DRAWING = "@baseboard_fab2_lib.baseboard_fab2(sch_1):page105";
BODY = "CAP","I1": #LOCATION = "C7G24" !CDS_LOCATION = "C7G24" #SEC = "1" !CDS_SEC = "1";
"A":   PN = "1"  !CDS_PN = "1";
"B":   PN = "2"  !CDS_PN = "2";
BODY = "CAP","I6": #LOCATION = "C7G6" !CDS_LOCATION = "C7G6" &SEC = "1" #&CDS_SEC = "1";
"A":   PN = "1"  !CDS_PN = "1";
"B":   PN = "2"  !CDS_PN = "2";
BODY = "CAP","I7": #LOCATION = "C7G7" !CDS_LOCATION = "C7G7" #SEC = "1" !CDS_SEC = "1";
"A":   PN = "1"  !CDS_PN = "1";
"B":   PN = "2"  !CDS_PN = "2";
BODY = "CAP","I8": #LOCATION = "C7G10" !CDS_LOCATION = "C7G10" #SEC = "1" !CDS_SEC = "1";
"A":   PN = "1"  !CDS_PN = "1";
"B":   PN = "2"  !CDS_PN = "2";
BODY = "CAP","I12": #LOCATION = "C7G12" !CDS_LOCATION = "C7G12" #SEC = "1" !CDS_SEC = "1";
"A":   PN = "1"  !CDS_PN = "1";
"B":   PN = "2"  !CDS_PN = "2";
BODY = "CAP","I13": #LOCATION = "C7G13" !CDS_LOCATION = "C7G13" #SEC = "1" !CDS_SEC = "1";
"A":   PN = "1"  !CDS_PN = "1";
"B":   PN = "2"  !CDS_PN = "2";
BODY = "CAP","I20": #LOCATION = "C7G5" !CDS_LOCATION = "C7G5" #SEC = "1" !CDS_SEC = "1";
"A":   PN = "1"  !CDS_PN = "1";
"B":   PN = "2"  !CDS_PN = "2";
BODY = "CAP","I21": #LOCATION = "C7G9" !CDS_LOCATION = "C7G9" #SEC = "1" !CDS_SEC = "1";
"A":   PN = "1"  !CDS_PN = "1";
"B":   PN = "2"  !CDS_PN = "2";
BODY = "CAP","I22": #LOCATION = "C7G8" !CDS_LOCATION = "C7G8" #SEC = "1" !CDS_SEC = "1";
"A":   PN = "1"  !CDS_PN = "1";
"B":   PN = "2"  !CDS_PN = "2";
BODY = "CAP","I27": #LOCATION = "C7G11" !CDS_LOCATION = "C7G11" #SEC = "1" !CDS_SEC = "1";
"A":   PN = "1"  !CDS_PN = "1";
"B":   PN = "2"  !CDS_PN = "2";
BODY = "CAP","I28": #LOCATION = "C7G14" !CDS_LOCATION = "C7G14" #SEC = "1" !CDS_SEC = "1";
"A":   PN = "1"  !CDS_PN = "1";
"B":   PN = "2"  !CDS_PN = "2";
BODY = "CAP","I31": #LOCATION = "C7G16" !CDS_LOCATION = "C7G16" #SEC = "1" !CDS_SEC = "1";
"A":   PN = "1"  !CDS_PN = "1";
"B":   PN = "2"  !CDS_PN = "2";
BODY = "CAP","I32": #LOCATION = "C7G18" !CDS_LOCATION = "C7G18" #SEC = "1" !CDS_SEC = "1";
"A":   PN = "1"  !CDS_PN = "1";
"B":   PN = "2"  !CDS_PN = "2";
BODY = "CAP","I37": #LOCATION = "C7G22" !CDS_LOCATION = "C7G22" #SEC = "1" !CDS_SEC = "1";
"A":   PN = "1"  !CDS_PN = "1";
"B":   PN = "2"  !CDS_PN = "2";
BODY = "CAP","I44": #LOCATION = "C7G17" !CDS_LOCATION = "C7G17" #SEC = "1" !CDS_SEC = "1";
"A":   PN = "1"  !CDS_PN = "1";
"B":   PN = "2"  !CDS_PN = "2";
BODY = "CAP","I45": #LOCATION = "C7G15" !CDS_LOCATION = "C7G15" #SEC = "1" !CDS_SEC = "1";
"A":   PN = "1"  !CDS_PN = "1";
"B":   PN = "2"  !CDS_PN = "2";
BODY = "CAP","I51": #LOCATION = "C7G21" !CDS_LOCATION = "C7G21" #SEC = "1" !CDS_SEC = "1";
"A":   PN = "1"  !CDS_PN = "1";
"B":   PN = "2"  !CDS_PN = "2";
BODY = "CAP","I52": #LOCATION = "C7G23" !CDS_LOCATION = "C7G23" #SEC = "1" !CDS_SEC = "1";
"A":   PN = "1"  !CDS_PN = "1";
"B":   PN = "2"  !CDS_PN = "2";
BODY = "CAP","I55": #LOCATION = "C7G26" !CDS_LOCATION = "C7G26" #SEC = "1" !CDS_SEC = "1";
"A":   PN = "1"  !CDS_PN = "1";
"B":   PN = "2"  !CDS_PN = "2";
BODY = "CAP","I56": #LOCATION = "C8G4" !CDS_LOCATION = "C8G4" #SEC = "1" !CDS_SEC = "1";
"A":   PN = "1"  !CDS_PN = "1";
"B":   PN = "2"  !CDS_PN = "2";
BODY = "CAP","I58": #LOCATION = "C8G2" !CDS_LOCATION = "C8G2" #SEC = "1" !CDS_SEC = "1";
"A":   PN = "1"  !CDS_PN = "1";
"B":   PN = "2"  !CDS_PN = "2";
BODY = "CAP","I61": #LOCATION = "C8G6" !CDS_LOCATION = "C8G6" #SEC = "1" !CDS_SEC = "1";
"A":   PN = "1"  !CDS_PN = "1";
"B":   PN = "2"  !CDS_PN = "2";
BODY = "CAP","I62": #LOCATION = "C8G7" !CDS_LOCATION = "C8G7" #SEC = "1" !CDS_SEC = "1";
"A":   PN = "1"  !CDS_PN = "1";
"B":   PN = "2"  !CDS_PN = "2";
BODY = "CAP","I69": #LOCATION = "C7G25" !CDS_LOCATION = "C7G25" #SEC = "1" !CDS_SEC = "1";
"A":   PN = "1"  !CDS_PN = "1";
"B":   PN = "2"  !CDS_PN = "2";
BODY = "CAP","I70": #LOCATION = "C8G1" !CDS_LOCATION = "C8G1" #SEC = "1" !CDS_SEC = "1";
"A":   PN = "1"  !CDS_PN = "1";
"B":   PN = "2"  !CDS_PN = "2";
BODY = "CAP","I71": #LOCATION = "C8G3" !CDS_LOCATION = "C8G3" #SEC = "1" !CDS_SEC = "1";
"A":   PN = "1"  !CDS_PN = "1";
"B":   PN = "2"  !CDS_PN = "2";
BODY = "CAP","I75": #LOCATION = "C8G5" !CDS_LOCATION = "C8G5" #SEC = "1" !CDS_SEC = "1";
"A":   PN = "1"  !CDS_PN = "1";
"B":   PN = "2"  !CDS_PN = "2";
BODY = "CAP","I76": #LOCATION = "C8G8" !CDS_LOCATION = "C8G8" #SEC = "1" !CDS_SEC = "1";
"A":   PN = "1"  !CDS_PN = "1";
"B":   PN = "2"  !CDS_PN = "2";
BODY = "CAP","I93": #LOCATION = "C8G9" !CDS_LOCATION = "C8G9" #SEC = "1" !CDS_SEC = "1";
"A":   PN = "1"  !CDS_PN = "1";
"B":   PN = "2"  !CDS_PN = "2";
BODY = "CAP","I96": #LOCATION = "C8G10" !CDS_LOCATION = "C8G10" #SEC = "1" !CDS_SEC = "1";
"A":   PN = "1"  !CDS_PN = "1";
"B":   PN = "2"  !CDS_PN = "2";
BODY = "CAP","I153": #LOCATION = "C6B18" !CDS_LOCATION = "C6B18" #SEC = "1" !CDS_SEC = "1";
"A":   PN = "1"  !CDS_PN = "1";
"B":   PN = "2"  !CDS_PN = "2";
BODY = "CAP","I160": #LOCATION = "C6B19" !CDS_LOCATION = "C6B19" #SEC = "1" !CDS_SEC = "1";
"A":   PN = "1"  !CDS_PN = "1";
"B":   PN = "2"  !CDS_PN = "2";
BODY = "CAP","I163": #LOCATION = "C6B15" !CDS_LOCATION = "C6B15" #SEC = "1" !CDS_SEC = "1";
"A":   PN = "1"  !CDS_PN = "1";
"B":   PN = "2"  !CDS_PN = "2";
BODY = "CAP","I166": #LOCATION = "C6B11" !CDS_LOCATION = "C6B11" #SEC = "1" !CDS_SEC = "1";
"A":   PN = "1"  !CDS_PN = "1";
"B":   PN = "2"  !CDS_PN = "2";
BODY = "CAP","I169": #LOCATION = "C6B6" !CDS_LOCATION = "C6B6" #SEC = "1" !CDS_SEC = "1";
"A":   PN = "1"  !CDS_PN = "1";
"B":   PN = "2"  !CDS_PN = "2";
BODY = "CAP","I173": #LOCATION = "C6B20" !CDS_LOCATION = "C6B20" #SEC = "1" !CDS_SEC = "1";
"A":   PN = "1"  !CDS_PN = "1";
"B":   PN = "2"  !CDS_PN = "2";
BODY = "CAP","I175": #LOCATION = "C6B17" !CDS_LOCATION = "C6B17" #SEC = "1" !CDS_SEC = "1";
"A":   PN = "1"  !CDS_PN = "1";
"B":   PN = "2"  !CDS_PN = "2";
BODY = "CAP","I180": #LOCATION = "C6B16" !CDS_LOCATION = "C6B16" #SEC = "1" !CDS_SEC = "1";
"A":   PN = "1"  !CDS_PN = "1";
"B":   PN = "2"  !CDS_PN = "2";
BODY = "CAP","I181": #LOCATION = "C6B14" !CDS_LOCATION = "C6B14" #SEC = "1" !CDS_SEC = "1";
"A":   PN = "1"  !CDS_PN = "1";
"B":   PN = "2"  !CDS_PN = "2";
BODY = "CAP","I185": #LOCATION = "C6B9" !CDS_LOCATION = "C6B9" #SEC = "1" !CDS_SEC = "1";
"A":   PN = "1"  !CDS_PN = "1";
"B":   PN = "2"  !CDS_PN = "2";
BODY = "CAP","I187": #LOCATION = "C6B12" !CDS_LOCATION = "C6B12" #SEC = "1" !CDS_SEC = "1";
"A":   PN = "1"  !CDS_PN = "1";
"B":   PN = "2"  !CDS_PN = "2";
BODY = "CAP","I189": #LOCATION = "C6B13" !CDS_LOCATION = "C6B13" #SEC = "1" !CDS_SEC = "1";
"A":   PN = "1"  !CDS_PN = "1";
"B":   PN = "2"  !CDS_PN = "2";
BODY = "CAP","I193": #LOCATION = "C6B10" !CDS_LOCATION = "C6B10" #SEC = "1" !CDS_SEC = "1";
"A":   PN = "1"  !CDS_PN = "1";
"B":   PN = "2"  !CDS_PN = "2";
BODY = "CAP","I196": #LOCATION = "C6B4" !CDS_LOCATION = "C6B4" #SEC = "1" !CDS_SEC = "1";
"A":   PN = "1"  !CDS_PN = "1";
"B":   PN = "2"  !CDS_PN = "2";
BODY = "CAP","I198": #LOCATION = "C6B8" !CDS_LOCATION = "C6B8" #SEC = "1" !CDS_SEC = "1";
"A":   PN = "1"  !CDS_PN = "1";
"B":   PN = "2"  !CDS_PN = "2";
BODY = "CAP","I201": #LOCATION = "C6B5" !CDS_LOCATION = "C6B5" #SEC = "1" !CDS_SEC = "1";
"A":   PN = "1"  !CDS_PN = "1";
"B":   PN = "2"  !CDS_PN = "2";
BODY = "CAP","I205": #LOCATION = "C3M25" !CDS_LOCATION = "C3M25" &SEC = "1" #&CDS_SEC = "1";
"A":   PN = "1"  !CDS_PN = "1";
"B":   PN = "2"  !CDS_PN = "2";
BODY = "CAP","I206": #LOCATION = "C3M34" !CDS_LOCATION = "C3M34" &SEC = "1" #&CDS_SEC = "1";
"A":   PN = "1"  !CDS_PN = "1";
"B":   PN = "2"  !CDS_PN = "2";
BODY = "CAP","I212": #LOCATION = "C3M28" !CDS_LOCATION = "C3M28" &SEC = "1" #&CDS_SEC = "1";
"A":   PN = "1"  !CDS_PN = "1";
"B":   PN = "2"  !CDS_PN = "2";
BODY = "CAP","I217": #LOCATION = "C3M33" !CDS_LOCATION = "C3M33" &SEC = "1" #&CDS_SEC = "1";
"A":   PN = "1"  !CDS_PN = "1";
"B":   PN = "2"  !CDS_PN = "2";
BODY = "CAP","I218": #LOCATION = "C3M36" !CDS_LOCATION = "C3M36" &SEC = "1" #&CDS_SEC = "1";
"A":   PN = "1"  !CDS_PN = "1";
"B":   PN = "2"  !CDS_PN = "2";
BODY = "CAP","I223": #LOCATION = "C3M32" !CDS_LOCATION = "C3M32" &SEC = "1" #&CDS_SEC = "1";
"A":   PN = "1"  !CDS_PN = "1";
"B":   PN = "2"  !CDS_PN = "2";
BODY = "CAP","I225": #LOCATION = "C3M35" !CDS_LOCATION = "C3M35" &SEC = "1" #&CDS_SEC = "1";
"A":   PN = "1"  !CDS_PN = "1";
"B":   PN = "2"  !CDS_PN = "2";
BODY = "CAP","I229": #LOCATION = "C3M26" !CDS_LOCATION = "C3M26" &SEC = "1" #&CDS_SEC = "1";
"A":   PN = "1"  !CDS_PN = "1";
"B":   PN = "2"  !CDS_PN = "2";
BODY = "CAP","I232": #LOCATION = "C3M3" !CDS_LOCATION = "C3M3" &SEC = "1" #&CDS_SEC = "1";
"A":   PN = "1"  !CDS_PN = "1";
"B":   PN = "2"  !CDS_PN = "2";
BODY = "CAP","I234": #LOCATION = "C3M11" !CDS_LOCATION = "C3M11" &SEC = "1" #&CDS_SEC = "1";
"A":   PN = "1"  !CDS_PN = "1";
"B":   PN = "2"  !CDS_PN = "2";
BODY = "CAP","I239": #LOCATION = "C3M13" !CDS_LOCATION = "C3M13" &SEC = "1" #&CDS_SEC = "1";
"A":   PN = "1"  !CDS_PN = "1";
"B":   PN = "2"  !CDS_PN = "2";
BODY = "CAP","I244": #LOCATION = "C3M4" !CDS_LOCATION = "C3M4" &SEC = "1" #&CDS_SEC = "1";
"A":   PN = "1"  !CDS_PN = "1";
"B":   PN = "2"  !CDS_PN = "2";
BODY = "CAP","I246": #LOCATION = "C3M12" !CDS_LOCATION = "C3M12" &SEC = "1" #&CDS_SEC = "1";
"A":   PN = "1"  !CDS_PN = "1";
"B":   PN = "2"  !CDS_PN = "2";
BODY = "CAP","I247": #LOCATION = "C3M2" !CDS_LOCATION = "C3M2" &SEC = "1" #&CDS_SEC = "1";
"A":   PN = "1"  !CDS_PN = "1";
"B":   PN = "2"  !CDS_PN = "2";
BODY = "CAP","I253": #LOCATION = "C3M14" !CDS_LOCATION = "C3M14" &SEC = "1" #&CDS_SEC = "1";
"A":   PN = "1"  !CDS_PN = "1";
"B":   PN = "2"  !CDS_PN = "2";
BODY = "CAP","I255": #LOCATION = "C3M1" !CDS_LOCATION = "C3M1" &SEC = "1" #&CDS_SEC = "1";
"A":   PN = "1"  !CDS_PN = "1";
"B":   PN = "2"  !CDS_PN = "2";
BODY = "CAP","I257": #LOCATION = "C7G19" !CDS_LOCATION = "C7G19" #SEC = "1" !CDS_SEC = "1";
"A":   PN = "1"  !CDS_PN = "1";
"B":   PN = "2"  !CDS_PN = "2";
BODY = "CAP","I258": #LOCATION = "C7G20" !CDS_LOCATION = "C7G20" #SEC = "1" !CDS_SEC = "1";
"A":   PN = "1"  !CDS_PN = "1";
"B":   PN = "2"  !CDS_PN = "2";
DRAWING = "@baseboard_fab2_lib.baseboard_fab2(sch_1):page106";
BODY = "CAP","I10": #LOCATION = "C1R2" !CDS_LOCATION = "C1R2" &SEC = "1" #&CDS_SEC = "1";
"A":   PN = "1"  !CDS_PN = "1";
"B":   PN = "2"  !CDS_PN = "2";
BODY = "CAP","I26": #LOCATION = "C1R4" !CDS_LOCATION = "C1R4" &SEC = "1" #&CDS_SEC = "1";
"A":   PN = "1"  !CDS_PN = "1";
"B":   PN = "2"  !CDS_PN = "2";
BODY = "CAP","I29": #LOCATION = "C1R1" !CDS_LOCATION = "C1R1" &SEC = "1" #&CDS_SEC = "1";
"A":   PN = "1"  !CDS_PN = "1";
"B":   PN = "2"  !CDS_PN = "2";
BODY = "CAP","I37": #LOCATION = "C1R3" !CDS_LOCATION = "C1R3" &SEC = "1" #&CDS_SEC = "1";
"A":   PN = "1"  !CDS_PN = "1";
"B":   PN = "2"  !CDS_PN = "2";
BODY = "CAP","I40": #LOCATION = "C1R6" !CDS_LOCATION = "C1R6" &SEC = "1" #&CDS_SEC = "1";
"A":   PN = "1"  !CDS_PN = "1";
"B":   PN = "2"  !CDS_PN = "2";
BODY = "CAP","I55": #LOCATION = "C1R8" !CDS_LOCATION = "C1R8" &SEC = "1" #&CDS_SEC = "1";
"A":   PN = "1"  !CDS_PN = "1";
"B":   PN = "2"  !CDS_PN = "2";
BODY = "CAP","I59": #LOCATION = "C1R5" !CDS_LOCATION = "C1R5" &SEC = "1" #&CDS_SEC = "1";
"A":   PN = "1"  !CDS_PN = "1";
"B":   PN = "2"  !CDS_PN = "2";
BODY = "CAP","I70": #LOCATION = "C1R7" !CDS_LOCATION = "C1R7" &SEC = "1" #&CDS_SEC = "1";
"A":   PN = "1"  !CDS_PN = "1";
"B":   PN = "2"  !CDS_PN = "2";
BODY = "CAP","I76": #LOCATION = "C2M14" !CDS_LOCATION = "C2M14" &SEC = "1" #&CDS_SEC = "1";
"A":   PN = "1"  !CDS_PN = "1";
"B":   PN = "2"  !CDS_PN = "2";
BODY = "CAP","I78": #LOCATION = "C1M18" !CDS_LOCATION = "C1M18" &SEC = "1" #&CDS_SEC = "1";
"A":   PN = "1"  !CDS_PN = "1";
"B":   PN = "2"  !CDS_PN = "2";
BODY = "CAP","I82": #LOCATION = "C1M16" !CDS_LOCATION = "C1M16" &SEC = "1" #&CDS_SEC = "1";
"A":   PN = "1"  !CDS_PN = "1";
"B":   PN = "2"  !CDS_PN = "2";
BODY = "CAP","I85": #LOCATION = "C1M14" !CDS_LOCATION = "C1M14" &SEC = "1" #&CDS_SEC = "1";
"A":   PN = "1"  !CDS_PN = "1";
"B":   PN = "2"  !CDS_PN = "2";
BODY = "CAP","I86": #LOCATION = "C2M15" !CDS_LOCATION = "C2M15" &SEC = "1" #&CDS_SEC = "1";
"A":   PN = "1"  !CDS_PN = "1";
"B":   PN = "2"  !CDS_PN = "2";
BODY = "CAP","I90": #LOCATION = "C1M19" !CDS_LOCATION = "C1M19" &SEC = "1" #&CDS_SEC = "1";
"A":   PN = "1"  !CDS_PN = "1";
"B":   PN = "2"  !CDS_PN = "2";
BODY = "CAP","I92": #LOCATION = "C1M17" !CDS_LOCATION = "C1M17" &SEC = "1" #&CDS_SEC = "1";
"A":   PN = "1"  !CDS_PN = "1";
"B":   PN = "2"  !CDS_PN = "2";
BODY = "CAP","I95": #LOCATION = "C1M15" !CDS_LOCATION = "C1M15" &SEC = "1" #&CDS_SEC = "1";
"A":   PN = "1"  !CDS_PN = "1";
"B":   PN = "2"  !CDS_PN = "2";
BODY = "CAP","I100": #LOCATION = "C1M12" !CDS_LOCATION = "C1M12" &SEC = "1" #&CDS_SEC = "1";
"A":   PN = "1"  !CDS_PN = "1";
"B":   PN = "2"  !CDS_PN = "2";
BODY = "CAP","I102": #LOCATION = "C1M10" !CDS_LOCATION = "C1M10" &SEC = "1" #&CDS_SEC = "1";
"A":   PN = "1"  !CDS_PN = "1";
"B":   PN = "2"  !CDS_PN = "2";
BODY = "CAP","I105": #LOCATION = "C1M8" !CDS_LOCATION = "C1M8" &SEC = "1" #&CDS_SEC = "1";
"A":   PN = "1"  !CDS_PN = "1";
"B":   PN = "2"  !CDS_PN = "2";
BODY = "CAP","I109": #LOCATION = "C1M6" !CDS_LOCATION = "C1M6" &SEC = "1" #&CDS_SEC = "1";
"A":   PN = "1"  !CDS_PN = "1";
"B":   PN = "2"  !CDS_PN = "2";
BODY = "CAP","I111": #LOCATION = "C1M13" !CDS_LOCATION = "C1M13" &SEC = "1" #&CDS_SEC = "1";
"A":   PN = "1"  !CDS_PN = "1";
"B":   PN = "2"  !CDS_PN = "2";
BODY = "CAP","I114": #LOCATION = "C1M9" !CDS_LOCATION = "C1M9" &SEC = "1" #&CDS_SEC = "1";
"A":   PN = "1"  !CDS_PN = "1";
"B":   PN = "2"  !CDS_PN = "2";
BODY = "CAP","I117": #LOCATION = "C1M11" !CDS_LOCATION = "C1M11" &SEC = "1" #&CDS_SEC = "1";
"A":   PN = "1"  !CDS_PN = "1";
"B":   PN = "2"  !CDS_PN = "2";
BODY = "CAP","I122": #LOCATION = "C1M7" !CDS_LOCATION = "C1M7" &SEC = "1" #&CDS_SEC = "1";
"A":   PN = "1"  !CDS_PN = "1";
"B":   PN = "2"  !CDS_PN = "2";
BODY = "CAP","I123": #LOCATION = "C2R7" !CDS_LOCATION = "C2R7" &SEC = "1" #&CDS_SEC = "1";
"A":   PN = "1"  !CDS_PN = "1";
"B":   PN = "2"  !CDS_PN = "2";
BODY = "CAP","I128": #LOCATION = "C1R10" !CDS_LOCATION = "C1R10" &SEC = "1" #&CDS_SEC = "1";
"A":   PN = "1"  !CDS_PN = "1";
"B":   PN = "2"  !CDS_PN = "2";
BODY = "CAP","I130": #LOCATION = "C2R14" !CDS_LOCATION = "C2R14" &SEC = "1" #&CDS_SEC = "1";
"A":   PN = "1"  !CDS_PN = "1";
"B":   PN = "2"  !CDS_PN = "2";
BODY = "CAP","I134": #LOCATION = "C1R9" !CDS_LOCATION = "C1R9" &SEC = "1" #&CDS_SEC = "1";
"A":   PN = "1"  !CDS_PN = "1";
"B":   PN = "2"  !CDS_PN = "2";
BODY = "CAP","I137": #LOCATION = "C2R13" !CDS_LOCATION = "C2R13" &SEC = "1" #&CDS_SEC = "1";
"A":   PN = "1"  !CDS_PN = "1";
"B":   PN = "2"  !CDS_PN = "2";
BODY = "CAP","I141": #LOCATION = "C2R8" !CDS_LOCATION = "C2R8" &SEC = "1" #&CDS_SEC = "1";
"A":   PN = "1"  !CDS_PN = "1";
"B":   PN = "2"  !CDS_PN = "2";
BODY = "CAP","I142": #LOCATION = "C2R10" !CDS_LOCATION = "C2R10" &SEC = "1" #&CDS_SEC = "1";
"A":   PN = "1"  !CDS_PN = "1";
"B":   PN = "2"  !CDS_PN = "2";
BODY = "CAP","I147": #LOCATION = "C2R9" !CDS_LOCATION = "C2R9" &SEC = "1" #&CDS_SEC = "1";
"A":   PN = "1"  !CDS_PN = "1";
"B":   PN = "2"  !CDS_PN = "2";
DRAWING = "@baseboard_fab2_lib.baseboard_fab2(sch_1):page107";
BODY = "CAP","I207": #LOCATION = "C3P13" !CDS_LOCATION = "C3P13" &SEC = "1" #&CDS_SEC = "1";
"A":   PN = "1"  !CDS_PN = "1";
"B":   PN = "2"  !CDS_PN = "2";
BODY = "CAP","I208": #LOCATION = "C3P17" !CDS_LOCATION = "C3P17" &SEC = "1" #&CDS_SEC = "1";
"A":   PN = "1"  !CDS_PN = "1";
"B":   PN = "2"  !CDS_PN = "2";
BODY = "CAP","I212": #LOCATION = "C3P11" !CDS_LOCATION = "C3P11" &SEC = "1" #&CDS_SEC = "1";
"A":   PN = "1"  !CDS_PN = "1";
"B":   PN = "2"  !CDS_PN = "2";
BODY = "CAP","I215": #LOCATION = "C3P20" !CDS_LOCATION = "C3P20" &SEC = "1" #&CDS_SEC = "1";
"A":   PN = "1"  !CDS_PN = "1";
"B":   PN = "2"  !CDS_PN = "2";
BODY = "CAP","I216": #LOCATION = "C3P25" !CDS_LOCATION = "C3P25" &SEC = "1" #&CDS_SEC = "1";
"A":   PN = "1"  !CDS_PN = "1";
"B":   PN = "2"  !CDS_PN = "2";
BODY = "CAP","I219": #LOCATION = "C3P18" !CDS_LOCATION = "C3P18" &SEC = "1" #&CDS_SEC = "1";
"A":   PN = "1"  !CDS_PN = "1";
"B":   PN = "2"  !CDS_PN = "2";
BODY = "CAP","I223": #LOCATION = "C3P27" !CDS_LOCATION = "C3P27" &SEC = "1" #&CDS_SEC = "1";
"A":   PN = "1"  !CDS_PN = "1";
"B":   PN = "2"  !CDS_PN = "2";
BODY = "CAP","I226": #LOCATION = "C3P15" !CDS_LOCATION = "C3P15" &SEC = "1" #&CDS_SEC = "1";
"A":   PN = "1"  !CDS_PN = "1";
"B":   PN = "2"  !CDS_PN = "2";
BODY = "CAP","I229": #LOCATION = "C3P23" !CDS_LOCATION = "C3P23" &SEC = "1" #&CDS_SEC = "1";
"A":   PN = "1"  !CDS_PN = "1";
"B":   PN = "2"  !CDS_PN = "2";
BODY = "CAP","I232": #LOCATION = "C3P28" !CDS_LOCATION = "C3P28" &SEC = "1" #&CDS_SEC = "1";
"A":   PN = "1"  !CDS_PN = "1";
"B":   PN = "2"  !CDS_PN = "2";
BODY = "CAP","I234": #LOCATION = "C3P32" !CDS_LOCATION = "C3P32" &SEC = "1" #&CDS_SEC = "1";
"A":   PN = "1"  !CDS_PN = "1";
"B":   PN = "2"  !CDS_PN = "2";
BODY = "CAP","I235": #LOCATION = "C3P37" !CDS_LOCATION = "C3P37" &SEC = "1" #&CDS_SEC = "1";
"A":   PN = "1"  !CDS_PN = "1";
"B":   PN = "2"  !CDS_PN = "2";
BODY = "CAP","I240": #LOCATION = "C3P35" !CDS_LOCATION = "C3P35" &SEC = "1" #&CDS_SEC = "1";
"A":   PN = "1"  !CDS_PN = "1";
"B":   PN = "2"  !CDS_PN = "2";
BODY = "CAP","I241": #LOCATION = "C3P40" !CDS_LOCATION = "C3P40" &SEC = "1" #&CDS_SEC = "1";
"A":   PN = "1"  !CDS_PN = "1";
"B":   PN = "2"  !CDS_PN = "2";
BODY = "CAP","I245": #LOCATION = "C3P30" !CDS_LOCATION = "C3P30" &SEC = "1" #&CDS_SEC = "1";
"A":   PN = "1"  !CDS_PN = "1";
"B":   PN = "2"  !CDS_PN = "2";
BODY = "CAP","I248": #LOCATION = "C3P39" !CDS_LOCATION = "C3P39" &SEC = "1" #&CDS_SEC = "1";
"A":   PN = "1"  !CDS_PN = "1";
"B":   PN = "2"  !CDS_PN = "2";
BODY = "CAP","I257": #LOCATION = "C2U4" !CDS_LOCATION = "C2U4" #SEC = "1" !CDS_SEC = "1";
"A":   PN = "1"  !CDS_PN = "1";
"B":   PN = "2"  !CDS_PN = "2";
BODY = "CAP","I260": #LOCATION = "C2U6" !CDS_LOCATION = "C2U6" #SEC = "1" !CDS_SEC = "1";
"A":   PN = "1"  !CDS_PN = "1";
"B":   PN = "2"  !CDS_PN = "2";
BODY = "CAP","I264": #LOCATION = "C2U8" !CDS_LOCATION = "C2U8" #SEC = "1" !CDS_SEC = "1";
"A":   PN = "1"  !CDS_PN = "1";
"B":   PN = "2"  !CDS_PN = "2";
BODY = "CAP","I265": #LOCATION = "C2U12" !CDS_LOCATION = "C2U12" #SEC = "1" !CDS_SEC = "1";
"A":   PN = "1"  !CDS_PN = "1";
"B":   PN = "2"  !CDS_PN = "2";
BODY = "CAP","I267": #LOCATION = "C2U10" !CDS_LOCATION = "C2U10" #SEC = "1" !CDS_SEC = "1";
"A":   PN = "1"  !CDS_PN = "1";
"B":   PN = "2"  !CDS_PN = "2";
BODY = "CAP","I272": #LOCATION = "C2U3" !CDS_LOCATION = "C2U3" #SEC = "1" !CDS_SEC = "1";
"A":   PN = "1"  !CDS_PN = "1";
"B":   PN = "2"  !CDS_PN = "2";
BODY = "CAP","I274": #LOCATION = "C2U5" !CDS_LOCATION = "C2U5" #SEC = "1" !CDS_SEC = "1";
"A":   PN = "1"  !CDS_PN = "1";
"B":   PN = "2"  !CDS_PN = "2";
BODY = "CAP","I277": #LOCATION = "C2U7" !CDS_LOCATION = "C2U7" #SEC = "1" !CDS_SEC = "1";
"A":   PN = "1"  !CDS_PN = "1";
"B":   PN = "2"  !CDS_PN = "2";
BODY = "CAP","I278": #LOCATION = "C2U11" !CDS_LOCATION = "C2U11" #SEC = "1" !CDS_SEC = "1";
"A":   PN = "1"  !CDS_PN = "1";
"B":   PN = "2"  !CDS_PN = "2";
BODY = "CAP","I279": #LOCATION = "C2U9" !CDS_LOCATION = "C2U9" #SEC = "1" !CDS_SEC = "1";
"A":   PN = "1"  !CDS_PN = "1";
"B":   PN = "2"  !CDS_PN = "2";
BODY = "CAP","I286": #LOCATION = "C2U16" !CDS_LOCATION = "C2U16" #SEC = "1" !CDS_SEC = "1";
"A":   PN = "1"  !CDS_PN = "1";
"B":   PN = "2"  !CDS_PN = "2";
BODY = "CAP","I287": #LOCATION = "C2U14" !CDS_LOCATION = "C2U14" #SEC = "1" !CDS_SEC = "1";
"A":   PN = "1"  !CDS_PN = "1";
"B":   PN = "2"  !CDS_PN = "2";
BODY = "CAP","I294": #LOCATION = "C2U18" !CDS_LOCATION = "C2U18" #SEC = "1" !CDS_SEC = "1";
"A":   PN = "1"  !CDS_PN = "1";
"B":   PN = "2"  !CDS_PN = "2";
BODY = "CAP","I296": #LOCATION = "C2U15" !CDS_LOCATION = "C2U15" #SEC = "1" !CDS_SEC = "1";
"A":   PN = "1"  !CDS_PN = "1";
"B":   PN = "2"  !CDS_PN = "2";
BODY = "CAP","I297": #LOCATION = "C2U13" !CDS_LOCATION = "C2U13" #SEC = "1" !CDS_SEC = "1";
"A":   PN = "1"  !CDS_PN = "1";
"B":   PN = "2"  !CDS_PN = "2";
BODY = "CAP","I300": #LOCATION = "C2U17" !CDS_LOCATION = "C2U17" #SEC = "1" !CDS_SEC = "1";
"A":   PN = "1"  !CDS_PN = "1";
"B":   PN = "2"  !CDS_PN = "2";
BODY = "CAP","I474": #LOCATION = "C3P41" !CDS_LOCATION = "C3P41" &SEC = "1" #&CDS_SEC = "1";
"A":   PN = "1"  !CDS_PN = "1";
"B":   PN = "2"  !CDS_PN = "2";
BODY = "CAP","I475": #LOCATION = "C3P36" !CDS_LOCATION = "C3P36" &SEC = "1" #&CDS_SEC = "1";
"A":   PN = "1"  !CDS_PN = "1";
"B":   PN = "2"  !CDS_PN = "2";
BODY = "CAP","I476": #LOCATION = "C3P16" !CDS_LOCATION = "C3P16" &SEC = "1" #&CDS_SEC = "1";
"A":   PN = "1"  !CDS_PN = "1";
"B":   PN = "2"  !CDS_PN = "2";
BODY = "CAP","I477": #LOCATION = "C3P33" !CDS_LOCATION = "C3P33" &SEC = "1" #&CDS_SEC = "1";
"A":   PN = "1"  !CDS_PN = "1";
"B":   PN = "2"  !CDS_PN = "2";
BODY = "CAP","I478": #LOCATION = "C3P29" !CDS_LOCATION = "C3P29" &SEC = "1" #&CDS_SEC = "1";
"A":   PN = "1"  !CDS_PN = "1";
"B":   PN = "2"  !CDS_PN = "2";
BODY = "CAP","I479": #LOCATION = "C3P24" !CDS_LOCATION = "C3P24" &SEC = "1" #&CDS_SEC = "1";
"A":   PN = "1"  !CDS_PN = "1";
"B":   PN = "2"  !CDS_PN = "2";
BODY = "CAP","I480": #LOCATION = "C3P21" !CDS_LOCATION = "C3P21" &SEC = "1" #&CDS_SEC = "1";
"A":   PN = "1"  !CDS_PN = "1";
"B":   PN = "2"  !CDS_PN = "2";
BODY = "CAP","I481": #LOCATION = "C3P12" !CDS_LOCATION = "C3P12" &SEC = "1" #&CDS_SEC = "1";
"A":   PN = "1"  !CDS_PN = "1";
"B":   PN = "2"  !CDS_PN = "2";
BODY = "CAP","I482": #LOCATION = "C3P10" !CDS_LOCATION = "C3P10" &SEC = "1" #&CDS_SEC = "1";
"A":   PN = "1"  !CDS_PN = "1";
"B":   PN = "2"  !CDS_PN = "2";
BODY = "CAP","I483": #LOCATION = "C3P14" !CDS_LOCATION = "C3P14" &SEC = "1" #&CDS_SEC = "1";
"A":   PN = "1"  !CDS_PN = "1";
"B":   PN = "2"  !CDS_PN = "2";
BODY = "CAP","I484": #LOCATION = "C3P22" !CDS_LOCATION = "C3P22" &SEC = "1" #&CDS_SEC = "1";
"A":   PN = "1"  !CDS_PN = "1";
"B":   PN = "2"  !CDS_PN = "2";
BODY = "CAP","I485": #LOCATION = "C3P19" !CDS_LOCATION = "C3P19" &SEC = "1" #&CDS_SEC = "1";
"A":   PN = "1"  !CDS_PN = "1";
"B":   PN = "2"  !CDS_PN = "2";
BODY = "CAP","I486": #LOCATION = "C3P38" !CDS_LOCATION = "C3P38" &SEC = "1" #&CDS_SEC = "1";
"A":   PN = "1"  !CDS_PN = "1";
"B":   PN = "2"  !CDS_PN = "2";
BODY = "CAP","I487": #LOCATION = "C3P26" !CDS_LOCATION = "C3P26" &SEC = "1" #&CDS_SEC = "1";
"A":   PN = "1"  !CDS_PN = "1";
"B":   PN = "2"  !CDS_PN = "2";
BODY = "CAP","I488": #LOCATION = "C3P31" !CDS_LOCATION = "C3P31" &SEC = "1" #&CDS_SEC = "1";
"A":   PN = "1"  !CDS_PN = "1";
"B":   PN = "2"  !CDS_PN = "2";
BODY = "CAP","I489": #LOCATION = "C3P34" !CDS_LOCATION = "C3P34" &SEC = "1" #&CDS_SEC = "1";
"A":   PN = "1"  !CDS_PN = "1";
"B":   PN = "2"  !CDS_PN = "2";
BODY = "RES","I490": #LOCATION = "R2U15" !CDS_LOCATION = "R2U15" &SEC = "1" #&CDS_SEC = "1";
"A":   PN = "1"  !CDS_PN = "1";
"B":   PN = "2"  !CDS_PN = "2";
BODY = "RES","I491": #LOCATION = "R2U21" !CDS_LOCATION = "R2U21" &SEC = "1" #&CDS_SEC = "1";
"A":   PN = "1"  !CDS_PN = "1";
"B":   PN = "2"  !CDS_PN = "2";
BODY = "RES","I492": #LOCATION = "R2U17" !CDS_LOCATION = "R2U17" &SEC = "1" #&CDS_SEC = "1";
"A":   PN = "1"  !CDS_PN = "1";
"B":   PN = "2"  !CDS_PN = "2";
BODY = "RES","I493": #LOCATION = "R2U19" !CDS_LOCATION = "R2U19" &SEC = "1" #&CDS_SEC = "1";
"A":   PN = "1"  !CDS_PN = "1";
"B":   PN = "2"  !CDS_PN = "2";
BODY = "RES","I494": #LOCATION = "R2U29" !CDS_LOCATION = "R2U29" &SEC = "1" #&CDS_SEC = "1";
"A":   PN = "1"  !CDS_PN = "1";
"B":   PN = "2"  !CDS_PN = "2";
BODY = "RES","I495": #LOCATION = "R2U23" !CDS_LOCATION = "R2U23" &SEC = "1" #&CDS_SEC = "1";
"A":   PN = "1"  !CDS_PN = "1";
"B":   PN = "2"  !CDS_PN = "2";
BODY = "RES","I496": #LOCATION = "R2U25" !CDS_LOCATION = "R2U25" &SEC = "1" #&CDS_SEC = "1";
"A":   PN = "1"  !CDS_PN = "1";
"B":   PN = "2"  !CDS_PN = "2";
BODY = "RES","I497": #LOCATION = "R2U27" !CDS_LOCATION = "R2U27" &SEC = "1" #&CDS_SEC = "1";
"A":   PN = "1"  !CDS_PN = "1";
"B":   PN = "2"  !CDS_PN = "2";
BODY = "RES","I498": #LOCATION = "R2U26" !CDS_LOCATION = "R2U26" &SEC = "1" #&CDS_SEC = "1";
"A":   PN = "1"  !CDS_PN = "1";
"B":   PN = "2"  !CDS_PN = "2";
BODY = "RES","I499": #LOCATION = "R2U14" !CDS_LOCATION = "R2U14" &SEC = "1" #&CDS_SEC = "1";
"A":   PN = "1"  !CDS_PN = "1";
"B":   PN = "2"  !CDS_PN = "2";
BODY = "RES","I500": #LOCATION = "R2U28" !CDS_LOCATION = "R2U28" &SEC = "1" #&CDS_SEC = "1";
"A":   PN = "1"  !CDS_PN = "1";
"B":   PN = "2"  !CDS_PN = "2";
BODY = "RES","I501": #LOCATION = "R2U16" !CDS_LOCATION = "R2U16" &SEC = "1" #&CDS_SEC = "1";
"A":   PN = "1"  !CDS_PN = "1";
"B":   PN = "2"  !CDS_PN = "2";
BODY = "RES","I502": #LOCATION = "R2U18" !CDS_LOCATION = "R2U18" &SEC = "1" #&CDS_SEC = "1";
"A":   PN = "1"  !CDS_PN = "1";
"B":   PN = "2"  !CDS_PN = "2";
BODY = "RES","I503": #LOCATION = "R2U20" !CDS_LOCATION = "R2U20" &SEC = "1" #&CDS_SEC = "1";
"A":   PN = "1"  !CDS_PN = "1";
"B":   PN = "2"  !CDS_PN = "2";
BODY = "RES","I504": #LOCATION = "R2U22" !CDS_LOCATION = "R2U22" &SEC = "1" #&CDS_SEC = "1";
"A":   PN = "1"  !CDS_PN = "1";
"B":   PN = "2"  !CDS_PN = "2";
BODY = "RES","I505": #LOCATION = "R2U24" !CDS_LOCATION = "R2U24" &SEC = "1" #&CDS_SEC = "1";
"A":   PN = "1"  !CDS_PN = "1";
"B":   PN = "2"  !CDS_PN = "2";
DRAWING = "@baseboard_fab2_lib.baseboard_fab2(sch_1):page108";
BODY = "CAP_A","I1": #LOCATION = "C2U20" !CDS_LOCATION = "C2U20" #SEC = "1" !CDS_SEC = "1";
"A":   PN = "1"  !CDS_PN = "1";
"B":   PN = "2"  !CDS_PN = "2";
BODY = "CAP_A","I2": #LOCATION = "C2U24" !CDS_LOCATION = "C2U24" #SEC = "1" !CDS_SEC = "1";
"A":   PN = "1"  !CDS_PN = "1";
"B":   PN = "2"  !CDS_PN = "2";
BODY = "CAP_A","I5": #LOCATION = "C2U21" !CDS_LOCATION = "C2U21" #SEC = "1" !CDS_SEC = "1";
"A":   PN = "1"  !CDS_PN = "1";
"B":   PN = "2"  !CDS_PN = "2";
BODY = "CAP_A","I7": #LOCATION = "C2U25" !CDS_LOCATION = "C2U25" #SEC = "1" !CDS_SEC = "1";
"A":   PN = "1"  !CDS_PN = "1";
"B":   PN = "2"  !CDS_PN = "2";
BODY = "RES","I173": #LOCATION = "R2U37" !CDS_LOCATION = "R2U37" #SEC = "1" !CDS_SEC = "1";
"A":   PN = "1"  !CDS_PN = "1";
"B":   PN = "2"  !CDS_PN = "2";
BODY = "SCONN200_H68296001","I258": #LOCATION = "J8G1" !CDS_LOCATION = "J8G1" #SEC = "1" !CDS_SEC = "1";
"IO1":   PN = "1"  !CDS_PN = "1";
"IO2":   PN = "2"  !CDS_PN = "2";
"IO3":   PN = "3"  !CDS_PN = "3";
"IO4":   PN = "4"  !CDS_PN = "4";
"IO5":   PN = "5"  !CDS_PN = "5";
"IO6":   PN = "6"  !CDS_PN = "6";
"IO7":   PN = "7"  !CDS_PN = "7";
"IO8":   PN = "8"  !CDS_PN = "8";
"IO9":   PN = "9"  !CDS_PN = "9";
"IO10":   PN = "10"  !CDS_PN = "10";
"IO11":   PN = "11"  !CDS_PN = "11";
"IO12":   PN = "12"  !CDS_PN = "12";
"IO13":   PN = "13"  !CDS_PN = "13";
"IO14":   PN = "14"  !CDS_PN = "14";
"IO15":   PN = "15"  !CDS_PN = "15";
"IO16":   PN = "16"  !CDS_PN = "16";
"IO17":   PN = "17"  !CDS_PN = "17";
"IO18":   PN = "18"  !CDS_PN = "18";
"IO19":   PN = "19"  !CDS_PN = "19";
"IO20":   PN = "20"  !CDS_PN = "20";
"IO21":   PN = "21"  !CDS_PN = "21";
"IO22":   PN = "22"  !CDS_PN = "22";
"IO23":   PN = "23"  !CDS_PN = "23";
"IO24":   PN = "24"  !CDS_PN = "24";
"IO25":   PN = "25"  !CDS_PN = "25";
"IO26":   PN = "26"  !CDS_PN = "26";
"IO27":   PN = "27"  !CDS_PN = "27";
"IO28":   PN = "28"  !CDS_PN = "28";
"IO29":   PN = "29"  !CDS_PN = "29";
"IO30":   PN = "30"  !CDS_PN = "30";
"IO31":   PN = "31"  !CDS_PN = "31";
"IO32":   PN = "32"  !CDS_PN = "32";
"IO33":   PN = "33"  !CDS_PN = "33";
"IO34":   PN = "34"  !CDS_PN = "34";
"IO35":   PN = "35"  !CDS_PN = "35";
"IO36":   PN = "36"  !CDS_PN = "36";
"IO37":   PN = "37"  !CDS_PN = "37";
"IO38":   PN = "38"  !CDS_PN = "38";
"IO39":   PN = "39"  !CDS_PN = "39";
"IO40":   PN = "40"  !CDS_PN = "40";
"IO41":   PN = "41"  !CDS_PN = "41";
"IO42":   PN = "42"  !CDS_PN = "42";
"IO43":   PN = "43"  !CDS_PN = "43";
"IO44":   PN = "44"  !CDS_PN = "44";
"IO45":   PN = "45"  !CDS_PN = "45";
"IO46":   PN = "46"  !CDS_PN = "46";
"IO47":   PN = "47"  !CDS_PN = "47";
"IO48":   PN = "48"  !CDS_PN = "48";
"IO49":   PN = "49"  !CDS_PN = "49";
"IO50":   PN = "50"  !CDS_PN = "50";
"IO51":   PN = "51"  !CDS_PN = "51";
"IO52":   PN = "52"  !CDS_PN = "52";
"IO53":   PN = "53"  !CDS_PN = "53";
"IO54":   PN = "54"  !CDS_PN = "54";
"IO55":   PN = "55"  !CDS_PN = "55";
"IO56":   PN = "56"  !CDS_PN = "56";
"IO57":   PN = "57"  !CDS_PN = "57";
"IO58":   PN = "58"  !CDS_PN = "58";
"IO59":   PN = "59"  !CDS_PN = "59";
"IO60":   PN = "60"  !CDS_PN = "60";
"IO61":   PN = "61"  !CDS_PN = "61";
"IO62":   PN = "62"  !CDS_PN = "62";
"IO63":   PN = "63"  !CDS_PN = "63";
"IO64":   PN = "64"  !CDS_PN = "64";
"IO65":   PN = "65"  !CDS_PN = "65";
"IO66":   PN = "66"  !CDS_PN = "66";
"IO67":   PN = "67"  !CDS_PN = "67";
"IO68":   PN = "68"  !CDS_PN = "68";
"IO69":   PN = "69"  !CDS_PN = "69";
"IO70":   PN = "70"  !CDS_PN = "70";
"IO71":   PN = "71"  !CDS_PN = "71";
"IO72":   PN = "72"  !CDS_PN = "72";
"IO73":   PN = "73"  !CDS_PN = "73";
"IO74":   PN = "74"  !CDS_PN = "74";
"IO75":   PN = "75"  !CDS_PN = "75";
"IO76":   PN = "76"  !CDS_PN = "76";
"IO77":   PN = "77"  !CDS_PN = "77";
"IO78":   PN = "78"  !CDS_PN = "78";
"IO79":   PN = "79"  !CDS_PN = "79";
"IO80":   PN = "80"  !CDS_PN = "80";
"IO81":   PN = "81"  !CDS_PN = "81";
"IO82":   PN = "82"  !CDS_PN = "82";
"IO83":   PN = "83"  !CDS_PN = "83";
"IO84":   PN = "84"  !CDS_PN = "84";
"IO85":   PN = "85"  !CDS_PN = "85";
"IO86":   PN = "86"  !CDS_PN = "86";
"IO87":   PN = "87"  !CDS_PN = "87";
"IO88":   PN = "88"  !CDS_PN = "88";
"IO89":   PN = "89"  !CDS_PN = "89";
"IO90":   PN = "90"  !CDS_PN = "90";
"IO91":   PN = "91"  !CDS_PN = "91";
"IO92":   PN = "92"  !CDS_PN = "92";
"IO93":   PN = "93"  !CDS_PN = "93";
"IO94":   PN = "94"  !CDS_PN = "94";
"IO95":   PN = "95"  !CDS_PN = "95";
"IO96":   PN = "96"  !CDS_PN = "96";
"IO97":   PN = "97"  !CDS_PN = "97";
"IO98":   PN = "98"  !CDS_PN = "98";
"IO99":   PN = "99"  !CDS_PN = "99";
"IO100":   PN = "100"  !CDS_PN = "100";
"MH1":   PN = "MH1"  !CDS_PN = "MH1";
"MH2":   PN = "MH2"  !CDS_PN = "MH2";
BODY = "CAP_A","I315": #LOCATION = "C2U23" !CDS_LOCATION = "C2U23" #SEC = "1" !CDS_SEC = "1";
"A":   PN = "1"  !CDS_PN = "1";
"B":   PN = "2"  !CDS_PN = "2";
BODY = "CAP_A","I318": #LOCATION = "C2U22" !CDS_LOCATION = "C2U22" #SEC = "1" !CDS_SEC = "1";
"A":   PN = "1"  !CDS_PN = "1";
"B":   PN = "2"  !CDS_PN = "2";
BODY = "RES","I330": #LOCATION = "R2U31" !CDS_LOCATION = "R2U31" &SEC = "1" #&CDS_SEC = "1";
"A":   PN = "1"  !CDS_PN = "1";
"B":   PN = "2"  !CDS_PN = "2";
BODY = "RES","I339": #LOCATION = "R2U32" !CDS_LOCATION = "R2U32" &SEC = "1" #&CDS_SEC = "1";
"A":   PN = "1"  !CDS_PN = "1";
"B":   PN = "2"  !CDS_PN = "2";
BODY = "RES","I341": #LOCATION = "R7E22" !CDS_LOCATION = "R7E22" #SEC = "1" !CDS_SEC = "1";
"A":   PN = "1"  !CDS_PN = "1";
"B":   PN = "2"  !CDS_PN = "2";
BODY = "RES","I343": #LOCATION = "R7E21" !CDS_LOCATION = "R7E21" #SEC = "1" !CDS_SEC = "1";
"A":   PN = "1"  !CDS_PN = "1";
"B":   PN = "2"  !CDS_PN = "2";
BODY = "RES","I350": #LOCATION = "R2U35" !CDS_LOCATION = "R2U35" &SEC = "1" #&CDS_SEC = "1";
"A":   PN = "1"  !CDS_PN = "1";
"B":   PN = "2"  !CDS_PN = "2";
BODY = "RES","I351": #LOCATION = "R2U36" !CDS_LOCATION = "R2U36" &SEC = "1" #&CDS_SEC = "1";
"A":   PN = "1"  !CDS_PN = "1";
"B":   PN = "2"  !CDS_PN = "2";
DRAWING = "@baseboard_fab2_lib.baseboard_fab2(sch_1):page111";
BODY = "RES","I6": #LOCATION = "R1L13" !CDS_LOCATION = "R1L13" #SEC = "1" !CDS_SEC = "1";
"A":   PN = "1"  !CDS_PN = "1";
"B":   PN = "2"  !CDS_PN = "2";
BODY = "CAP_A","I10": #LOCATION = "C9A2" !CDS_LOCATION = "C9A2" #SEC = "1" !CDS_SEC = "1";
"A":   PN = "1"  !CDS_PN = "1";
"B":   PN = "2"  !CDS_PN = "2";
BODY = "RES","I11": #LOCATION = "R9A14" !CDS_LOCATION = "R9A14" #SEC = "1" !CDS_SEC = "1";
"A":   PN = "1"  !CDS_PN = "1";
"B":   PN = "2"  !CDS_PN = "2";
BODY = "CAP_A","I12": #LOCATION = "C9A5" !CDS_LOCATION = "C9A5" #SEC = "1" !CDS_SEC = "1";
"A":   PN = "1"  !CDS_PN = "1";
"B":   PN = "2"  !CDS_PN = "2";
BODY = "RES","I13": #LOCATION = "R1L23" !CDS_LOCATION = "R1L23" #SEC = "1" !CDS_SEC = "1";
"A":   PN = "1"  !CDS_PN = "1";
"B":   PN = "2"  !CDS_PN = "2";
BODY = "CAP_A","I14": #LOCATION = "C1L8" !CDS_LOCATION = "C1L8" #SEC = "1" !CDS_SEC = "1";
"A":   PN = "1"  !CDS_PN = "1";
"B":   PN = "2"  !CDS_PN = "2";
BODY = "CAP_A","I25": #LOCATION = "C9A6" !CDS_LOCATION = "C9A6" &SEC = "1" #&CDS_SEC = "1";
"A":   PN = "1"  !CDS_PN = "1";
"B":   PN = "2"  !CDS_PN = "2";
BODY = "SCONN60_C21100002","I26": #LOCATION = "J9A3" !CDS_LOCATION = "J9A3" #SEC = "1" !CDS_SEC = "1";
"IO1":   PN = "1"  !CDS_PN = "1";
"IO2":   PN = "2"  !CDS_PN = "2";
"IO3":   PN = "3"  !CDS_PN = "3";
"IO4":   PN = "4"  !CDS_PN = "4";
"IO5":   PN = "5"  !CDS_PN = "5";
"IO6":   PN = "6"  !CDS_PN = "6";
"IO7":   PN = "7"  !CDS_PN = "7";
"IO8":   PN = "8"  !CDS_PN = "8";
"IO9":   PN = "9"  !CDS_PN = "9";
"IO10":   PN = "10"  !CDS_PN = "10";
"IO11":   PN = "11"  !CDS_PN = "11";
"IO12":   PN = "12"  !CDS_PN = "12";
"IO13":   PN = "13"  !CDS_PN = "13";
"IO14":   PN = "14"  !CDS_PN = "14";
"IO15":   PN = "15"  !CDS_PN = "15";
"IO16":   PN = "16"  !CDS_PN = "16";
"IO17":   PN = "17"  !CDS_PN = "17";
"IO18":   PN = "18"  !CDS_PN = "18";
"IO19":   PN = "19"  !CDS_PN = "19";
"IO20":   PN = "20"  !CDS_PN = "20";
"IO21":   PN = "21"  !CDS_PN = "21";
"IO22":   PN = "22"  !CDS_PN = "22";
"IO23":   PN = "23"  !CDS_PN = "23";
"IO24":   PN = "24"  !CDS_PN = "24";
"IO25":   PN = "25"  !CDS_PN = "25";
"IO26":   PN = "26"  !CDS_PN = "26";
"IO27":   PN = "27"  !CDS_PN = "27";
"IO28":   PN = "28"  !CDS_PN = "28";
"IO29":   PN = "29"  !CDS_PN = "29";
"IO30":   PN = "30"  !CDS_PN = "30";
"IO31":   PN = "31"  !CDS_PN = "31";
"IO32":   PN = "32"  !CDS_PN = "32";
"IO33":   PN = "33"  !CDS_PN = "33";
"IO34":   PN = "34"  !CDS_PN = "34";
"IO35":   PN = "35"  !CDS_PN = "35";
"IO36":   PN = "36"  !CDS_PN = "36";
"IO37":   PN = "37"  !CDS_PN = "37";
"IO38":   PN = "38"  !CDS_PN = "38";
"IO39":   PN = "39"  !CDS_PN = "39";
"IO40":   PN = "40"  !CDS_PN = "40";
"IO41":   PN = "41"  !CDS_PN = "41";
"IO42":   PN = "42"  !CDS_PN = "42";
"IO43":   PN = "43"  !CDS_PN = "43";
"IO44":   PN = "44"  !CDS_PN = "44";
"IO45":   PN = "45"  !CDS_PN = "45";
"IO46":   PN = "46"  !CDS_PN = "46";
"IO47":   PN = "47"  !CDS_PN = "47";
"IO48":   PN = "48"  !CDS_PN = "48";
"IO49":   PN = "49"  !CDS_PN = "49";
"IO50":   PN = "50"  !CDS_PN = "50";
"IO51":   PN = "51"  !CDS_PN = "51";
"IO52":   PN = "52"  !CDS_PN = "52";
"IO53":   PN = "53"  !CDS_PN = "53";
"IO54":   PN = "54"  !CDS_PN = "54";
"IO55":   PN = "55"  !CDS_PN = "55";
"IO56":   PN = "56"  !CDS_PN = "56";
"IO57":   PN = "57"  !CDS_PN = "57";
"IO58":   PN = "58"  !CDS_PN = "58";
"IO59":   PN = "59"  !CDS_PN = "59";
"IO60":   PN = "60"  !CDS_PN = "60";
BODY = "CAP_A","I30": #LOCATION = "C1L5" !CDS_LOCATION = "C1L5" &SEC = "1" #&CDS_SEC = "1";
"A":   PN = "1"  !CDS_PN = "1";
"B":   PN = "2"  !CDS_PN = "2";
BODY = "RES","I37": #LOCATION = "R2P2" !CDS_LOCATION = "R2P2" #SEC = "1" !CDS_SEC = "1";
"A":   PN = "1"  !CDS_PN = "1";
"B":   PN = "2"  !CDS_PN = "2";
BODY = "RES","I55": #LOCATION = "R9A4" !CDS_LOCATION = "R9A4" #SEC = "1" !CDS_SEC = "1";
"A":   PN = "1"  !CDS_PN = "1";
"B":   PN = "2"  !CDS_PN = "2";
BODY = "RES","I56": #LOCATION = "R1L17" !CDS_LOCATION = "R1L17" #SEC = "1" !CDS_SEC = "1";
"A":   PN = "1"  !CDS_PN = "1";
"B":   PN = "2"  !CDS_PN = "2";
BODY = "RES","I57": #LOCATION = "R9A17" !CDS_LOCATION = "R9A17" #SEC = "1" !CDS_SEC = "1";
"A":   PN = "1"  !CDS_PN = "1";
"B":   PN = "2"  !CDS_PN = "2";
BODY = "CAP_A","I59": #LOCATION = "C9A4" !CDS_LOCATION = "C9A4" #SEC = "1" !CDS_SEC = "1";
"A":   PN = "1"  !CDS_PN = "1";
"B":   PN = "2"  !CDS_PN = "2";
BODY = "RES","I60": #LOCATION = "R9A15" !CDS_LOCATION = "R9A15" #SEC = "1" !CDS_SEC = "1";
"A":   PN = "1"  !CDS_PN = "1";
"B":   PN = "2"  !CDS_PN = "2";
BODY = "RES","I68": #LOCATION = "R1L29" !CDS_LOCATION = "R1L29" #SEC = "1" !CDS_SEC = "1";
"A":   PN = "1"  !CDS_PN = "1";
"B":   PN = "2"  !CDS_PN = "2";
BODY = "RES","I74": #LOCATION = "R9A3" !CDS_LOCATION = "R9A3" #SEC = "1" !CDS_SEC = "1";
"A":   PN = "1"  !CDS_PN = "1";
"B":   PN = "2"  !CDS_PN = "2";
BODY = "RES","I83": #LOCATION = "R9A2" !CDS_LOCATION = "R9A2" #SEC = "1" !CDS_SEC = "1";
"A":   PN = "1"  !CDS_PN = "1";
"B":   PN = "2"  !CDS_PN = "2";
BODY = "TTL1G07_A","I85": #LOCATION = "U1L4" !CDS_LOCATION = "U1L4" #SEC = "1" !CDS_SEC = "1";
"A":   PN = "2"  !CDS_PN = "2";
"Y":   PN = "4"  !CDS_PN = "4";
BODY = "CAP_A","I87": #LOCATION = "C1L11" !CDS_LOCATION = "C1L11" #SEC = "1" !CDS_SEC = "1";
"A":   PN = "1"  !CDS_PN = "1";
"B":   PN = "2"  !CDS_PN = "2";
BODY = "RES","I89": #LOCATION = "R8E2" !CDS_LOCATION = "R8E2" #SEC = "1" !CDS_SEC = "1";
"A":   PN = "1"  !CDS_PN = "1";
"B":   PN = "2"  !CDS_PN = "2";
BODY = "NPN_DUAL","I93": #LOCATION = "Q9A1" !CDS_LOCATION = "Q9A1" #SEC = "2" !CDS_SEC = "2";
"B<0>":   PN = "2"  !CDS_PN = "2";
"C<0>":   PN = "6"  !CDS_PN = "6";
"E<0>":   PN = "1"  !CDS_PN = "1";
BODY = "NPN_DUAL","I94": #LOCATION = "Q9A1" !CDS_LOCATION = "Q9A1" #SEC = "1" !CDS_SEC = "1";
"B<0>":   PN = "5"  !CDS_PN = "5";
"C<0>":   PN = "3"  !CDS_PN = "3";
"E<0>":   PN = "4"  !CDS_PN = "4";
BODY = "RES","I95": #LOCATION = "R9A1" !CDS_LOCATION = "R9A1" #SEC = "1" !CDS_SEC = "1";
"A":   PN = "1"  !CDS_PN = "1";
"B":   PN = "2"  !CDS_PN = "2";
BODY = "RES","I97": #LOCATION = "R1L28" !CDS_LOCATION = "R1L28" #SEC = "1" !CDS_SEC = "1";
"A":   PN = "1"  !CDS_PN = "1";
"B":   PN = "2"  !CDS_PN = "2";
DRAWING = "@baseboard_fab2_lib.baseboard_fab2(sch_1):page112";
BODY = "NC7SB3157","I40": #LOCATION = "U1M7" !CDS_LOCATION = "U1M7" &SEC = "1" #&CDS_SEC = "1";
"A":   PN = "4"  !CDS_PN = "4";
"B0":   PN = "3"  !CDS_PN = "3";
"B1":   PN = "1"  !CDS_PN = "1";
"GND":   PN = "2"  !CDS_PN = "2";
"S":   PN = "6"  !CDS_PN = "6";
"VCC":   PN = "5"  !CDS_PN = "5";
BODY = "CAP_A","I42": #LOCATION = "C1M36" !CDS_LOCATION = "C1M36" #SEC = "1" !CDS_SEC = "1";
"A":   PN = "1"  !CDS_PN = "1";
"B":   PN = "2"  !CDS_PN = "2";
BODY = "CAP_A","I47": #LOCATION = "C1M37" !CDS_LOCATION = "C1M37" &SEC = "1" #&CDS_SEC = "1";
"A":   PN = "1"  !CDS_PN = "1";
"B":   PN = "2"  !CDS_PN = "2";
BODY = "RES","I49": #LOCATION = "R6P46" !CDS_LOCATION = "R6P46" #SEC = "1" !CDS_SEC = "1";
"A":   PN = "1"  !CDS_PN = "1";
"B":   PN = "2"  !CDS_PN = "2";
BODY = "RES","I50": #LOCATION = "R7P30" !CDS_LOCATION = "R7P30" #SEC = "1" !CDS_SEC = "1";
"A":   PN = "1"  !CDS_PN = "1";
"B":   PN = "2"  !CDS_PN = "2";
BODY = "RES","I51": #LOCATION = "R1M3" !CDS_LOCATION = "R1M3" #SEC = "1" !CDS_SEC = "1";
"A":   PN = "1"  !CDS_PN = "1";
"B":   PN = "2"  !CDS_PN = "2";
BODY = "RES","I53": #LOCATION = "R4P15" !CDS_LOCATION = "R4P15" #SEC = "1" !CDS_SEC = "1";
"A":   PN = "1"  !CDS_PN = "1";
"B":   PN = "2"  !CDS_PN = "2";
BODY = "RES","I54": #LOCATION = "R1M4" !CDS_LOCATION = "R1M4" #SEC = "1" !CDS_SEC = "1";
"A":   PN = "1"  !CDS_PN = "1";
"B":   PN = "2"  !CDS_PN = "2";
BODY = "RES","I55": #LOCATION = "R6T7" !CDS_LOCATION = "R6T7" #SEC = "1" !CDS_SEC = "1";
"A":   PN = "1"  !CDS_PN = "1";
"B":   PN = "2"  !CDS_PN = "2";
BODY = "RES","I56": #LOCATION = "R6T6" !CDS_LOCATION = "R6T6" #SEC = "1" !CDS_SEC = "1";
"A":   PN = "1"  !CDS_PN = "1";
"B":   PN = "2"  !CDS_PN = "2";
BODY = "RES","I57": #LOCATION = "R4P12" !CDS_LOCATION = "R4P12" #SEC = "1" !CDS_SEC = "1";
"A":   PN = "1"  !CDS_PN = "1";
"B":   PN = "2"  !CDS_PN = "2";
BODY = "RES","I58": #LOCATION = "R4P23" !CDS_LOCATION = "R4P23" #SEC = "1" !CDS_SEC = "1";
"A":   PN = "1"  !CDS_PN = "1";
"B":   PN = "2"  !CDS_PN = "2";
BODY = "RES","I59": #LOCATION = "R4P24" !CDS_LOCATION = "R4P24" #SEC = "1" !CDS_SEC = "1";
"A":   PN = "1"  !CDS_PN = "1";
"B":   PN = "2"  !CDS_PN = "2";
BODY = "RES","I60": #LOCATION = "R1L15" !CDS_LOCATION = "R1L15" #SEC = "1" !CDS_SEC = "1";
"A":   PN = "1"  !CDS_PN = "1";
"B":   PN = "2"  !CDS_PN = "2";
BODY = "RES","I61": #LOCATION = "R7P29" !CDS_LOCATION = "R7P29" &SEC = "1" #&CDS_SEC = "1";
"A":   PN = "1"  !CDS_PN = "1";
"B":   PN = "2"  !CDS_PN = "2";
BODY = "RES","I62": #LOCATION = "R6T5" !CDS_LOCATION = "R6T5" #SEC = "1" !CDS_SEC = "1";
"A":   PN = "1"  !CDS_PN = "1";
"B":   PN = "2"  !CDS_PN = "2";
BODY = "RES","I76": #LOCATION = "R1L39" !CDS_LOCATION = "R1L39" #SEC = "1" !CDS_SEC = "1";
"A":   PN = "1"  !CDS_PN = "1";
"B":   PN = "2"  !CDS_PN = "2";
BODY = "RES","I77": #LOCATION = "R1L41" !CDS_LOCATION = "R1L41" #SEC = "1" !CDS_SEC = "1";
"A":   PN = "1"  !CDS_PN = "1";
"B":   PN = "2"  !CDS_PN = "2";
BODY = "RES","I78": #LOCATION = "R9A11" !CDS_LOCATION = "R9A11" #SEC = "1" !CDS_SEC = "1";
"A":   PN = "1"  !CDS_PN = "1";
"B":   PN = "2"  !CDS_PN = "2";
BODY = "RES","I79": #LOCATION = "R8A13" !CDS_LOCATION = "R8A13" #SEC = "1" !CDS_SEC = "1";
"A":   PN = "1"  !CDS_PN = "1";
"B":   PN = "2"  !CDS_PN = "2";
BODY = "RES","I80": #LOCATION = "R8A14" !CDS_LOCATION = "R8A14" #SEC = "1" !CDS_SEC = "1";
"A":   PN = "1"  !CDS_PN = "1";
"B":   PN = "2"  !CDS_PN = "2";
BODY = "RES","I85": #LOCATION = "R3M10" !CDS_LOCATION = "R3M10" #SEC = "1" !CDS_SEC = "1";
"A":   PN = "1"  !CDS_PN = "1";
"B":   PN = "2"  !CDS_PN = "2";
BODY = "RES","I94": #LOCATION = "R8B2" !CDS_LOCATION = "R8B2" #SEC = "1" !CDS_SEC = "1";
"A":   PN = "1"  !CDS_PN = "1";
"B":   PN = "2"  !CDS_PN = "2";
BODY = "RES","I95": #LOCATION = "R8B1" !CDS_LOCATION = "R8B1" &SEC = "1" #&CDS_SEC = "1";
"A":   PN = "1"  !CDS_PN = "1";
"B":   PN = "2"  !CDS_PN = "2";
BODY = "TTL3126","I108": #LOCATION = "U1L1" !CDS_LOCATION = "U1L1";
"A<0>":   PN = "12"  !CDS_PN = "12";
"A<1>":   PN = "9"  !CDS_PN = "9";
"A<2>":   PN = "5"  !CDS_PN = "5";
"A<3>":   PN = "2"  !CDS_PN = "2";
"B<0>":   PN = "11"  !CDS_PN = "11";
"B<1>":   PN = "8"  !CDS_PN = "8";
"B<2>":   PN = "6"  !CDS_PN = "6";
"B<3>":   PN = "3"  !CDS_PN = "3";
"OE<0>":   PN = "13"  !CDS_PN = "13";
"OE<1>":   PN = "10"  !CDS_PN = "10";
"OE<2>":   PN = "4"  !CDS_PN = "4";
"OE<3>":   PN = "1"  !CDS_PN = "1";
BODY = "TTL3126","I109": #LOCATION = "U1L5" !CDS_LOCATION = "U1L5";
"A<0>":   PN = "12"  !CDS_PN = "12";
"A<1>":   PN = "9"  !CDS_PN = "9";
"A<2>":   PN = "5"  !CDS_PN = "5";
"A<3>":   PN = "2"  !CDS_PN = "2";
"B<0>":   PN = "11"  !CDS_PN = "11";
"B<1>":   PN = "8"  !CDS_PN = "8";
"B<2>":   PN = "6"  !CDS_PN = "6";
"B<3>":   PN = "3"  !CDS_PN = "3";
"OE<0>":   PN = "13"  !CDS_PN = "13";
"OE<1>":   PN = "10"  !CDS_PN = "10";
"OE<2>":   PN = "4"  !CDS_PN = "4";
"OE<3>":   PN = "1"  !CDS_PN = "1";
BODY = "RES","I120": #LOCATION = "R6T9" !CDS_LOCATION = "R6T9" #SEC = "1" !CDS_SEC = "1";
"A":   PN = "1"  !CDS_PN = "1";
"B":   PN = "2"  !CDS_PN = "2";
BODY = "RES","I121": #LOCATION = "R6T8" !CDS_LOCATION = "R6T8" #SEC = "1" !CDS_SEC = "1";
"A":   PN = "1"  !CDS_PN = "1";
"B":   PN = "2"  !CDS_PN = "2";
BODY = "74CBTLV1G125","I127": #LOCATION = "U1M4" !CDS_LOCATION = "U1M4" #SEC = "1" !CDS_SEC = "1";
"A":   PN = "2"  !CDS_PN = "2";
"B":   PN = "4"  !CDS_PN = "4";
"OE_N":   PN = "1"  !CDS_PN = "1";
BODY = "CAP_A","I131": #LOCATION = "C1M30" !CDS_LOCATION = "C1M30" #SEC = "1" !CDS_SEC = "1";
"A":   PN = "1"  !CDS_PN = "1";
"B":   PN = "2"  !CDS_PN = "2";
BODY = "CAP","I136": #LOCATION = "C1L1" !CDS_LOCATION = "C1L1" #SEC = "1" !CDS_SEC = "1";
"A":   PN = "1"  !CDS_PN = "1";
"B":   PN = "2"  !CDS_PN = "2";
BODY = "CAP","I140": #LOCATION = "C1L19" !CDS_LOCATION = "C1L19" #SEC = "1" !CDS_SEC = "1";
"A":   PN = "1"  !CDS_PN = "1";
"B":   PN = "2"  !CDS_PN = "2";
DRAWING = "@baseboard_fab2_lib.baseboard_fab2(sch_1):page113";
BODY = "NC7SB3157","I107": #LOCATION = "U1M2" !CDS_LOCATION = "U1M2" #SEC = "1" !CDS_SEC = "1";
"A":   PN = "4"  !CDS_PN = "4";
"B0":   PN = "3"  !CDS_PN = "3";
"B1":   PN = "1"  !CDS_PN = "1";
"GND":   PN = "2"  !CDS_PN = "2";
"S":   PN = "6"  !CDS_PN = "6";
"VCC":   PN = "5"  !CDS_PN = "5";
BODY = "CAP_A","I116": #LOCATION = "C1M31" !CDS_LOCATION = "C1M31" #SEC = "1" !CDS_SEC = "1";
"A":   PN = "1"  !CDS_PN = "1";
"B":   PN = "2"  !CDS_PN = "2";
BODY = "CAP_A","I117": #LOCATION = "C1M32" !CDS_LOCATION = "C1M32" #SEC = "1" !CDS_SEC = "1";
"A":   PN = "1"  !CDS_PN = "1";
"B":   PN = "2"  !CDS_PN = "2";
BODY = "CAP_A","I119": #LOCATION = "C1M28" !CDS_LOCATION = "C1M28" #SEC = "1" !CDS_SEC = "1";
"A":   PN = "1"  !CDS_PN = "1";
"B":   PN = "2"  !CDS_PN = "2";
BODY = "74CBTLV1G125","I127": #LOCATION = "U1M6" !CDS_LOCATION = "U1M6" #SEC = "1" !CDS_SEC = "1";
"A":   PN = "2"  !CDS_PN = "2";
"B":   PN = "4"  !CDS_PN = "4";
"OE_N":   PN = "1"  !CDS_PN = "1";
BODY = "CAP_A","I147": #LOCATION = "C1M29" !CDS_LOCATION = "C1M29" &SEC = "1" #&CDS_SEC = "1";
"A":   PN = "1"  !CDS_PN = "1";
"B":   PN = "2"  !CDS_PN = "2";
BODY = "RES","I168": #LOCATION = "R9B14" !CDS_LOCATION = "R9B14" #SEC = "1" !CDS_SEC = "1";
"A":   PN = "1"  !CDS_PN = "1";
"B":   PN = "2"  !CDS_PN = "2";
BODY = "SCONN10_C12536004","I175": #LOCATION = "J9B4" !CDS_LOCATION = "J9B4" #SEC = "1" !CDS_SEC = "1";
"IO1":   PN = "1"  !CDS_PN = "1";
"IO2":   PN = "2"  !CDS_PN = "2";
"IO3":   PN = "3"  !CDS_PN = "3";
"IO4":   PN = "4"  !CDS_PN = "4";
"IO5":   PN = "5"  !CDS_PN = "5";
"IO6":   PN = "6"  !CDS_PN = "6";
"IO7":   PN = "7"  !CDS_PN = "7";
"IO8":   PN = "8"  !CDS_PN = "8";
"IO9":   PN = "9"  !CDS_PN = "9";
"IO10":   PN = "10"  !CDS_PN = "10";
BODY = "RES","I179": #LOCATION = "R9B9" !CDS_LOCATION = "R9B9" #SEC = "1" !CDS_SEC = "1";
"A":   PN = "1"  !CDS_PN = "1";
"B":   PN = "2"  !CDS_PN = "2";
BODY = "RES","I180": #LOCATION = "R9B10" !CDS_LOCATION = "R9B10" #SEC = "1" !CDS_SEC = "1";
"A":   PN = "1"  !CDS_PN = "1";
"B":   PN = "2"  !CDS_PN = "2";
BODY = "74CBTLV1G125","I185": #LOCATION = "U9A5" !CDS_LOCATION = "U9A5" #SEC = "1" !CDS_SEC = "1";
"A":   PN = "2"  !CDS_PN = "2";
"B":   PN = "4"  !CDS_PN = "4";
"OE_N":   PN = "1"  !CDS_PN = "1";
BODY = "74CBTLV1G125","I190": #LOCATION = "U6M1" !CDS_LOCATION = "U6M1" #SEC = "1" !CDS_SEC = "1";
"A":   PN = "2"  !CDS_PN = "2";
"B":   PN = "4"  !CDS_PN = "4";
"OE_N":   PN = "1"  !CDS_PN = "1";
BODY = "RES","I195": #LOCATION = "R1M22" !CDS_LOCATION = "R1M22" #SEC = "1" !CDS_SEC = "1";
"A":   PN = "1"  !CDS_PN = "1";
"B":   PN = "2"  !CDS_PN = "2";
BODY = "74CBTLV1G125","I196": #LOCATION = "U1M5" !CDS_LOCATION = "U1M5" #SEC = "1" !CDS_SEC = "1";
"A":   PN = "2"  !CDS_PN = "2";
"B":   PN = "4"  !CDS_PN = "4";
"OE_N":   PN = "1"  !CDS_PN = "1";
BODY = "RES","I199": #LOCATION = "R1M23" !CDS_LOCATION = "R1M23" #SEC = "1" !CDS_SEC = "1";
"A":   PN = "1"  !CDS_PN = "1";
"B":   PN = "2"  !CDS_PN = "2";
BODY = "RES","I202": #LOCATION = "R1M19" !CDS_LOCATION = "R1M19" #SEC = "1" !CDS_SEC = "1";
"A":   PN = "1"  !CDS_PN = "1";
"B":   PN = "2"  !CDS_PN = "2";
BODY = "RES","I203": #LOCATION = "R9B12" !CDS_LOCATION = "R9B12" #SEC = "1" !CDS_SEC = "1";
"A":   PN = "1"  !CDS_PN = "1";
"B":   PN = "2"  !CDS_PN = "2";
BODY = "RES","I204": #LOCATION = "R1M20" !CDS_LOCATION = "R1M20" #SEC = "1" !CDS_SEC = "1";
"A":   PN = "1"  !CDS_PN = "1";
"B":   PN = "2"  !CDS_PN = "2";
BODY = "RES","I205": #LOCATION = "R1M21" !CDS_LOCATION = "R1M21" #SEC = "1" !CDS_SEC = "1";
"A":   PN = "1"  !CDS_PN = "1";
"B":   PN = "2"  !CDS_PN = "2";
BODY = "74CBTLV1G125","I206": #LOCATION = "U4R1" !CDS_LOCATION = "U4R1" #SEC = "1" !CDS_SEC = "1";
"A":   PN = "2"  !CDS_PN = "2";
"B":   PN = "4"  !CDS_PN = "4";
"OE_N":   PN = "1"  !CDS_PN = "1";
BODY = "RES","I239": #LOCATION = "R9B11" !CDS_LOCATION = "R9B11" #SEC = "1" !CDS_SEC = "1";
"A":   PN = "1"  !CDS_PN = "1";
"B":   PN = "2"  !CDS_PN = "2";
BODY = "RES","I240": #LOCATION = "R9B13" !CDS_LOCATION = "R9B13" #SEC = "1" !CDS_SEC = "1";
"A":   PN = "1"  !CDS_PN = "1";
"B":   PN = "2"  !CDS_PN = "2";
BODY = "CAP_A","I246": #LOCATION = "C4R2" !CDS_LOCATION = "C4R2" #SEC = "1" !CDS_SEC = "1";
"A":   PN = "1"  !CDS_PN = "1";
"B":   PN = "2"  !CDS_PN = "2";
BODY = "CAP_A","I248": #LOCATION = "C1M33" !CDS_LOCATION = "C1M33" #SEC = "1" !CDS_SEC = "1";
"A":   PN = "1"  !CDS_PN = "1";
"B":   PN = "2"  !CDS_PN = "2";
BODY = "CAP_A","I250": #LOCATION = "C6M6" !CDS_LOCATION = "C6M6" #SEC = "1" !CDS_SEC = "1";
"A":   PN = "1"  !CDS_PN = "1";
"B":   PN = "2"  !CDS_PN = "2";
BODY = "NC7SB3157","I255": #LOCATION = "U2M1" !CDS_LOCATION = "U2M1" #SEC = "1" !CDS_SEC = "1";
"A":   PN = "4"  !CDS_PN = "4";
"B0":   PN = "3"  !CDS_PN = "3";
"B1":   PN = "1"  !CDS_PN = "1";
"GND":   PN = "2"  !CDS_PN = "2";
"S":   PN = "6"  !CDS_PN = "6";
"VCC":   PN = "5"  !CDS_PN = "5";
BODY = "CAP_A","I265": #LOCATION = "C1M34" !CDS_LOCATION = "C1M34" #SEC = "1" !CDS_SEC = "1";
"A":   PN = "1"  !CDS_PN = "1";
"B":   PN = "2"  !CDS_PN = "2";
BODY = "CAP_A","I266": #LOCATION = "C1M35" !CDS_LOCATION = "C1M35" #SEC = "1" !CDS_SEC = "1";
"A":   PN = "1"  !CDS_PN = "1";
"B":   PN = "2"  !CDS_PN = "2";
BODY = "CAP_A","I267": #LOCATION = "C1L20" !CDS_LOCATION = "C1L20" #SEC = "1" !CDS_SEC = "1";
"A":   PN = "1"  !CDS_PN = "1";
"B":   PN = "2"  !CDS_PN = "2";
BODY = "RES","I270": #LOCATION = "R4R6" !CDS_LOCATION = "R4R6" #SEC = "1" !CDS_SEC = "1";
"A":   PN = "1"  !CDS_PN = "1";
"B":   PN = "2"  !CDS_PN = "2";
BODY = "RES","I271": #LOCATION = "R6M8" !CDS_LOCATION = "R6M8" #SEC = "1" !CDS_SEC = "1";
"A":   PN = "1"  !CDS_PN = "1";
"B":   PN = "2"  !CDS_PN = "2";
BODY = "RES","I272": #LOCATION = "R5W1" !CDS_LOCATION = "R5W1" #SEC = "1" !CDS_SEC = "1";
"A":   PN = "1"  !CDS_PN = "1";
"B":   PN = "2"  !CDS_PN = "2";
BODY = "RES","I273": #LOCATION = "R5W2" !CDS_LOCATION = "R5W2" &SEC = "1" #&CDS_SEC = "1";
"A":   PN = "1"  !CDS_PN = "1";
"B":   PN = "2"  !CDS_PN = "2";
DRAWING = "@baseboard_fab2_lib.baseboard_fab2(sch_1):page114";
BODY = "LBG_CORE_QAT_EXT_D","I40": #LOCATION = "U7C1" !CDS_LOCATION = "U7C1" #SEC = "1" !CDS_SEC = "1";
"CLKOUT_ITPXDPN":   PN = "A39"  !CDS_PN = "A39";
"CLKOUT_ITPXDPP":   PN = "C39"  !CDS_PN = "C39";
"CLKOUT_NSSCCAP0N":   PN = "A32"  !CDS_PN = "A32";
"CLKOUT_NSSCCAP0P":   PN = "C32"  !CDS_PN = "C32";
"CLKOUT_NSSCCAP1N":   PN = "B38"  !CDS_PN = "B38";
"CLKOUT_NSSCCAP1P":   PN = "D38"  !CDS_PN = "D38";
"CLKOUT_PLAT0N":   PN = "B29"  !CDS_PN = "B29";
"CLKOUT_PLAT0P":   PN = "D29"  !CDS_PN = "D29";
"CLKOUT_PLAT1N":   PN = "B40"  !CDS_PN = "B40";
"CLKOUT_PLAT1P":   PN = "D40"  !CDS_PN = "D40";
"CLKOUT_SRCN<0>":   PN = "K38"  !CDS_PN = "K38";
"CLKOUT_SRCN<1>":   PN = "K35"  !CDS_PN = "K35";
"CLKOUT_SRCN<2>":   PN = "J33"  !CDS_PN = "J33";
"CLKOUT_SRCN<3>":   PN = "K42"  !CDS_PN = "K42";
"CLKOUT_SRCN<4>":   PN = "A28"  !CDS_PN = "A28";
"CLKOUT_SRCN<5>":   PN = "J40"  !CDS_PN = "J40";
"CLKOUT_SRCN<6>":   PN = "D33"  !CDS_PN = "D33";
"CLKOUT_SRCN<7>":   PN = "H31"  !CDS_PN = "H31";
"CLKOUT_SRCN<8>":   PN = "D31"  !CDS_PN = "D31";
"CLKOUT_SRCN<9>":   PN = "J26"  !CDS_PN = "J26";
"CLKOUT_SRCN<10>":   PN = "B23"  !CDS_PN = "B23";
"CLKOUT_SRCN<11>":   PN = "B21"  !CDS_PN = "B21";
"CLKOUT_SRCN<12>":   PN = "K24"  !CDS_PN = "K24";
"CLKOUT_SRCN<13>":   PN = "C24"  !CDS_PN = "C24";
"CLKOUT_SRCN<14>":   PN = "C20"  !CDS_PN = "C20";
"CLKOUT_SRCN<15>":   PN = "K27"  !CDS_PN = "K27";
"CLKOUT_SRCP<0>":   PN = "H38"  !CDS_PN = "H38";
"CLKOUT_SRCP<1>":   PN = "H35"  !CDS_PN = "H35";
"CLKOUT_SRCP<2>":   PN = "G33"  !CDS_PN = "G33";
"CLKOUT_SRCP<3>":   PN = "H42"  !CDS_PN = "H42";
"CLKOUT_SRCP<4>":   PN = "C28"  !CDS_PN = "C28";
"CLKOUT_SRCP<5>":   PN = "G40"  !CDS_PN = "G40";
"CLKOUT_SRCP<6>":   PN = "B33"  !CDS_PN = "B33";
"CLKOUT_SRCP<7>":   PN = "K31"  !CDS_PN = "K31";
"CLKOUT_SRCP<8>":   PN = "B31"  !CDS_PN = "B31";
"CLKOUT_SRCP<9>":   PN = "G26"  !CDS_PN = "G26";
"CLKOUT_SRCP<10>":   PN = "D23"  !CDS_PN = "D23";
"CLKOUT_SRCP<11>":   PN = "D21"  !CDS_PN = "D21";
"CLKOUT_SRCP<12>":   PN = "H24"  !CDS_PN = "H24";
"CLKOUT_SRCP<13>":   PN = "A24"  !CDS_PN = "A24";
"CLKOUT_SRCP<14>":   PN = "A20"  !CDS_PN = "A20";
"CLKOUT_SRCP<15>":   PN = "H27"  !CDS_PN = "H27";
"CLOCKSE_BMCCLK":   PN = "BW50"  !CDS_PN = "BW50";
"CLOCKSE_PMSYNCCLK1":   PN = "BY51"  !CDS_PN = "BY51";
"CLOCKSE_PMSYNCCLK2":   PN = "BV51"  !CDS_PN = "BV51";
"RSVD<64>":   PN = "C26"  !CDS_PN = "C26";
"RSVD<65>":   PN = "A26"  !CDS_PN = "A26";
"RTCX1":   PN = "K17"  !CDS_PN = "K17";
"RTCX2":   PN = "H17"  !CDS_PN = "H17";
"XCLK_BIASREF":   PN = "G44"  !CDS_PN = "G44";
"XTAL_IN":   PN = "B35"  !CDS_PN = "B35";
"XTAL_OUT":   PN = "D35"  !CDS_PN = "D35";
BODY = "CAP","I47": #LOCATION = "C7C5" !CDS_LOCATION = "C7C5" #SEC = "1" !CDS_SEC = "1";
"A":   PN = "1"  !CDS_PN = "1";
"B":   PN = "2"  !CDS_PN = "2";
BODY = "RES","I48": #LOCATION = "R7C1" !CDS_LOCATION = "R7C1" #SEC = "1" !CDS_SEC = "1";
"A":   PN = "1"  !CDS_PN = "1";
"B":   PN = "2"  !CDS_PN = "2";
BODY = "CRYSTAL","I49": #LOCATION = "Y7C1" !CDS_LOCATION = "Y7C1" #SEC = "1" !CDS_SEC = "1";
"A":   PN = "1"  !CDS_PN = "1";
"B":   PN = "3"  !CDS_PN = "3";
BODY = "CAP","I50": #LOCATION = "C7C4" !CDS_LOCATION = "C7C4" #SEC = "1" !CDS_SEC = "1";
"A":   PN = "1"  !CDS_PN = "1";
"B":   PN = "2"  !CDS_PN = "2";
BODY = "RES","I54": #LOCATION = "R7C6" !CDS_LOCATION = "R7C6" &SEC = "1" #&CDS_SEC = "1";
"A":   PN = "1"  !CDS_PN = "1";
"B":   PN = "2"  !CDS_PN = "2";
BODY = "CRYSTAL","I55": #LOCATION = "Y7C2" !CDS_LOCATION = "Y7C2" #SEC = "1" !CDS_SEC = "1";
"A":   PN = "1"  !CDS_PN = "1";
"B":   PN = "2"  !CDS_PN = "2";
BODY = "RES","I110": #LOCATION = "R8B20" !CDS_LOCATION = "R8B20" #SEC = "1" !CDS_SEC = "1";
"A":   PN = "1"  !CDS_PN = "1";
"B":   PN = "2"  !CDS_PN = "2";
BODY = "RES","I124": #LOCATION = "R8B21" !CDS_LOCATION = "R8B21" #SEC = "1" !CDS_SEC = "1";
"A":   PN = "1"  !CDS_PN = "1";
"B":   PN = "2"  !CDS_PN = "2";
BODY = "RES","I149": #LOCATION = "R3N1" !CDS_LOCATION = "R3N1" #SEC = "1" !CDS_SEC = "1";
"A":   PN = "1"  !CDS_PN = "1";
"B":   PN = "2"  !CDS_PN = "2";
BODY = "RES","I191": #LOCATION = "R7C4" !CDS_LOCATION = "R7C4" #SEC = "1" !CDS_SEC = "1";
"A":   PN = "1"  !CDS_PN = "1";
"B":   PN = "2"  !CDS_PN = "2";
BODY = "RES","I192": #LOCATION = "R7C2" !CDS_LOCATION = "R7C2" #SEC = "1" !CDS_SEC = "1";
"A":   PN = "1"  !CDS_PN = "1";
"B":   PN = "2"  !CDS_PN = "2";
BODY = "CAP","I193": #LOCATION = "C3W1" !CDS_LOCATION = "C3W1" #SEC = "1" !CDS_SEC = "1";
"A":   PN = "1"  !CDS_PN = "1";
"B":   PN = "2"  !CDS_PN = "2";
BODY = "CAP","I195": #LOCATION = "C7C13" !CDS_LOCATION = "C7C13" #SEC = "1" !CDS_SEC = "1";
"A":   PN = "1"  !CDS_PN = "1";
"B":   PN = "2"  !CDS_PN = "2";
BODY = "CAP","I196": #LOCATION = "C7C15" !CDS_LOCATION = "C7C15" #SEC = "1" !CDS_SEC = "1";
"A":   PN = "1"  !CDS_PN = "1";
"B":   PN = "2"  !CDS_PN = "2";
DRAWING = "@baseboard_fab2_lib.baseboard_fab2(sch_1):page115";
BODY = "LBG_CORE_QAT_EXT_D","I74": #LOCATION = "U7C1" !CDS_LOCATION = "U7C1" #SEC = "2" !CDS_SEC = "2";
"RSVD<55>":   PN = "BN68"  !CDS_PN = "BN68";
"USB2_COMP":   PN = "BN70"  !CDS_PN = "BN70";
"USB2_VBUS":   PN = "BR67"  !CDS_PN = "BR67";
"USB2N_1":   PN = "BY60"  !CDS_PN = "BY60";
"USB2N_2":   PN = "CA61"  !CDS_PN = "CA61";
"USB2N_3":   PN = "CA59"  !CDS_PN = "CA59";
"USB2N_4":   PN = "BY62"  !CDS_PN = "BY62";
"USB2N_5":   PN = "BY58"  !CDS_PN = "BY58";
"USB2N_6":   PN = "CA63"  !CDS_PN = "CA63";
"USB2N_7":   PN = "CA57"  !CDS_PN = "CA57";
"USB2N_8":   PN = "BY64"  !CDS_PN = "BY64";
"USB2N_9":   PN = "BY55"  !CDS_PN = "BY55";
"USB2N_10":   PN = "BW65"  !CDS_PN = "BW65";
"USB2N_11":   PN = "CA54"  !CDS_PN = "CA54";
"USB2N_12":   PN = "BW67"  !CDS_PN = "BW67";
"USB2N_13":   PN = "BY53"  !CDS_PN = "BY53";
"USB2N_14":   PN = "BW68"  !CDS_PN = "BW68";
"USB2P_1":   PN = "BV60"  !CDS_PN = "BV60";
"USB2P_2":   PN = "BW61"  !CDS_PN = "BW61";
"USB2P_3":   PN = "BW59"  !CDS_PN = "BW59";
"USB2P_4":   PN = "BV62"  !CDS_PN = "BV62";
"USB2P_5":   PN = "BV58"  !CDS_PN = "BV58";
"USB2P_6":   PN = "BW63"  !CDS_PN = "BW63";
"USB2P_7":   PN = "BW57"  !CDS_PN = "BW57";
"USB2P_8":   PN = "BV64"  !CDS_PN = "BV64";
"USB2P_9":   PN = "BV55"  !CDS_PN = "BV55";
"USB2P_10":   PN = "BU65"  !CDS_PN = "BU65";
"USB2P_11":   PN = "BW54"  !CDS_PN = "BW54";
"USB2P_12":   PN = "BV66"  !CDS_PN = "BV66";
"USB2P_13":   PN = "BV53"  !CDS_PN = "BV53";
"USB2P_14":   PN = "BU67"  !CDS_PN = "BU67";
"USB3_1_RXN":   PN = "BK71"  !CDS_PN = "BK71";
"USB3_1_RXP":   PN = "BK69"  !CDS_PN = "BK69";
"USB3_1_TXN":   PN = "BL52"  !CDS_PN = "BL52";
"USB3_1_TXP":   PN = "BK54"  !CDS_PN = "BK54";
"USB3_2_RXN":   PN = "BJ72"  !CDS_PN = "BJ72";
"USB3_2_RXP":   PN = "BJ70"  !CDS_PN = "BJ70";
"USB3_2_TXN":   PN = "BL56"  !CDS_PN = "BL56";
"USB3_2_TXP":   PN = "BJ56"  !CDS_PN = "BJ56";
"USB3_3_RXN":   PN = "BH71"  !CDS_PN = "BH71";
"USB3_3_RXP":   PN = "BH69"  !CDS_PN = "BH69";
"USB3_3_TXN":   PN = "BM54"  !CDS_PN = "BM54";
"USB3_3_TXP":   PN = "BN56"  !CDS_PN = "BN56";
"USB3_4_RXN":   PN = "BF72"  !CDS_PN = "BF72";
"USB3_4_RXP":   PN = "BF70"  !CDS_PN = "BF70";
"USB3_4_TXN":   PN = "BH58"  !CDS_PN = "BH58";
"USB3_4_TXP":   PN = "BG56"  !CDS_PN = "BG56";
"USB3_5_RXN":   PN = "BE71"  !CDS_PN = "BE71";
"USB3_5_RXP":   PN = "BE69"  !CDS_PN = "BE69";
"USB3_5_TXN":   PN = "BK58"  !CDS_PN = "BK58";
"USB3_5_TXP":   PN = "BJ59"  !CDS_PN = "BJ59";
"USB3_6_RXN":   PN = "BD72"  !CDS_PN = "BD72";
"USB3_6_RXP":   PN = "BD70"  !CDS_PN = "BD70";
"USB3_6_TXN":   PN = "BL59"  !CDS_PN = "BL59";
"USB3_6_TXP":   PN = "BM61"  !CDS_PN = "BM61";
BODY = "RES","I90": #LOCATION = "R8B9" !CDS_LOCATION = "R8B9" #SEC = "1" !CDS_SEC = "1";
"A":   PN = "1"  !CDS_PN = "1";
"B":   PN = "2"  !CDS_PN = "2";
BODY = "RES","I114": #LOCATION = "R8B32" !CDS_LOCATION = "R8B32" #SEC = "1" !CDS_SEC = "1";
"A":   PN = "1"  !CDS_PN = "1";
"B":   PN = "2"  !CDS_PN = "2";
BODY = "RES","I118": #LOCATION = "R1W14" !CDS_LOCATION = "R1W14" #SEC = "1" !CDS_SEC = "1";
"A":   PN = "1"  !CDS_PN = "1";
"B":   PN = "2"  !CDS_PN = "2";
BODY = "RES","I119": #LOCATION = "R1W15" !CDS_LOCATION = "R1W15" #SEC = "1" !CDS_SEC = "1";
"A":   PN = "1"  !CDS_PN = "1";
"B":   PN = "2"  !CDS_PN = "2";
BODY = "RES","I120": #LOCATION = "R1W17" !CDS_LOCATION = "R1W17" #SEC = "1" !CDS_SEC = "1";
"A":   PN = "1"  !CDS_PN = "1";
"B":   PN = "2"  !CDS_PN = "2";
BODY = "RES","I121": #LOCATION = "R1W16" !CDS_LOCATION = "R1W16" #SEC = "1" !CDS_SEC = "1";
"A":   PN = "1"  !CDS_PN = "1";
"B":   PN = "2"  !CDS_PN = "2";
BODY = "RES","I122": #LOCATION = "R1W19" !CDS_LOCATION = "R1W19" #SEC = "1" !CDS_SEC = "1";
"A":   PN = "1"  !CDS_PN = "1";
"B":   PN = "2"  !CDS_PN = "2";
BODY = "RES","I123": #LOCATION = "R1W18" !CDS_LOCATION = "R1W18" #SEC = "1" !CDS_SEC = "1";
"A":   PN = "1"  !CDS_PN = "1";
"B":   PN = "2"  !CDS_PN = "2";
DRAWING = "@baseboard_fab2_lib.baseboard_fab2(sch_1):page116";
BODY = "RES","I108": #LOCATION = "R3M11" !CDS_LOCATION = "R3M11" #SEC = "1" !CDS_SEC = "1";
"A":   PN = "1"  !CDS_PN = "1";
"B":   PN = "2"  !CDS_PN = "2";
BODY = "RES","I181": #LOCATION = "R3M12" !CDS_LOCATION = "R3M12" #SEC = "1" !CDS_SEC = "1";
"A":   PN = "1"  !CDS_PN = "1";
"B":   PN = "2"  !CDS_PN = "2";
BODY = "LBG_CORE_QAT_EXT_D","I220": #LOCATION = "U7C1" !CDS_LOCATION = "U7C1" #SEC = "3" !CDS_SEC = "3";
"EXTCLKN":   PN = "D66"  !CDS_PN = "D66";
"EXTCLKP":   PN = "E67"  !CDS_PN = "E67";
"PCIE4_GBE_RXN":   PN = "AN70"  !CDS_PN = "AN70";
"PCIE4_GBE_RXP":   PN = "AN72"  !CDS_PN = "AN72";
"PCIE4_GBE_TXN":   PN = "BG66"  !CDS_PN = "BG66";
"PCIE4_GBE_TXP":   PN = "BJ66"  !CDS_PN = "BJ66";
"PCIE5_GBE_RXN":   PN = "AM69"  !CDS_PN = "AM69";
"PCIE5_GBE_RXP":   PN = "AM71"  !CDS_PN = "AM71";
"PCIE5_GBE_TXN":   PN = "BH65"  !CDS_PN = "BH65";
"PCIE5_GBE_TXP":   PN = "BJ63"  !CDS_PN = "BJ63";
"PCIE6_SSATA0_RXN":   PN = "BB63"  !CDS_PN = "BB63";
"PCIE6_SSATA0_RXP":   PN = "BD61"  !CDS_PN = "BD61";
"PCIE6_SSATA0_TXN":   PN = "AJ70"  !CDS_PN = "AJ70";
"PCIE6_SSATA0_TXP":   PN = "AJ72"  !CDS_PN = "AJ72";
"PCIE7_SSATA1_RXN":   PN = "AY59"  !CDS_PN = "AY59";
"PCIE7_SSATA1_RXP":   PN = "BA61"  !CDS_PN = "BA61";
"PCIE7_SSATA1_TXN":   PN = "AH69"  !CDS_PN = "AH69";
"PCIE7_SSATA1_TXP":   PN = "AH71"  !CDS_PN = "AH71";
"PCIE8_SSATA2_GBE_RXN":   PN = "BA65"  !CDS_PN = "BA65";
"PCIE8_SSATA2_GBE_RXP":   PN = "BD65"  !CDS_PN = "BD65";
"PCIE8_SSATA2_GBE_TXN":   PN = "AF70"  !CDS_PN = "AF70";
"PCIE8_SSATA2_GBE_TXP":   PN = "AF72"  !CDS_PN = "AF72";
"PCIE9_SSATA3_RXN":   PN = "AW65"  !CDS_PN = "AW65";
"PCIE9_SSATA3_RXP":   PN = "AY66"  !CDS_PN = "AY66";
"PCIE9_SSATA3_TXN":   PN = "AE69"  !CDS_PN = "AE69";
"PCIE9_SSATA3_TXP":   PN = "AE71"  !CDS_PN = "AE71";
"PCIE10_SSATA4_RXN":   PN = "AV63"  !CDS_PN = "AV63";
"PCIE10_SSATA4_RXP":   PN = "AU65"  !CDS_PN = "AU65";
"PCIE10_SSATA4_TXN":   PN = "AD70"  !CDS_PN = "AD70";
"PCIE10_SSATA4_TXP":   PN = "AD72"  !CDS_PN = "AD72";
"PCIE11_SSATA5_GBE_RXN":   PN = "AT66"  !CDS_PN = "AT66";
"PCIE11_SSATA5_GBE_RXP":   PN = "AV66"  !CDS_PN = "AV66";
"PCIE11_SSATA5_GBE_TXN":   PN = "AC69"  !CDS_PN = "AC69";
"PCIE11_SSATA5_GBE_TXP":   PN = "AC71"  !CDS_PN = "AC71";
"PCIE12_UP0_SATA0_RXN":   PN = "AR61"  !CDS_PN = "AR61";
"PCIE12_UP0_SATA0_RXP":   PN = "AT63"  !CDS_PN = "AT63";
"PCIE12_UP0_SATA0_TXN":   PN = "W69"  !CDS_PN = "W69";
"PCIE12_UP0_SATA0_TXP":   PN = "W71"  !CDS_PN = "W71";
"PCIE13_UP1_SATA1_RXN":   PN = "AL66"  !CDS_PN = "AL66";
"PCIE13_UP1_SATA1_RXP":   PN = "AN65"  !CDS_PN = "AN65";
"PCIE13_UP1_SATA1_TXN":   PN = "V70"  !CDS_PN = "V70";
"PCIE13_UP1_SATA1_TXP":   PN = "V72"  !CDS_PN = "V72";
"PCIE14_UP2_SATA2_RXN":   PN = "AK65"  !CDS_PN = "AK65";
"PCIE14_UP2_SATA2_RXP":   PN = "AJ63"  !CDS_PN = "AJ63";
"PCIE14_UP2_SATA2_TXN":   PN = "T69"  !CDS_PN = "T69";
"PCIE14_UP2_SATA2_TXP":   PN = "T71"  !CDS_PN = "T71";
"PCIE15_UP3_SATA3_RXN":   PN = "AP63"  !CDS_PN = "AP63";
"PCIE15_UP3_SATA3_RXP":   PN = "AL63"  !CDS_PN = "AL63";
"PCIE15_UP3_SATA3_TXN":   PN = "R70"  !CDS_PN = "R70";
"PCIE15_UP3_SATA3_TXP":   PN = "R72"  !CDS_PN = "R72";
"PCIE16_UP4_SATA4_RXN":   PN = "AF65"  !CDS_PN = "AF65";
"PCIE16_UP4_SATA4_RXP":   PN = "AH65"  !CDS_PN = "AH65";
"PCIE16_UP4_SATA4_TXN":   PN = "P69"  !CDS_PN = "P69";
"PCIE16_UP4_SATA4_TXP":   PN = "P71"  !CDS_PN = "P71";
"PCIE17_UP5_SATA5_RXN":   PN = "AH61"  !CDS_PN = "AH61";
"PCIE17_UP5_SATA5_RXP":   PN = "AG63"  !CDS_PN = "AG63";
"PCIE17_UP5_SATA5_TXN":   PN = "N70"  !CDS_PN = "N70";
"PCIE17_UP5_SATA5_TXP":   PN = "N72"  !CDS_PN = "N72";
"PCIE18_UP6_SATA6_RXN":   PN = "AP59"  !CDS_PN = "AP59";
"PCIE18_UP6_SATA6_RXP":   PN = "AN61"  !CDS_PN = "AN61";
"PCIE18_UP6_SATA6_TXN":   PN = "M69"  !CDS_PN = "M69";
"PCIE18_UP6_SATA6_TXP":   PN = "M71"  !CDS_PN = "M71";
"PCIE19_UP7_SATA7_RXN":   PN = "AA61"  !CDS_PN = "AA61";
"PCIE19_UP7_SATA7_RXP":   PN = "AD61"  !CDS_PN = "AD61";
"PCIE19_UP7_SATA7_TXN":   PN = "L70"  !CDS_PN = "L70";
"PCIE19_UP7_SATA7_TXP":   PN = "L72"  !CDS_PN = "L72";
"PCIE_RCOMPN":   PN = "BD58"  !CDS_PN = "BD58";
"PCIE_RCOMPP":   PN = "BB56"  !CDS_PN = "BB56";
"PCIEUP_RCOMPN":   PN = "AF58"  !CDS_PN = "AF58";
"PCIEUP_RCOMPP":   PN = "AH58"  !CDS_PN = "AH58";
"RSVD<47>":   PN = "AP69"  !CDS_PN = "AP69";
"RSVD<48>":   PN = "AP71"  !CDS_PN = "AP71";
"RSVD<49>":   PN = "G67"  !CDS_PN = "G67";
"RSVD<50>":   PN = "H69"  !CDS_PN = "H69";
"RSVD<51>":   PN = "AA69"  !CDS_PN = "AA69";
"RSVD<52>":   PN = "AA71"  !CDS_PN = "AA71";
"USB3_7_PCIE0_RXN":   PN = "BA71"  !CDS_PN = "BA71";
"USB3_7_PCIE0_RXP":   PN = "BA69"  !CDS_PN = "BA69";
"USB3_7_PCIE0_TXN":   PN = "BR61"  !CDS_PN = "BR61";
"USB3_7_PCIE0_TXP":   PN = "BN63"  !CDS_PN = "BN63";
"USB3_8_PCIE1_RXN":   PN = "AY72"  !CDS_PN = "AY72";
"USB3_8_PCIE1_RXP":   PN = "AY70"  !CDS_PN = "AY70";
"USB3_8_PCIE1_TXN":   PN = "BM65"  !CDS_PN = "BM65";
"USB3_8_PCIE1_TXP":   PN = "BR65"  !CDS_PN = "BR65";
"USB3_9_PCIE2_RXN":   PN = "AW71"  !CDS_PN = "AW71";
"USB3_9_PCIE2_RXP":   PN = "AW69"  !CDS_PN = "AW69";
"USB3_9_PCIE2_TXN":   PN = "BK65"  !CDS_PN = "BK65";
"USB3_9_PCIE2_TXP":   PN = "BL66"  !CDS_PN = "BL66";
"USB3_10_PCIE3_GBE_RXN":   PN = "AV72"  !CDS_PN = "AV72";
"USB3_10_PCIE3_GBE_RXP":   PN = "AV70"  !CDS_PN = "AV70";
"USB3_10_PCIE3_GBE_TXN":   PN = "BH61"  !CDS_PN = "BH61";
"USB3_10_PCIE3_GBE_TXP":   PN = "BK61"  !CDS_PN = "BK61";
BODY = "RES","I229": #LOCATION = "R7B8" !CDS_LOCATION = "R7B8" #SEC = "1" !CDS_SEC = "1";
"A":   PN = "1"  !CDS_PN = "1";
"B":   PN = "2"  !CDS_PN = "2";
BODY = "RES","I230": #LOCATION = "R7B7" !CDS_LOCATION = "R7B7" #SEC = "1" !CDS_SEC = "1";
"A":   PN = "1"  !CDS_PN = "1";
"B":   PN = "2"  !CDS_PN = "2";
BODY = "RES","I234": #LOCATION = "R3M9" !CDS_LOCATION = "R3M9" &SEC = "1" #&CDS_SEC = "1";
"A":   PN = "1"  !CDS_PN = "1";
"B":   PN = "2"  !CDS_PN = "2";
BODY = "RES","I235": #LOCATION = "R3M8" !CDS_LOCATION = "R3M8" &SEC = "1" #&CDS_SEC = "1";
"A":   PN = "1"  !CDS_PN = "1";
"B":   PN = "2"  !CDS_PN = "2";
BODY = "CAP_A","I238": #LOCATION = "C2M4" !CDS_LOCATION = "C2M4" #SEC = "1" !CDS_SEC = "1";
"A":   PN = "1"  !CDS_PN = "1";
"B":   PN = "2"  !CDS_PN = "2";
BODY = "CAP_A","I239": #LOCATION = "C2M3" !CDS_LOCATION = "C2M3" #SEC = "1" !CDS_SEC = "1";
"A":   PN = "1"  !CDS_PN = "1";
"B":   PN = "2"  !CDS_PN = "2";
DRAWING = "@baseboard_fab2_lib.baseboard_fab2(sch_1):page117";
BODY = "LBG_CORE_QAT_EXT_D","I9": #LOCATION = "U7C1" !CDS_LOCATION = "U7C1" #SEC = "4" !CDS_SEC = "4";
"DMI_RXN<0>":   PN = "D42"  !CDS_PN = "D42";
"DMI_RXN<1>":   PN = "C43"  !CDS_PN = "C43";
"DMI_RXN<2>":   PN = "D44"  !CDS_PN = "D44";
"DMI_RXN<3>":   PN = "C45"  !CDS_PN = "C45";
"DMI_RXP<0>":   PN = "B42"  !CDS_PN = "B42";
"DMI_RXP<1>":   PN = "A43"  !CDS_PN = "A43";
"DMI_RXP<2>":   PN = "B44"  !CDS_PN = "B44";
"DMI_RXP<3>":   PN = "A45"  !CDS_PN = "A45";
"DMI_TXN<0>":   PN = "H46"  !CDS_PN = "H46";
"DMI_TXN<1>":   PN = "J48"  !CDS_PN = "J48";
"DMI_TXN<2>":   PN = "K50"  !CDS_PN = "K50";
"DMI_TXN<3>":   PN = "P52"  !CDS_PN = "P52";
"DMI_TXP<0>":   PN = "K46"  !CDS_PN = "K46";
"DMI_TXP<1>":   PN = "H50"  !CDS_PN = "H50";
"DMI_TXP<2>":   PN = "M52"  !CDS_PN = "M52";
"DMI_TXP<3>":   PN = "N54"  !CDS_PN = "N54";
"PCIEUP_0_RXN":   PN = "C48"  !CDS_PN = "C48";
"PCIEUP_0_RXP":   PN = "A48"  !CDS_PN = "A48";
"PCIEUP_0_TXN":   PN = "J52"  !CDS_PN = "J52";
"PCIEUP_0_TXP":   PN = "G52"  !CDS_PN = "G52";
"PCIEUP_1_RXN":   PN = "D49"  !CDS_PN = "D49";
"PCIEUP_1_RXP":   PN = "B49"  !CDS_PN = "B49";
"PCIEUP_1_TXN":   PN = "P56"  !CDS_PN = "P56";
"PCIEUP_1_TXP":   PN = "M56"  !CDS_PN = "M56";
"PCIEUP_2_RXN":   PN = "C50"  !CDS_PN = "C50";
"PCIEUP_2_RXP":   PN = "A50"  !CDS_PN = "A50";
"PCIEUP_2_TXN":   PN = "H54"  !CDS_PN = "H54";
"PCIEUP_2_TXP":   PN = "G56"  !CDS_PN = "G56";
"PCIEUP_3_RXN":   PN = "D51"  !CDS_PN = "D51";
"PCIEUP_3_RXP":   PN = "B51"  !CDS_PN = "B51";
"PCIEUP_3_TXN":   PN = "J56"  !CDS_PN = "J56";
"PCIEUP_3_TXP":   PN = "K58"  !CDS_PN = "K58";
"PCIEUP_4_RXN":   PN = "C52"  !CDS_PN = "C52";
"PCIEUP_4_RXP":   PN = "A52"  !CDS_PN = "A52";
"PCIEUP_4_TXN":   PN = "N58"  !CDS_PN = "N58";
"PCIEUP_4_TXP":   PN = "M59"  !CDS_PN = "M59";
"PCIEUP_5_RXN":   PN = "D53"  !CDS_PN = "D53";
"PCIEUP_5_RXP":   PN = "B53"  !CDS_PN = "B53";
"PCIEUP_5_TXN":   PN = "N61"  !CDS_PN = "N61";
"PCIEUP_5_TXP":   PN = "K61"  !CDS_PN = "K61";
"PCIEUP_6_RXN":   PN = "C54"  !CDS_PN = "C54";
"PCIEUP_6_RXP":   PN = "A54"  !CDS_PN = "A54";
"PCIEUP_6_TXN":   PN = "H61"  !CDS_PN = "H61";
"PCIEUP_6_TXP":   PN = "J63"  !CDS_PN = "J63";
"PCIEUP_7_RXN":   PN = "D55"  !CDS_PN = "D55";
"PCIEUP_7_RXP":   PN = "B55"  !CDS_PN = "B55";
"PCIEUP_7_TXN":   PN = "P59"  !CDS_PN = "P59";
"PCIEUP_7_TXP":   PN = "R61"  !CDS_PN = "R61";
"PCIEUP_8_RXN":   PN = "C57"  !CDS_PN = "C57";
"PCIEUP_8_RXP":   PN = "A57"  !CDS_PN = "A57";
"PCIEUP_8_TXN":   PN = "K65"  !CDS_PN = "K65";
"PCIEUP_8_TXP":   PN = "M63"  !CDS_PN = "M63";
"PCIEUP_9_RXN":   PN = "D58"  !CDS_PN = "D58";
"PCIEUP_9_RXP":   PN = "B58"  !CDS_PN = "B58";
"PCIEUP_9_TXN":   PN = "J66"  !CDS_PN = "J66";
"PCIEUP_9_TXP":   PN = "M66"  !CDS_PN = "M66";
"PCIEUP_10_RXN":   PN = "C59"  !CDS_PN = "C59";
"PCIEUP_10_RXP":   PN = "A59"  !CDS_PN = "A59";
"PCIEUP_10_TXN":   PN = "N65"  !CDS_PN = "N65";
"PCIEUP_10_TXP":   PN = "P66"  !CDS_PN = "P66";
"PCIEUP_11_RXN":   PN = "D60"  !CDS_PN = "D60";
"PCIEUP_11_RXP":   PN = "B60"  !CDS_PN = "B60";
"PCIEUP_11_TXN":   PN = "T59"  !CDS_PN = "T59";
"PCIEUP_11_TXP":   PN = "V59"  !CDS_PN = "V59";
"PCIEUP_12_RXN":   PN = "C61"  !CDS_PN = "C61";
"PCIEUP_12_RXP":   PN = "A61"  !CDS_PN = "A61";
"PCIEUP_12_TXN":   PN = "R65"  !CDS_PN = "R65";
"PCIEUP_12_TXP":   PN = "U65"  !CDS_PN = "U65";
"PCIEUP_13_RXN":   PN = "D62"  !CDS_PN = "D62";
"PCIEUP_13_RXP":   PN = "B62"  !CDS_PN = "B62";
"PCIEUP_13_TXN":   PN = "T63"  !CDS_PN = "T63";
"PCIEUP_13_TXP":   PN = "U61"  !CDS_PN = "U61";
"PCIEUP_14_RXN":   PN = "C63"  !CDS_PN = "C63";
"PCIEUP_14_RXP":   PN = "A63"  !CDS_PN = "A63";
"PCIEUP_14_TXN":   PN = "W65"  !CDS_PN = "W65";
"PCIEUP_14_TXP":   PN = "V63"  !CDS_PN = "V63";
"PCIEUP_15_RXN":   PN = "D64"  !CDS_PN = "D64";
"PCIEUP_15_RXP":   PN = "B64"  !CDS_PN = "B64";
"PCIEUP_15_TXN":   PN = "Y66"  !CDS_PN = "Y66";
"PCIEUP_15_TXP":   PN = "AA65"  !CDS_PN = "AA65";
DRAWING = "@baseboard_fab2_lib.baseboard_fab2(sch_1):page118";
BODY = "RES","I66": #LOCATION = "R3N9" !CDS_LOCATION = "R3N9" #SEC = "1" !CDS_SEC = "1";
"A":   PN = "1"  !CDS_PN = "1";
"B":   PN = "2"  !CDS_PN = "2";
BODY = "RES","I67": #LOCATION = "R3N14" !CDS_LOCATION = "R3N14" #SEC = "1" !CDS_SEC = "1";
"A":   PN = "1"  !CDS_PN = "1";
"B":   PN = "2"  !CDS_PN = "2";
BODY = "RES","I71": #LOCATION = "R3N13" !CDS_LOCATION = "R3N13" #SEC = "1" !CDS_SEC = "1";
"A":   PN = "1"  !CDS_PN = "1";
"B":   PN = "2"  !CDS_PN = "2";
BODY = "LBG_CORE_QAT_EXT_D","I73": #LOCATION = "U7C1" !CDS_LOCATION = "U7C1" #SEC = "5" !CDS_SEC = "5";
"CPU_TRST_N":   PN = "AT56"  !CDS_PN = "AT56";
"DSW_PWROK":   PN = "K13"  !CDS_PN = "K13";
"GPD0":   PN = "G15"  !CDS_PN = "G15";
"GPD1_ACPRESENT":   PN = "H13"  !CDS_PN = "H13";
"GPD2_GBE_WAKE_N":   PN = "M11"  !CDS_PN = "M11";
"GPD3_PWRBTN_N":   PN = "C15"  !CDS_PN = "C15";
"GPD4_SLP_S3_N":   PN = "D14"  !CDS_PN = "D14";
"GPD5_SLP_S4_N":   PN = "B16"  !CDS_PN = "B16";
"GPD6_SLP_A_N":   PN = "G11"  !CDS_PN = "G11";
"GPD7":   PN = "H9"  !CDS_PN = "H9";
"GPD8_SUSCLK":   PN = "C13"  !CDS_PN = "C13";
"GPD9":   PN = "A15"  !CDS_PN = "A15";
"GPD10_SLP_S5_N":   PN = "B14"  !CDS_PN = "B14";
"GPD11_GBEPHY":   PN = "A13"  !CDS_PN = "A13";
"ITP_PMODE":   PN = "AR54"  !CDS_PN = "AR54";
"JTAG_TCK":   PN = "AL56"  !CDS_PN = "AL56";
"JTAG_TDI":   PN = "AN54"  !CDS_PN = "AN54";
"JTAG_TDO":   PN = "AP56"  !CDS_PN = "AP56";
"JTAG_TMS":   PN = "AH54"  !CDS_PN = "AH54";
"JTAGX":   PN = "AF54"  !CDS_PN = "AF54";
"LAN_RBIAS_0":   PN = "BB29"  !CDS_PN = "BB29";
"LAN_RBIAS_1":   PN = "BD42"  !CDS_PN = "BD42";
"LAN_RX_P0N":   PN = "BH31"  !CDS_PN = "BH31";
"LAN_RX_P0P":   PN = "BF31"  !CDS_PN = "BF31";
"LAN_RX_P1N":   PN = "BG29"  !CDS_PN = "BG29";
"LAN_RX_P1P":   PN = "BJ29"  !CDS_PN = "BJ29";
"LAN_RX_P2N":   PN = "BJ37"  !CDS_PN = "BJ37";
"LAN_RX_P2P":   PN = "BG37"  !CDS_PN = "BG37";
"LAN_RX_P3N":   PN = "BF35"  !CDS_PN = "BF35";
"LAN_RX_P3P":   PN = "BH35"  !CDS_PN = "BH35";
"LAN_TX_P0N":   PN = "BM27"  !CDS_PN = "BM27";
"LAN_TX_P0P":   PN = "BR27"  !CDS_PN = "BR27";
"LAN_TX_P1N":   PN = "BM24"  !CDS_PN = "BM24";
"LAN_TX_P1P":   PN = "BR24"  !CDS_PN = "BR24";
"LAN_TX_P2N":   PN = "BM35"  !CDS_PN = "BM35";
"LAN_TX_P2P":   PN = "BR35"  !CDS_PN = "BR35";
"LAN_TX_P3N":   PN = "BR31"  !CDS_PN = "BR31";
"LAN_TX_P3P":   PN = "BM31"  !CDS_PN = "BM31";
"LAN_XTAL_IN":   PN = "BV16"  !CDS_PN = "BV16";
"LAN_XTAL_OUT":   PN = "BY16"  !CDS_PN = "BY16";
"PCH_PWROK":   PN = "R17"  !CDS_PN = "R17";
"PECI":   PN = "U9"  !CDS_PN = "U9";
"PLTRST_CPU_N":   PN = "U17"  !CDS_PN = "U17";
"PM_SYNC":   PN = "U13"  !CDS_PN = "U13";
"PM_SYNC2":   PN = "V7"  !CDS_PN = "V7";
"PRDY_N":   PN = "AD54"  !CDS_PN = "AD54";
"PREQ_N":   PN = "U54"  !CDS_PN = "U54";
"PROC_PWRGD":   PN = "R9"  !CDS_PN = "R9";
"RSMRST_N":   PN = "P15"  !CDS_PN = "P15";
"RSVD<32>":   PN = "AA54"  !CDS_PN = "AA54";
"RSVD<33>":   PN = "V56"  !CDS_PN = "V56";
"RSVD<34>":   PN = "Y56"  !CDS_PN = "Y56";
"RSVD<35>":   PN = "W54"  !CDS_PN = "W54";
"RSVD<36>":   PN = "AK54"  !CDS_PN = "AK54";
"RSVD<37>":   PN = "BN29"  !CDS_PN = "BN29";
"RSVD<38>":   PN = "BL29"  !CDS_PN = "BL29";
"RSVD<39>":   PN = "BL26"  !CDS_PN = "BL26";
"RSVD<40>":   PN = "BN26"  !CDS_PN = "BN26";
"RSVD<41>":   PN = "BJ40"  !CDS_PN = "BJ40";
"RSVD<42>":   PN = "BG40"  !CDS_PN = "BG40";
"RSVD<43>":   PN = "BL33"  !CDS_PN = "BL33";
"RSVD<44>":   PN = "BN33"  !CDS_PN = "BN33";
"RSVD<45>":   PN = "P22"  !CDS_PN = "P22";
"RSVD<53>":   PN = "P26"  !CDS_PN = "P26";
"RSVD<54>":   PN = "R24"  !CDS_PN = "R24";
"SLP_GBE_N":   PN = "M15"  !CDS_PN = "M15";
"SLP_SUS_N":   PN = "P7"  !CDS_PN = "P7";
"SYS_PWROK":   PN = "BY19"  !CDS_PN = "BY19";
"SYS_RESET_N":   PN = "BV19"  !CDS_PN = "BV19";
"THRMTRIP_N":   PN = "V15"  !CDS_PN = "V15";
"TRIGGER_IN":   PN = "M7"  !CDS_PN = "M7";
"TRIGGER_OUT":   PN = "R13"  !CDS_PN = "R13";
"WAKE_N":   PN = "K9"  !CDS_PN = "K9";
BODY = "CRYSTAL","I76": #LOCATION = "Y8C1" !CDS_LOCATION = "Y8C1" #SEC = "1" !CDS_SEC = "1";
"A":   PN = "1"  !CDS_PN = "1";
"B":   PN = "3"  !CDS_PN = "3";
BODY = "RES","I96": #LOCATION = "R2N4" !CDS_LOCATION = "R2N4" #SEC = "1" !CDS_SEC = "1";
"A":   PN = "1"  !CDS_PN = "1";
"B":   PN = "2"  !CDS_PN = "2";
BODY = "RES","I99": #LOCATION = "R2M6" !CDS_LOCATION = "R2M6" #SEC = "1" !CDS_SEC = "1";
"A":   PN = "1"  !CDS_PN = "1";
"B":   PN = "2"  !CDS_PN = "2";
BODY = "RES","I120": #LOCATION = "R8C24" !CDS_LOCATION = "R8C24" #SEC = "1" !CDS_SEC = "1";
"A":   PN = "1"  !CDS_PN = "1";
"B":   PN = "2"  !CDS_PN = "2";
BODY = "RES","I125": #LOCATION = "R8C23" !CDS_LOCATION = "R8C23" #SEC = "1" !CDS_SEC = "1";
"A":   PN = "1"  !CDS_PN = "1";
"B":   PN = "2"  !CDS_PN = "2";
BODY = "RES","I128": #LOCATION = "R2N6" !CDS_LOCATION = "R2N6" #SEC = "1" !CDS_SEC = "1";
"A":   PN = "1"  !CDS_PN = "1";
"B":   PN = "2"  !CDS_PN = "2";
BODY = "RES","I131": #LOCATION = "R7D23" !CDS_LOCATION = "R7D23" #SEC = "1" !CDS_SEC = "1";
"A":   PN = "1"  !CDS_PN = "1";
"B":   PN = "2"  !CDS_PN = "2";
BODY = "CAP_A","I136": #LOCATION = "C7D1" !CDS_LOCATION = "C7D1" #SEC = "1" !CDS_SEC = "1";
"A":   PN = "1"  !CDS_PN = "1";
"B":   PN = "2"  !CDS_PN = "2";
BODY = "74CBTLV1G125","I142": #LOCATION = "U7D1" !CDS_LOCATION = "U7D1" &SEC = "1" #&CDS_SEC = "1";
"A":   PN = "2"  !CDS_PN = "2";
"B":   PN = "4"  !CDS_PN = "4";
"OE_N":   PN = "1"  !CDS_PN = "1";
BODY = "RES","I144": #LOCATION = "R7C23" !CDS_LOCATION = "R7C23" #SEC = "1" !CDS_SEC = "1";
"A":   PN = "1"  !CDS_PN = "1";
"B":   PN = "2"  !CDS_PN = "2";
BODY = "RES","I167": #LOCATION = "R7W1" !CDS_LOCATION = "R7W1" #SEC = "1" !CDS_SEC = "1";
"A":   PN = "1"  !CDS_PN = "1";
"B":   PN = "2"  !CDS_PN = "2";
BODY = "RES","I168": #LOCATION = "R1W30" !CDS_LOCATION = "R1W30" #SEC = "1" !CDS_SEC = "1";
"A":   PN = "1"  !CDS_PN = "1";
"B":   PN = "2"  !CDS_PN = "2";
BODY = "RES","I176": #LOCATION = "R7W6" !CDS_LOCATION = "R7W6" #SEC = "1" !CDS_SEC = "1";
"A":   PN = "1"  !CDS_PN = "1";
"B":   PN = "2"  !CDS_PN = "2";
BODY = "RES","I177": #LOCATION = "R7W9" !CDS_LOCATION = "R7W9" #SEC = "1" !CDS_SEC = "1";
"A":   PN = "1"  !CDS_PN = "1";
"B":   PN = "2"  !CDS_PN = "2";
BODY = "CAP","I178": #LOCATION = "C8C1" !CDS_LOCATION = "C8C1" #SEC = "1" !CDS_SEC = "1";
"A":   PN = "1"  !CDS_PN = "1";
"B":   PN = "2"  !CDS_PN = "2";
BODY = "CAP","I179": #LOCATION = "C8C2" !CDS_LOCATION = "C8C2" #SEC = "1" !CDS_SEC = "1";
"A":   PN = "1"  !CDS_PN = "1";
"B":   PN = "2"  !CDS_PN = "2";
BODY = "RES","I180": #LOCATION = "R7W19" !CDS_LOCATION = "R7W19" #SEC = "1" !CDS_SEC = "1";
"A":   PN = "1"  !CDS_PN = "1";
"B":   PN = "2"  !CDS_PN = "2";
BODY = "RES","I183": #LOCATION = "R7W21" !CDS_LOCATION = "R7W21" #SEC = "1" !CDS_SEC = "1";
"A":   PN = "1"  !CDS_PN = "1";
"B":   PN = "2"  !CDS_PN = "2";
DRAWING = "@baseboard_fab2_lib.baseboard_fab2(sch_1):page119";
BODY = "LBG_CORE_QAT_EXT_D","I115": #LOCATION = "U7C1" !CDS_LOCATION = "U7C1" #SEC = "6" !CDS_SEC = "6";
"GPP_A0_RCIN_N_ESPI_ALERT1_N":   PN = "N3"  !CDS_PN = "N3";
"GPP_A1_LAD0_ESPI_IO0":   PN = "Y3"  !CDS_PN = "Y3";
"GPP_A2_LAD1_ESPI_IO1":   PN = "N1"  !CDS_PN = "N1";
"GPP_A3_LAD2_ESPI_IO2":   PN = "W2"  !CDS_PN = "W2";
"GPP_A4_LAD3_ESPI_IO3":   PN = "Y1"  !CDS_PN = "Y1";
"GPP_A5_LFRAME_N_ESPI_CS0_N":   PN = "P4"  !CDS_PN = "P4";
"GPP_A6_SERIRQ_ESPI_CS1_N":   PN = "P2"  !CDS_PN = "P2";
"GPP_A7_PIRQA_N_ESPI_ALERT0_N":   PN = "AA2"  !CDS_PN = "AA2";
"GPP_A8_CLKRUN_N":   PN = "AB1"  !CDS_PN = "AB1";
"GPP_A9_CLKOUT_LPC0_ESPI_CLK":   PN = "R3"  !CDS_PN = "R3";
"GPP_A10_CLKOUT_LPC1":   PN = "AA4"  !CDS_PN = "AA4";
"GPP_A11_PME_N":   PN = "AC2"  !CDS_PN = "AC2";
"GPP_A12_BMBUSY_N_SXEXITHLDOFF_N":   PN = "R1"  !CDS_PN = "R1";
"GPP_A13_SUSWARN_N_SUSPWRDNACK":   PN = "T4"  !CDS_PN = "T4";
"GPP_A14_ESPI_RESET_N":   PN = "AB3"  !CDS_PN = "AB3";
"GPP_A15_SUSACK_N":   PN = "AC4"  !CDS_PN = "AC4";
"GPP_A16_CLKOUT_LPC2":   PN = "T2"  !CDS_PN = "T2";
"GPP_A17":   PN = "AD1"  !CDS_PN = "AD1";
"GPP_A18":   PN = "AD3"  !CDS_PN = "AD3";
"GPP_A19":   PN = "V3"  !CDS_PN = "V3";
"GPP_A20":   PN = "W4"  !CDS_PN = "W4";
"GPP_A21":   PN = "AE2"  !CDS_PN = "AE2";
"GPP_A22":   PN = "AE4"  !CDS_PN = "AE4";
"GPP_A23":   PN = "V1"  !CDS_PN = "V1";
"GPP_B0_CORE_VID0":   PN = "BL7"  !CDS_PN = "BL7";
"GPP_B1_CORE_VID1":   PN = "BH9"  !CDS_PN = "BH9";
"GPP_B2":   PN = "BN15"  !CDS_PN = "BN15";
"GPP_B3_CPU_GP2":   PN = "BR9"  !CDS_PN = "BR9";
"GPP_B4_CPU_GP3":   PN = "BN7"  !CDS_PN = "BN7";
"GPP_B5_SRCCLKREQ0_N":   PN = "BK17"  !CDS_PN = "BK17";
"GPP_B6_SRCCLKREQ1_N":   PN = "BG18"  !CDS_PN = "BG18";
"GPP_B7_SRCCLKREQ2_N":   PN = "BR13"  !CDS_PN = "BR13";
"GPP_B8_SRCCLKREQ3_N":   PN = "BN11"  !CDS_PN = "BN11";
"GPP_B9_SRCCLKREQ4_N":   PN = "BH20"  !CDS_PN = "BH20";
"GPP_B10_SRCCLKREQ5_N":   PN = "BL11"  !CDS_PN = "BL11";
"GPP_B11":   PN = "BK9"  !CDS_PN = "BK9";
"GPP_B12_GLB_RST_WARN_N":   PN = "BL18"  !CDS_PN = "BL18";
"GPP_B13_PLTRST_N":   PN = "BN18"  !CDS_PN = "BN18";
"GPP_B14_SPKR":   PN = "BH13"  !CDS_PN = "BH13";
"GPP_B15":   PN = "BK13"  !CDS_PN = "BK13";
"GPP_B16":   PN = "BG22"  !CDS_PN = "BG22";
"GPP_B17":   PN = "BG15"  !CDS_PN = "BG15";
"GPP_B18":   PN = "BL15"  !CDS_PN = "BL15";
"GPP_B19":   PN = "BK20"  !CDS_PN = "BK20";
"GPP_B20":   PN = "BJ22"  !CDS_PN = "BJ22";
"GPP_B21":   PN = "BH17"  !CDS_PN = "BH17";
"GPP_B22":   PN = "BR17"  !CDS_PN = "BR17";
"GPP_B23_MEIE_SML1ALRT_N_PHOT_N":   PN = "BM20"  !CDS_PN = "BM20";
"GPP_C0_SMBCLK":   PN = "BW28"  !CDS_PN = "BW28";
"GPP_C1_SMBDATA":   PN = "BV27"  !CDS_PN = "BV27";
"GPP_C2_SMBALERT_N":   PN = "BY27"  !CDS_PN = "BY27";
"GPP_C3_SML0CLK_IE":   PN = "BV29"  !CDS_PN = "BV29";
"GPP_C4_SML0DATA_IE":   PN = "BW30"  !CDS_PN = "BW30";
"GPP_C5_SML0ALERT_IE_N":   PN = "BW34"  !CDS_PN = "BW34";
"GPP_C6_SML1CLK_IE":   PN = "CA28"  !CDS_PN = "CA28";
"GPP_C7_SML1DATA_IE":   PN = "BV35"  !CDS_PN = "BV35";
"GPP_C8":   PN = "BW32"  !CDS_PN = "BW32";
"GPP_C9":   PN = "BY29"  !CDS_PN = "BY29";
"GPP_C10":   PN = "BV31"  !CDS_PN = "BV31";
"GPP_C11":   PN = "BV33"  !CDS_PN = "BV33";
"GPP_C12":   PN = "CA30"  !CDS_PN = "CA30";
"GPP_C13":   PN = "BV38"  !CDS_PN = "BV38";
"GPP_C14":   PN = "BY38"  !CDS_PN = "BY38";
"GPP_C15":   PN = "CA32"  !CDS_PN = "CA32";
"GPP_C16":   PN = "BW37"  !CDS_PN = "BW37";
"GPP_C17":   PN = "BY31"  !CDS_PN = "BY31";
"GPP_C18":   PN = "BY35"  !CDS_PN = "BY35";
"GPP_C19":   PN = "BW39"  !CDS_PN = "BW39";
"GPP_C20":   PN = "CA39"  !CDS_PN = "CA39";
"GPP_C21":   PN = "BY33"  !CDS_PN = "BY33";
"GPP_C22":   PN = "CA34"  !CDS_PN = "CA34";
"GPP_C23":   PN = "CA37"  !CDS_PN = "CA37";
"GPP_D0":   PN = "BR42"  !CDS_PN = "BR42";
"GPP_D1":   PN = "BK46"  !CDS_PN = "BK46";
"GPP_D2":   PN = "BJ44"  !CDS_PN = "BJ44";
"GPP_D3":   PN = "BW45"  !CDS_PN = "BW45";
"GPP_D4":   PN = "BM42"  !CDS_PN = "BM42";
"GPP_D5":   PN = "BM38"  !CDS_PN = "BM38";
"GPP_D6":   PN = "BW41"  !CDS_PN = "BW41";
"GPP_D7":   PN = "CA45"  !CDS_PN = "CA45";
"GPP_D8":   PN = "BR38"  !CDS_PN = "BR38";
"GPP_D9_SSATA_DEVSLP3":   PN = "BY42"  !CDS_PN = "BY42";
"GPP_D10_SSATA_DEVSLP4":   PN = "BV47"  !CDS_PN = "BV47";
"GPP_D11_SSATA_DEVSLP5":   PN = "BY47"  !CDS_PN = "BY47";
"GPP_D12_SSATA_SDATAOUT1":   PN = "BN40"  !CDS_PN = "BN40";
"GPP_D13_SML0BCLK_IE":   PN = "BY44"  !CDS_PN = "BY44";
"GPP_D14_SML0BDATA_IE":   PN = "BL44"  !CDS_PN = "BL44";
"GPP_D15_SSATA_SDATAOUT0":   PN = "BW43"  !CDS_PN = "BW43";
"GPP_D16_SML0BALERT_IE_N":   PN = "BV42"  !CDS_PN = "BV42";
"GPP_D17":   PN = "BW48"  !CDS_PN = "BW48";
"GPP_D18":   PN = "CA41"  !CDS_PN = "CA41";
"GPP_D19":   PN = "CA43"  !CDS_PN = "CA43";
"GPP_D20":   PN = "CA48"  !CDS_PN = "CA48";
"GPP_D21_IE_UART_RX":   PN = "BV44"  !CDS_PN = "BV44";
"GPP_D22_IE_UART_TX":   PN = "BR46"  !CDS_PN = "BR46";
"GPP_D23":   PN = "BN44"  !CDS_PN = "BN44";
BODY = "RES","I172": #LOCATION = "R2M3" !CDS_LOCATION = "R2M3" #SEC = "1" !CDS_SEC = "1";
"A":   PN = "1"  !CDS_PN = "1";
"B":   PN = "2"  !CDS_PN = "2";
BODY = "RES","I173": #LOCATION = "R2N1" !CDS_LOCATION = "R2N1" #SEC = "1" !CDS_SEC = "1";
"A":   PN = "1"  !CDS_PN = "1";
"B":   PN = "2"  !CDS_PN = "2";
BODY = "RES","I174": #LOCATION = "R2M7" !CDS_LOCATION = "R2M7" #SEC = "1" !CDS_SEC = "1";
"A":   PN = "1"  !CDS_PN = "1";
"B":   PN = "2"  !CDS_PN = "2";
BODY = "FET_N_DUAL","I175": #LOCATION = "Q9A2" !CDS_LOCATION = "Q9A2" #SEC = "1" !CDS_SEC = "1";
"DRAIN<0>":   PN = "6"  !CDS_PN = "6";
"GATE<0>":   PN = "2"  !CDS_PN = "2";
"SOURCE<0>":   PN = "1"  !CDS_PN = "1";
BODY = "RES","I178": #LOCATION = "R9A20" !CDS_LOCATION = "R9A20" #SEC = "1" !CDS_SEC = "1";
"A":   PN = "1"  !CDS_PN = "1";
"B":   PN = "2"  !CDS_PN = "2";
BODY = "LED","I179": #LOCATION = "DS9A5" !CDS_LOCATION = "DS9A5" #SEC = "1" !CDS_SEC = "1";
"A":   PN = "1"  !CDS_PN = "1";
"C":   PN = "2"  !CDS_PN = "2";
BODY = "FET_N_DUAL","I180": #LOCATION = "Q9A2" !CDS_LOCATION = "Q9A2" #SEC = "2" !CDS_SEC = "2";
"DRAIN<0>":   PN = "3"  !CDS_PN = "3";
"GATE<0>":   PN = "5"  !CDS_PN = "5";
"SOURCE<0>":   PN = "4"  !CDS_PN = "4";
BODY = "RES","I183": #LOCATION = "R9A18" !CDS_LOCATION = "R9A18" #SEC = "1" !CDS_SEC = "1";
"A":   PN = "1"  !CDS_PN = "1";
"B":   PN = "2"  !CDS_PN = "2";
BODY = "RES","I186": #LOCATION = "R9A21" !CDS_LOCATION = "R9A21" #SEC = "1" !CDS_SEC = "1";
"A":   PN = "1"  !CDS_PN = "1";
"B":   PN = "2"  !CDS_PN = "2";
BODY = "RES","I189": #LOCATION = "R7C26" !CDS_LOCATION = "R7C26" #SEC = "1" !CDS_SEC = "1";
"A":   PN = "1"  !CDS_PN = "1";
"B":   PN = "2"  !CDS_PN = "2";
BODY = "RES","I213": #LOCATION = "R2U48" !CDS_LOCATION = "R2U48" #SEC = "1" !CDS_SEC = "1";
"A":   PN = "1"  !CDS_PN = "1";
"B":   PN = "2"  !CDS_PN = "2";
BODY = "RES","I223": #LOCATION = "R2W3" !CDS_LOCATION = "R2W3" #SEC = "1" !CDS_SEC = "1";
"A":   PN = "1"  !CDS_PN = "1";
"B":   PN = "2"  !CDS_PN = "2";
BODY = "RES","I224": #LOCATION = "R2W4" !CDS_LOCATION = "R2W4" #SEC = "1" !CDS_SEC = "1";
"A":   PN = "1"  !CDS_PN = "1";
"B":   PN = "2"  !CDS_PN = "2";
BODY = "RES","I226": #LOCATION = "R7W13" !CDS_LOCATION = "R7W13" #SEC = "1" !CDS_SEC = "1";
"A":   PN = "1"  !CDS_PN = "1";
"B":   PN = "2"  !CDS_PN = "2";
BODY = "RES","I227": #LOCATION = "R7W15" !CDS_LOCATION = "R7W15" #SEC = "1" !CDS_SEC = "1";
"A":   PN = "1"  !CDS_PN = "1";
"B":   PN = "2"  !CDS_PN = "2";
BODY = "RES","I228": #LOCATION = "R2U50" !CDS_LOCATION = "R2U50" #SEC = "1" !CDS_SEC = "1";
"A":   PN = "1"  !CDS_PN = "1";
"B":   PN = "2"  !CDS_PN = "2";
BODY = "RES","I229": #LOCATION = "R7W17" !CDS_LOCATION = "R7W17" #SEC = "1" !CDS_SEC = "1";
"A":   PN = "1"  !CDS_PN = "1";
"B":   PN = "2"  !CDS_PN = "2";
BODY = "RES","I230": #LOCATION = "R7W22" !CDS_LOCATION = "R7W22" #SEC = "1" !CDS_SEC = "1";
"A":   PN = "1"  !CDS_PN = "1";
"B":   PN = "2"  !CDS_PN = "2";
DRAWING = "@baseboard_fab2_lib.baseboard_fab2(sch_1):page120";
BODY = "LBG_CORE_QAT_EXT_D","I147": #LOCATION = "U7C1" !CDS_LOCATION = "U7C1" #SEC = "7" !CDS_SEC = "7";
"GPIO_RCOMP_3P3":   PN = "BY25"  !CDS_PN = "BY25";
"GPP_E0_SATAXPCIE0_SATAGP0":   PN = "BH50"  !CDS_PN = "BH50";
"GPP_E1_SATAXPCIE1_SATAGP1":   PN = "AY52"  !CDS_PN = "AY52";
"GPP_E2_SATAXPCIE2_SATAGP2":   PN = "BG52"  !CDS_PN = "BG52";
"GPP_E3_CPU_GP0":   PN = "BE52"  !CDS_PN = "BE52";
"GPP_E4_SATA_DEVSLP0":   PN = "AV52"  !CDS_PN = "AV52";
"GPP_E5_SATA_DEVSLP1":   PN = "AT52"  !CDS_PN = "AT52";
"GPP_E6_SATA_DEVSLP2":   PN = "BB52"  !CDS_PN = "BB52";
"GPP_E7_CPU_GP1":   PN = "BJ48"  !CDS_PN = "BJ48";
"GPP_E8_SATA_LED_N":   PN = "AV56"  !CDS_PN = "AV56";
"GPP_E9_USB2_OC0_N":   PN = "BL48"  !CDS_PN = "BL48";
"GPP_E10_USB2_OC1_N":   PN = "BN48"  !CDS_PN = "BN48";
"GPP_E11_USB2_OC2_N":   PN = "AW54"  !CDS_PN = "AW54";
"GPP_E12_USB2_OC3_N":   PN = "AU58"  !CDS_PN = "AU58";
"GPP_F0_SATAXPCIE3_SATAGP3":   PN = "AG7"  !CDS_PN = "AG7";
"GPP_F1_SATAXPCIE4_SATAGP4":   PN = "AK9"  !CDS_PN = "AK9";
"GPP_F2_SATAXPCIE5_SATAGP5":   PN = "AK20"  !CDS_PN = "AK20";
"GPP_F3_SATAXPCIE6_SATAGP6":   PN = "AK13"  !CDS_PN = "AK13";
"GPP_F4_SATAXPCIE7_SATAGP7":   PN = "AH13"  !CDS_PN = "AH13";
"GPP_F5_SATA_DEVSLP3":   PN = "AH17"  !CDS_PN = "AH17";
"GPP_F6_SATA_DEVSLP4":   PN = "AL18"  !CDS_PN = "AL18";
"GPP_F7_SATA_DEVSLP5":   PN = "AK17"  !CDS_PN = "AK17";
"GPP_F8_SATA_DEVSLP6":   PN = "AH9"  !CDS_PN = "AH9";
"GPP_F9_SATA_DEVSLP7":   PN = "AR20"  !CDS_PN = "AR20";
"GPP_F10_SATA_SCLOCK":   PN = "AL7"  !CDS_PN = "AL7";
"GPP_F11_SATA_SLOAD":   PN = "AR9"  !CDS_PN = "AR9";
"GPP_F12_SATA_SDATAOUT1":   PN = "AP7"  !CDS_PN = "AP7";
"GPP_F13_SATA_SDATAOUT0":   PN = "AP11"  !CDS_PN = "AP11";
"GPP_F14_SSATA_LED_N":   PN = "AL11"  !CDS_PN = "AL11";
"GPP_F15_USB2_OC4_N":   PN = "AR13"  !CDS_PN = "AR13";
"GPP_F16_USB2_OC5_N":   PN = "AU13"  !CDS_PN = "AU13";
"GPP_F17_USB2_OC6_N":   PN = "AP15"  !CDS_PN = "AP15";
"GPP_F18_USB2_OC7_N":   PN = "AL15"  !CDS_PN = "AL15";
"GPP_F19_LAN_SMBCLK":   PN = "AU9"  !CDS_PN = "AU9";
"GPP_F20_LAN_SMBDATA":   PN = "AU20"  !CDS_PN = "AU20";
"GPP_F21_LAN_SMBALRT_N":   PN = "AR17"  !CDS_PN = "AR17";
"GPP_F22_SSATA_SCLOCK":   PN = "AP18"  !CDS_PN = "AP18";
"GPP_F23_SSATA_SLOAD":   PN = "AU17"  !CDS_PN = "AU17";
"GPP_G0_FANTACH0_FANTACH0IE":   PN = "AY11"  !CDS_PN = "AY11";
"GPP_G1_FANTACH1_FANTACH1IE":   PN = "AV15"  !CDS_PN = "AV15";
"GPP_G2_FANTACH2_FANTACH2IE":   PN = "BE22"  !CDS_PN = "BE22";
"GPP_G3_FANTACH3_FANTACH3IE":   PN = "AY7"  !CDS_PN = "AY7";
"GPP_G4_FANTACH4_FANTACH4IE":   PN = "BA9"  !CDS_PN = "BA9";
"GPP_G5_FANTACH5_FANTACH5IE":   PN = "AW20"  !CDS_PN = "AW20";
"GPP_G6_FANTACH6_FANTACH6IE":   PN = "AV18"  !CDS_PN = "AV18";
"GPP_G7_FANTACH7_FANTACH7IE":   PN = "AY15"  !CDS_PN = "AY15";
"GPP_G8_FANPWM0_FANPWM0IE":   PN = "BG11"  !CDS_PN = "BG11";
"GPP_G9_FANPWM1_FAMPWM1IE":   PN = "AV11"  !CDS_PN = "AV11";
"GPP_G10_FANPWM2_FANPWM2IE":   PN = "BE11"  !CDS_PN = "BE11";
"GPP_G11_FANPWM3_FANPMW3IE":   PN = "BA20"  !CDS_PN = "BA20";
"GPP_G12":   PN = "BD13"  !CDS_PN = "BD13";
"GPP_G13":   PN = "AY18"  !CDS_PN = "AY18";
"GPP_G14":   PN = "AV7"  !CDS_PN = "AV7";
"GPP_G15":   PN = "BE18"  !CDS_PN = "BE18";
"GPP_G16":   PN = "BD17"  !CDS_PN = "BD17";
"GPP_G17_ADR_COMPLETE":   PN = "BD9"  !CDS_PN = "BD9";
"GPP_G18_NMI_N":   PN = "BE7"  !CDS_PN = "BE7";
"GPP_G19_SMI_N":   PN = "BE15"  !CDS_PN = "BE15";
"GPP_G20_SSATA_DEVSLP0":   PN = "BA17"  !CDS_PN = "BA17";
"GPP_G21_SSATA_DEVSLP1":   PN = "BG7"  !CDS_PN = "BG7";
"GPP_G22_SSATA_DEVSLP2":   PN = "BD20"  !CDS_PN = "BD20";
"GPP_G23_SSATAXPCIE0_SSATAGP0":   PN = "BA13"  !CDS_PN = "BA13";
"GPP_H0_SRCCLKREQ6_N":   PN = "AT4"  !CDS_PN = "AT4";
"GPP_H1_SRCCLKREQ7_N":   PN = "AW4"  !CDS_PN = "AW4";
"GPP_H2_SRCCLKREQ8_N":   PN = "AV3"  !CDS_PN = "AV3";
"GPP_H3_SRCCLKREQ9_N":   PN = "AR1"  !CDS_PN = "AR1";
"GPP_H4_SRCCLKREQ10_N":   PN = "AT2"  !CDS_PN = "AT2";
"GPP_H5_SRCCLKREQ11_N":   PN = "AY3"  !CDS_PN = "AY3";
"GPP_H6_SRCCLKREQ12_N":   PN = "AW2"  !CDS_PN = "AW2";
"GPP_H7_SRCCLKREQ13_N":   PN = "AV1"  !CDS_PN = "AV1";
"GPP_H8_SRCCLKREQ14_N":   PN = "AR3"  !CDS_PN = "AR3";
"GPP_H9_SRCCLKREQ15_N":   PN = "BE2"  !CDS_PN = "BE2";
"GPP_H10_SML2CLK_IE":   PN = "BA4"  !CDS_PN = "BA4";
"GPP_H11_SML2DATA_IE":   PN = "BD1"  !CDS_PN = "BD1";
"GPP_H12_SML2ALERT_N_IE_N":   PN = "BB1"  !CDS_PN = "BB1";
"GPP_H13_SML3CLK_IE":   PN = "AY1"  !CDS_PN = "AY1";
"GPP_H14_SML3DATA_IE":   PN = "BC2"  !CDS_PN = "BC2";
"GPP_H15_SML3ALERT_N_IE_N":   PN = "BB3"  !CDS_PN = "BB3";
"GPP_H16_SML4CLK_IE":   PN = "BF1"  !CDS_PN = "BF1";
"GPP_H17_SML4DATA_IE":   PN = "BE4"  !CDS_PN = "BE4";
"GPP_H18_SML4ALERT_N_IE_N":   PN = "BC4"  !CDS_PN = "BC4";
"GPP_H19_SSATAXPCIE1_SSATAGP1":   PN = "BD3"  !CDS_PN = "BD3";
"GPP_H20_SSATAXPCIE2_SSATAGP2":   PN = "BF3"  !CDS_PN = "BF3";
"GPP_H21_SSATAXPCIE3_SSATAGP3":   PN = "BA2"  !CDS_PN = "BA2";
"GPP_H22_SSATAXPCIE4_SSATAGP4":   PN = "BH2"  !CDS_PN = "BH2";
"GPP_H23_SSATAXPCIE5_SSATAGP5":   PN = "BH4"  !CDS_PN = "BH4";
"GPP_I0_LAN_TDO":   PN = "CA20"  !CDS_PN = "CA20";
"GPP_I1_LAN_TCK":   PN = "BV21"  !CDS_PN = "BV21";
"GPP_I2_LAN_TMS":   PN = "CA22"  !CDS_PN = "CA22";
"GPP_I3_LAN_TDI":   PN = "BY23"  !CDS_PN = "BY23";
"GPP_I4_DO_RESET_IN_N":   PN = "BW20"  !CDS_PN = "BW20";
"GPP_I5_DO_RESET_OUT_N":   PN = "BW24"  !CDS_PN = "BW24";
"GPP_I6_RESET_DONE":   PN = "BV23"  !CDS_PN = "BV23";
"GPP_I7_LAN_TRST_N":   PN = "CA24"  !CDS_PN = "CA24";
"GPP_I8_PCI_DIS_N":   PN = "BW22"  !CDS_PN = "BW22";
"GPP_I9_LAN_DIS_N":   PN = "BY21"  !CDS_PN = "BY21";
"GPP_I10":   PN = "BV25"  !CDS_PN = "BV25";
"GPP_J0_LAN_LED_P0_0":   PN = "BL1"  !CDS_PN = "BL1";
"GPP_J1_LAN_LED_P0_1":   PN = "BK4"  !CDS_PN = "BK4";
"GPP_J2_LAN_LED_P1_0":   PN = "BP4"  !CDS_PN = "BP4";
"GPP_J3_LAN_LED_P1_1":   PN = "BK2"  !CDS_PN = "BK2";
"GPP_J4_LAN_LED_P2_0":   PN = "BL3"  !CDS_PN = "BL3";
"GPP_J5_LAN_LED_P2_1":   PN = "BU6"  !CDS_PN = "BU6";
"GPP_J6_LAN_LED_P3_0":   PN = "CA13"  !CDS_PN = "CA13";
"GPP_J7_LAN_LED_P3_1":   PN = "BM2"  !CDS_PN = "BM2";
"GPP_J8_LAN_I2C_SCL_MDC_P0":   PN = "BM4"  !CDS_PN = "BM4";
"GPP_J9_LAN_I2C_SDA_MDIO_P0":   PN = "BN3"  !CDS_PN = "BN3";
"GPP_J10_LAN_I2C_SCL_MDC_P1":   PN = "BW5"  !CDS_PN = "BW5";
"GPP_J11_LAN_I2C_SDA_MDIO_P1":   PN = "BV8"  !CDS_PN = "BV8";
"GPP_J12_LAN_I2C_SCL_MDC_P2":   PN = "BT5"  !CDS_PN = "BT5";
"GPP_J13_LAN_I2C_SDA_MDIO_P2":   PN = "BW11"  !CDS_PN = "BW11";
"GPP_J14_LAN_I2C_SCL_MDC_P3":   PN = "BW6"  !CDS_PN = "BW6";
"GPP_J15_LAN_I2C_SDA_MDIO_P3":   PN = "BW9"  !CDS_PN = "BW9";
"GPP_J16_LAN_SDP_P0_0":   PN = "BV10"  !CDS_PN = "BV10";
"GPP_J17_LAN_SDP_P0_1":   PN = "CA11"  !CDS_PN = "CA11";
"GPP_J18_LAN_SDP_P1_0":   PN = "BY10"  !CDS_PN = "BY10";
"GPP_J19_LAN_SDP_P1_1":   PN = "BY14"  !CDS_PN = "BY14";
"GPP_J20_LAN_SDP_P2_0":   PN = "BW13"  !CDS_PN = "BW13";
"GPP_J21_LAN_SDP_P2_1":   PN = "BV12"  !CDS_PN = "BV12";
"GPP_J22_LAN_SDP_P3_0":   PN = "BY12"  !CDS_PN = "BY12";
"GPP_J23_LAN_SDP_P3_1":   PN = "BV14"  !CDS_PN = "BV14";
BODY = "RES","I218": #LOCATION = "R2M1" !CDS_LOCATION = "R2M1" #SEC = "1" !CDS_SEC = "1";
"A":   PN = "1"  !CDS_PN = "1";
"B":   PN = "2"  !CDS_PN = "2";
BODY = "RES","I219": #LOCATION = "R2N26" !CDS_LOCATION = "R2N26" #SEC = "1" !CDS_SEC = "1";
"A":   PN = "1"  !CDS_PN = "1";
"B":   PN = "2"  !CDS_PN = "2";
BODY = "RES","I269": #LOCATION = "R7W8" !CDS_LOCATION = "R7W8" #SEC = "1" !CDS_SEC = "1";
"A":   PN = "1"  !CDS_PN = "1";
"B":   PN = "2"  !CDS_PN = "2";
BODY = "RES","I270": #LOCATION = "R7W10" !CDS_LOCATION = "R7W10" #SEC = "1" !CDS_SEC = "1";
"A":   PN = "1"  !CDS_PN = "1";
"B":   PN = "2"  !CDS_PN = "2";
BODY = "RES","I271": #LOCATION = "R7W12" !CDS_LOCATION = "R7W12" #SEC = "1" !CDS_SEC = "1";
"A":   PN = "1"  !CDS_PN = "1";
"B":   PN = "2"  !CDS_PN = "2";
BODY = "RES","I273": #LOCATION = "R7W11" !CDS_LOCATION = "R7W11" #SEC = "1" !CDS_SEC = "1";
"A":   PN = "1"  !CDS_PN = "1";
"B":   PN = "2"  !CDS_PN = "2";
BODY = "RES","I274": #LOCATION = "R7W14" !CDS_LOCATION = "R7W14" #SEC = "1" !CDS_SEC = "1";
"A":   PN = "1"  !CDS_PN = "1";
"B":   PN = "2"  !CDS_PN = "2";
BODY = "RES","I275": #LOCATION = "R8C21" !CDS_LOCATION = "R8C21" #SEC = "1" !CDS_SEC = "1";
"A":   PN = "1"  !CDS_PN = "1";
"B":   PN = "2"  !CDS_PN = "2";
BODY = "RES","I276": #LOCATION = "R7W16" !CDS_LOCATION = "R7W16" #SEC = "1" !CDS_SEC = "1";
"A":   PN = "1"  !CDS_PN = "1";
"B":   PN = "2"  !CDS_PN = "2";
BODY = "RES","I277": #LOCATION = "R7W18" !CDS_LOCATION = "R7W18" #SEC = "1" !CDS_SEC = "1";
"A":   PN = "1"  !CDS_PN = "1";
"B":   PN = "2"  !CDS_PN = "2";
BODY = "RES","I278": #LOCATION = "R7W20" !CDS_LOCATION = "R7W20" #SEC = "1" !CDS_SEC = "1";
"A":   PN = "1"  !CDS_PN = "1";
"B":   PN = "2"  !CDS_PN = "2";
DRAWING = "@baseboard_fab2_lib.baseboard_fab2(sch_1):page121";
BODY = "RES","I31": #LOCATION = "R7C15" !CDS_LOCATION = "R7C15" &SEC = "1" #&CDS_SEC = "1";
"A":   PN = "1"  !CDS_PN = "1";
"B":   PN = "2"  !CDS_PN = "2";
BODY = "RES","I33": #LOCATION = "R7C16" !CDS_LOCATION = "R7C16" &SEC = "1" #&CDS_SEC = "1";
"A":   PN = "1"  !CDS_PN = "1";
"B":   PN = "2"  !CDS_PN = "2";
BODY = "LBG_CORE_QAT_EXT_D","I34": #LOCATION = "U7C1" !CDS_LOCATION = "U7C1" #SEC = "8" !CDS_SEC = "8";
"CGC_DUT_DETECT_N":   PN = "C70"  !CDS_PN = "C70";
"GPIO_RCOMP_1P8_3P3":   PN = "AM4"  !CDS_PN = "AM4";
"GPP_K0_LAN_NCSI_CLK_IN":   PN = "AJ1"  !CDS_PN = "AJ1";
"GPP_K1_LAN_NCSI_TXD0":   PN = "AM2"  !CDS_PN = "AM2";
"GPP_K2_LAN_NCSI_TXD1":   PN = "AK2"  !CDS_PN = "AK2";
"GPP_K3_LAN_NCSI_TX_EN":   PN = "AL3"  !CDS_PN = "AL3";
"GPP_K4_LAN_NCSI_CRS_DV":   PN = "AN3"  !CDS_PN = "AN3";
"GPP_K5_LAN_NCSI_RXD0":   PN = "AL1"  !CDS_PN = "AL1";
"GPP_K6_LAN_NCSI_RXD1":   PN = "AN1"  !CDS_PN = "AN1";
"GPP_K7":   PN = "AH2"  !CDS_PN = "AH2";
"GPP_K8_LAN_NCSI_ARB_IN":   PN = "AJ3"  !CDS_PN = "AJ3";
"GPP_K9_LAN_NCSI_ARB_OUT":   PN = "AK4"  !CDS_PN = "AK4";
"GPP_K10_PE_RST_N":   PN = "AH4"  !CDS_PN = "AH4";
"GPP_L2_TESTCH0_D0":   PN = "AE18"  !CDS_PN = "AE18";
"GPP_L3_TESTCH0_D1":   PN = "AE15"  !CDS_PN = "AE15";
"GPP_L4_TESTCH0_D2":   PN = "AE11"  !CDS_PN = "AE11";
"GPP_L5_TESTCH0_D3":   PN = "Y18"  !CDS_PN = "Y18";
"GPP_L6_TESTCH0_D4":   PN = "AA20"  !CDS_PN = "AA20";
"GPP_L7_TESTCH0_D5":   PN = "AA17"  !CDS_PN = "AA17";
"GPP_L8_TESTCH0_D6":   PN = "AD9"  !CDS_PN = "AD9";
"GPP_L9_TESTCH0_D7":   PN = "AD17"  !CDS_PN = "AD17";
"GPP_L10_TESTCH0_CLK":   PN = "AF20"  !CDS_PN = "AF20";
"GPP_L11_TESTCH1_D0":   PN = "AD20"  !CDS_PN = "AD20";
"GPP_L12_TESTCH1_D1":   PN = "Y15"  !CDS_PN = "Y15";
"GPP_L13_TESTCH1_D2":   PN = "AD13"  !CDS_PN = "AD13";
"GPP_L14_TESTCH1_D3":   PN = "AA13"  !CDS_PN = "AA13";
"GPP_L15_TESTCH1_D4":   PN = "Y11"  !CDS_PN = "Y11";
"GPP_L16_TESTCH1_D5":   PN = "Y7"  !CDS_PN = "Y7";
"GPP_L17_TESTCH1_D6":   PN = "AA9"  !CDS_PN = "AA9";
"GPP_L18_TESTCH1_D7":   PN = "AE7"  !CDS_PN = "AE7";
"GPP_L19_TESTCH1_CLK":   PN = "AG11"  !CDS_PN = "AG11";
"HDA_BCLK":   PN = "P18"  !CDS_PN = "P18";
"HDA_RST_N":   PN = "M18"  !CDS_PN = "M18";
"HDA_SDI_0":   PN = "K20"  !CDS_PN = "K20";
"HDA_SDI_1":   PN = "V18"  !CDS_PN = "V18";
"HDA_SDO":   PN = "U24"  !CDS_PN = "U24";
"HDA_SYNC":   PN = "H20"  !CDS_PN = "H20";
"INTRUDER_N":   PN = "AG18"  !CDS_PN = "AG18";
"RSVD<0>":   PN = "AF61"  !CDS_PN = "AF61";
"RSVD<1>":   PN = "AC56"  !CDS_PN = "AC56";
"RSVD<2>":   PN = "AA58"  !CDS_PN = "AA58";
"RSVD<3>":   PN = "V11"  !CDS_PN = "V11";
"RSVD<4>":   PN = "P37"  !CDS_PN = "P37";
"RSVD<5>":   PN = "AG15"  !CDS_PN = "AG15";
"RSVD<6>":   PN = "AT69"  !CDS_PN = "AT69";
"RSVD<7>":   PN = "F8"  !CDS_PN = "F8";
"RSVD<8>":   PN = "F69"  !CDS_PN = "F69";
"RSVD<9>":   PN = "F66"  !CDS_PN = "F66";
"RSVD<10>":   PN = "D8"  !CDS_PN = "D8";
"RSVD<11>":   PN = "C18"  !CDS_PN = "C18";
"RSVD<12>":   PN = "C68"  !CDS_PN = "C68";
"RSVD<13>":   PN = "C67"  !CDS_PN = "C67";
"RSVD<14>":   PN = "E18"  !CDS_PN = "E18";
"RSVD<15>":   PN = "C6"  !CDS_PN = "C6";
"RSVD<16>":   PN = "C5"  !CDS_PN = "C5";
"RSVD<17>":   PN = "B10"  !CDS_PN = "B10";
"RSVD<18>":   PN = "C11"  !CDS_PN = "C11";
"RSVD<19>":   PN = "C9"  !CDS_PN = "C9";
"RSVD<20>":   PN = "D10"  !CDS_PN = "D10";
"RSVD<21>":   PN = "A11"  !CDS_PN = "A11";
"RSVD<22>":   PN = "AT71"  !CDS_PN = "AT71";
"RSVD<23>":   PN = "P40"  !CDS_PN = "P40";
"RSVD<24>":   PN = "P44"  !CDS_PN = "P44";
"RSVD<25>":   PN = "P48"  !CDS_PN = "P48";
"RSVD<26>":   PN = "BH24"  !CDS_PN = "BH24";
"RSVD<27>":   PN = "BG26"  !CDS_PN = "BG26";
"RSVD<46>":   PN = "BW3"  !CDS_PN = "BW3";
"RSVD<66>":   PN = "U20"  !CDS_PN = "U20";
"RSVD<67>":   PN = "R20"  !CDS_PN = "R20";
"RSVD<68>":   PN = "V22"  !CDS_PN = "V22";
"RTCRST_N":   PN = "P11"  !CDS_PN = "P11";
"SPI0_CLK":   PN = "K2"  !CDS_PN = "K2";
"SPI0_FLASH_CS0_N":   PN = "J3"  !CDS_PN = "J3";
"SPI0_FLASH_CS1_N":   PN = "G7"  !CDS_PN = "G7";
"SPI0_IO2":   PN = "F5"  !CDS_PN = "F5";
"SPI0_IO3":   PN = "L1"  !CDS_PN = "L1";
"SPI0_MISO_IO1":   PN = "L3"  !CDS_PN = "L3";
"SPI0_MOSI_IO0":   PN = "H4"  !CDS_PN = "H4";
"SPI0_TPM_CS_N":   PN = "K4"  !CDS_PN = "K4";
"SRTCRST_N":   PN = "G18"  !CDS_PN = "G18";
BODY = "RES","I35": #LOCATION = "R8C26" !CDS_LOCATION = "R8C26" #SEC = "1" !CDS_SEC = "1";
"A":   PN = "1"  !CDS_PN = "1";
"B":   PN = "2"  !CDS_PN = "2";
BODY = "RES","I37": #LOCATION = "R3N10" !CDS_LOCATION = "R3N10" #SEC = "1" !CDS_SEC = "1";
"A":   PN = "1"  !CDS_PN = "1";
"B":   PN = "2"  !CDS_PN = "2";
BODY = "RES","I73": #LOCATION = "R7C20" !CDS_LOCATION = "R7C20" #SEC = "1" !CDS_SEC = "1";
"A":   PN = "1"  !CDS_PN = "1";
"B":   PN = "2"  !CDS_PN = "2";
BODY = "RES","I89": #LOCATION = "R3P3" !CDS_LOCATION = "R3P3" #SEC = "1" !CDS_SEC = "1";
"A":   PN = "1"  !CDS_PN = "1";
"B":   PN = "2"  !CDS_PN = "2";
BODY = "RES","I90": #LOCATION = "R3P2" !CDS_LOCATION = "R3P2" #SEC = "1" !CDS_SEC = "1";
"A":   PN = "1"  !CDS_PN = "1";
"B":   PN = "2"  !CDS_PN = "2";
BODY = "RES","I91": #LOCATION = "R2P1" !CDS_LOCATION = "R2P1" #SEC = "1" !CDS_SEC = "1";
"A":   PN = "1"  !CDS_PN = "1";
"B":   PN = "2"  !CDS_PN = "2";
BODY = "RES","I98": #LOCATION = "R7C14" !CDS_LOCATION = "R7C14" #SEC = "1" !CDS_SEC = "1";
"A":   PN = "1"  !CDS_PN = "1";
"B":   PN = "2"  !CDS_PN = "2";
BODY = "RES","I101": #LOCATION = "R8D11" !CDS_LOCATION = "R8D11" #SEC = "1" !CDS_SEC = "1";
"A":   PN = "1"  !CDS_PN = "1";
"B":   PN = "2"  !CDS_PN = "2";
DRAWING = "@baseboard_fab2_lib.baseboard_fab2(sch_1):page122";
BODY = "LBG_CORE_QAT_EXT_D","I63": #LOCATION = "U7C1" !CDS_LOCATION = "U7C1" #SEC = "9" !CDS_SEC = "9";
"RSVD<28>":   PN = "R35"  !CDS_PN = "R35";
"RSVD<29>":   PN = "P33"  !CDS_PN = "P33";
"RSVD<30>":   PN = "R31"  !CDS_PN = "R31";
"RSVD<31>":   PN = "P29"  !CDS_PN = "P29";
"RSVD<58>":   PN = "AP27"  !CDS_PN = "AP27";
"RSVD<59>":   PN = "AT27"  !CDS_PN = "AT27";
"VCCA_CLKFILT_1P05<0>":   PN = "W50"  !CDS_PN = "W50";
"VCCA_CLKFILT_1P05<1>":   PN = "AG45"  !CDS_PN = "AG45";
"VCCA_CLKFILT_1P05<2>":   PN = "AJ46"  !CDS_PN = "AJ46";
"VCCA_CLKFILT_1P05<3>":   PN = "AJ48"  !CDS_PN = "AJ48";
"VCCA_CLKFILT_1P05<4>":   PN = "AE46"  !CDS_PN = "AE46";
"VCCA_CLKUNF_1P05<0>":   PN = "AH50"  !CDS_PN = "AH50";
"VCCA_CLKUNF_1P05<1>":   PN = "U50"  !CDS_PN = "U50";
"VCCA_CLKXTAL_1P05":   PN = "AD50"  !CDS_PN = "AD50";
"VCCA_PLL0_1P05":   PN = "AG48"  !CDS_PN = "AG48";
"VCCA_PLL1_1P05":   PN = "AE45"  !CDS_PN = "AE45";
"VCCMPHY_1P05<0>":   PN = "AW45"  !CDS_PN = "AW45";
"VCCMPHY_1P05<1>":   PN = "AW43"  !CDS_PN = "AW43";
"VCCMPHY_1P05<2>":   PN = "AJ43"  !CDS_PN = "AJ43";
"VCCMPHY_1P05<3>":   PN = "AU45"  !CDS_PN = "AU45";
"VCCMPHY_1P05<4>":   PN = "AU43"  !CDS_PN = "AU43";
"VCCMPHY_1P05<5>":   PN = "AT45"  !CDS_PN = "AT45";
"VCCMPHY_1P05<6>":   PN = "AT43"  !CDS_PN = "AT43";
"VCCMPHY_1P05<7>":   PN = "AP45"  !CDS_PN = "AP45";
"VCCMPHY_1P05<8>":   PN = "AP43"  !CDS_PN = "AP43";
"VCCMPHY_1P05<9>":   PN = "AM45"  !CDS_PN = "AM45";
"VCCMPHY_1P05<10>":   PN = "AM43"  !CDS_PN = "AM43";
"VCCMPHY_1P05<11>":   PN = "AK45"  !CDS_PN = "AK45";
"VCCMPHY_1P05<12>":   PN = "AK43"  !CDS_PN = "AK43";
"VCCP10GBE_HV_1P8<0>":   PN = "BA29"  !CDS_PN = "BA29";
"VCCP10GBE_HV_1P8<1>":   PN = "BA27"  !CDS_PN = "BA27";
"VCCP10GBE_LV_1P05<0>":   PN = "BB37"  !CDS_PN = "BB37";
"VCCP10GBE_LV_1P05<1>":   PN = "BB33"  !CDS_PN = "BB33";
"VCCP10GBE_LV_1P05<2>":   PN = "BA37"  !CDS_PN = "BA37";
"VCCP10GBE_LV_1P05<3>":   PN = "BA36"  !CDS_PN = "BA36";
"VCCP10GBE_LV_1P05<4>":   PN = "BA34"  !CDS_PN = "BA34";
"VCCP10GBE_LV_1P05<5>":   PN = "BA32"  !CDS_PN = "BA32";
"VCCP10GBE_LV_1P05<6>":   PN = "BA30"  !CDS_PN = "BA30";
"VCCP10GBEPLL_1P05<0>":   PN = "BD38"  !CDS_PN = "BD38";
"VCCP10GBEPLL_1P05<1>":   PN = "BB40"  !CDS_PN = "BB40";
"VCCP10GBEPLL_1P05<2>":   PN = "BA41"  !CDS_PN = "BA41";
"VCCP10GBEPLL_1P05<3>":   PN = "BA39"  !CDS_PN = "BA39";
"VCCP_1P8<0>":   PN = "BD46"  !CDS_PN = "BD46";
"VCCP_1P8<1>":   PN = "AE26"  !CDS_PN = "AE26";
"VCCP_3P3<0>":   PN = "BA46"  !CDS_PN = "BA46";
"VCCP_3P3<1>":   PN = "BA45"  !CDS_PN = "BA45";
"VCCP_3P3<2>":   PN = "AD24"  !CDS_PN = "AD24";
"VCCP_3P3<5>":   PN = "AN24"  !CDS_PN = "AN24";
"VCCP_HSIOPLL_1P05<0>":   PN = "AW48"  !CDS_PN = "AW48";
"VCCP_HSIOPLL_1P05<2>":   PN = "AU48"  !CDS_PN = "AU48";
"VCCP_HSIOPLL_1P05<3>":   PN = "AP48"  !CDS_PN = "AP48";
"VCCP_HSIOPLLUNF_1P05":   PN = "AT48"  !CDS_PN = "AT48";
"VCCP_UPPLL_1P05<0>":   PN = "AN50"  !CDS_PN = "AN50";
"VCCP_UPPLL_1P05<2>":   PN = "AK50"  !CDS_PN = "AK50";
"VCCP_UPPLLUNF_1P05":   PN = "AM48"  !CDS_PN = "AM48";
"VCCPDSW_3P3":   PN = "AH24"  !CDS_PN = "AH24";
"VCCPGPP_1P8<0>":   PN = "AU29"  !CDS_PN = "AU29";
"VCCPGPP_1P8<1>":   PN = "AW29"  !CDS_PN = "AW29";
"VCCPGPP_1P8<2>":   PN = "AT29"  !CDS_PN = "AT29";
"VCCPGPP_1P8<3>":   PN = "AM29"  !CDS_PN = "AM29";
"VCCPGPP_1P8<4>":   PN = "AP29"  !CDS_PN = "AP29";
"VCCPGPP_1P8<5>":   PN = "AW27"  !CDS_PN = "AW27";
"VCCPGPP_1P8<6>":   PN = "AK24"  !CDS_PN = "AK24";
"VCCPGPPA":   PN = "AW24"  !CDS_PN = "AW24";
"VCCPGPPB":   PN = "BE26"  !CDS_PN = "BE26";
"VCCPGPPC":   PN = "BE40"  !CDS_PN = "BE40";
"VCCPGPPD":   PN = "BA43"  !CDS_PN = "BA43";
"VCCPGPPE":   PN = "BE44"  !CDS_PN = "BE44";
"VCCPGPPF":   PN = "AU27"  !CDS_PN = "AU27";
"VCCPGPPG":   PN = "BA26"  !CDS_PN = "BA26";
"VCCPGPPH":   PN = "BA24"  !CDS_PN = "BA24";
"VCCPGPPJ":   PN = "BB26"  !CDS_PN = "BB26";
"VCCPGPPK":   PN = "AU24"  !CDS_PN = "AU24";
"VCCPHDA_1P8":   PN = "AG27"  !CDS_PN = "AG27";
"VCCPRIM_1P05<0>":   PN = "BF46"  !CDS_PN = "BF46";
"VCCPRIM_1P05<1>":   PN = "BE48"  !CDS_PN = "BE48";
"VCCPRIM_1P05<2>":   PN = "AU39"  !CDS_PN = "AU39";
"VCCPRIM_1P05<3>":   PN = "AU37"  !CDS_PN = "AU37";
"VCCPRIM_1P05<4>":   PN = "AT39"  !CDS_PN = "AT39";
"VCCPRIM_1P05<5>":   PN = "AM27"  !CDS_PN = "AM27";
"VCCPRIM_1P05<6>":   PN = "AJ29"  !CDS_PN = "AJ29";
"VCCPRIM_1P05<7>":   PN = "AC26"  !CDS_PN = "AC26";
"VCCPRIM_1P05<8>":   PN = "AA46"  !CDS_PN = "AA46";
"VCCPRIM_1P05<9>":   PN = "AA45"  !CDS_PN = "AA45";
"VCCPRIM_1P05<10>":   PN = "Y46"  !CDS_PN = "Y46";
"VCCPRIM_1P05<11>":   PN = "Y45"  !CDS_PN = "Y45";
"VCCPRIM_1P05<12>":   PN = "V44"  !CDS_PN = "V44";
"VCCPRIM_1P05<13>":   PN = "U46"  !CDS_PN = "U46";
"VCCPRIM_1P05<14>":   PN = "T44"  !CDS_PN = "T44";
"VCCPRIM_1P05<15>":   PN = "R46"  !CDS_PN = "R46";
"VCCPRIM_1P05<16>":   PN = "R42"  !CDS_PN = "R42";
"VCCPRIM_1P05<17>":   PN = "AK27"  !CDS_PN = "AK27";
"VCCPRIM_1P05<18>":   PN = "AA24"  !CDS_PN = "AA24";
"VCCPRIM_1P05<19>":   PN = "Y26"  !CDS_PN = "Y26";
"VCCPRTC":   PN = "AJ27"  !CDS_PN = "AJ27";
"VCCPRTCPRIM_3P3":   PN = "AG29"  !CDS_PN = "AG29";
"VCCPSPI":   PN = "AR24"  !CDS_PN = "AR24";
"VCCPSPI_1P8":   PN = "AK29"  !CDS_PN = "AK29";
"VCCPUSBDSW_3P3":   PN = "BA48"  !CDS_PN = "BA48";
"VCCRTCEXT":   PN = "AG22"  !CDS_PN = "AG22";
DRAWING = "@baseboard_fab2_lib.baseboard_fab2(sch_1):page123";
BODY = "LBG_CORE_QAT_EXT_D","I13": #LOCATION = "U7C1" !CDS_LOCATION = "U7C1" #SEC = "11" !CDS_SEC = "11";
"VSS<355>":   PN = "N31"  !CDS_PN = "N31";
"VSS<356>":   PN = "N27"  !CDS_PN = "N27";
"VSS<357>":   PN = "N24"  !CDS_PN = "N24";
"VSS<358>":   PN = "N20"  !CDS_PN = "N20";
"VSS<359>":   PN = "N17"  !CDS_PN = "N17";
"VSS<360>":   PN = "N13"  !CDS_PN = "N13";
"VSS<361>":   PN = "M48"  !CDS_PN = "M48";
"VSS<362>":   PN = "M44"  !CDS_PN = "M44";
"VSS<363>":   PN = "N50"  !CDS_PN = "N50";
"VSS<364>":   PN = "N42"  !CDS_PN = "N42";
"VSS<365>":   PN = "M40"  !CDS_PN = "M40";
"VSS<366>":   PN = "M4"  !CDS_PN = "M4";
"VSS<367>":   PN = "M37"  !CDS_PN = "M37";
"VSS<368>":   PN = "M33"  !CDS_PN = "M33";
"VSS<369>":   PN = "M29"  !CDS_PN = "M29";
"VSS<370>":   PN = "M26"  !CDS_PN = "M26";
"VSS<371>":   PN = "M22"  !CDS_PN = "M22";
"VSS<372>":   PN = "M2"  !CDS_PN = "M2";
"VSS<373>":   PN = "L68"  !CDS_PN = "L68";
"VSS<374>":   PN = "L5"  !CDS_PN = "L5";
"VSS<375>":   PN = "K71"  !CDS_PN = "K71";
"VSS<376>":   PN = "K69"  !CDS_PN = "K69";
"VSS<377>":   PN = "K54"  !CDS_PN = "K54";
"VSS<378>":   PN = "J70"  !CDS_PN = "J70";
"VSS<379>":   PN = "J68"  !CDS_PN = "J68";
"VSS<380>":   PN = "J59"  !CDS_PN = "J59";
"VSS<381>":   PN = "J44"  !CDS_PN = "J44";
"VSS<382>":   PN = "J37"  !CDS_PN = "J37";
"VSS<383>":   PN = "J22"  !CDS_PN = "J22";
"VSS<384>":   PN = "J15"  !CDS_PN = "J15";
"VSS<385>":   PN = "J11"  !CDS_PN = "J11";
"VSS<386>":   PN = "H65"  !CDS_PN = "H65";
"VSS<387>":   PN = "J7"  !CDS_PN = "J7";
"VSS<388>":   PN = "J5"  !CDS_PN = "J5";
"VSS<389>":   PN = "J29"  !CDS_PN = "J29";
"VSS<390>":   PN = "H58"  !CDS_PN = "H58";
"VSS<391>":   PN = "G66"  !CDS_PN = "G66";
"VSS<392>":   PN = "G63"  !CDS_PN = "G63";
"VSS<393>":   PN = "G6"  !CDS_PN = "G6";
"VSS<394>":   PN = "G48"  !CDS_PN = "G48";
"VSS<395>":   PN = "G37"  !CDS_PN = "G37";
"VSS<396>":   PN = "G29"  !CDS_PN = "G29";
"VSS<397>":   PN = "G22"  !CDS_PN = "G22";
"VSS<398>":   PN = "E9"  !CDS_PN = "E9";
"VSS<399>":   PN = "G59"  !CDS_PN = "G59";
"VSS<400>":   PN = "E63"  !CDS_PN = "E63";
"VSS<401>":   PN = "E61"  !CDS_PN = "E61";
"VSS<402>":   PN = "E6"  !CDS_PN = "E6";
"VSS<403>":   PN = "E57"  !CDS_PN = "E57";
"VSS<404>":   PN = "E54"  !CDS_PN = "E54";
"VSS<405>":   PN = "E52"  !CDS_PN = "E52";
"VSS<406>":   PN = "E50"  !CDS_PN = "E50";
"VSS<407>":   PN = "E48"  !CDS_PN = "E48";
"VSS<408>":   PN = "E45"  !CDS_PN = "E45";
"VSS<409>":   PN = "E43"  !CDS_PN = "E43";
"VSS<410>":   PN = "E41"  !CDS_PN = "E41";
"VSS<411>":   PN = "E39"  !CDS_PN = "E39";
"VSS<412>":   PN = "E37"  !CDS_PN = "E37";
"VSS<413>":   PN = "E34"  !CDS_PN = "E34";
"VSS<414>":   PN = "E32"  !CDS_PN = "E32";
"VSS<415>":   PN = "E30"  !CDS_PN = "E30";
"VSS<416>":   PN = "E28"  !CDS_PN = "E28";
"VSS<417>":   PN = "E26"  !CDS_PN = "E26";
"VSS<418>":   PN = "E24"  !CDS_PN = "E24";
"VSS<419>":   PN = "E22"  !CDS_PN = "E22";
"VSS<420>":   PN = "E20"  !CDS_PN = "E20";
"VSS<421>":   PN = "E15"  !CDS_PN = "E15";
"VSS<422>":   PN = "E13"  !CDS_PN = "E13";
"VSS<423>":   PN = "E11"  !CDS_PN = "E11";
"VSS<424>":   PN = "D47"  !CDS_PN = "D47";
"VSS<425>":   PN = "E65"  !CDS_PN = "E65";
"VSS<426>":   PN = "E59"  !CDS_PN = "E59";
"VSS<427>":   PN = "D27"  !CDS_PN = "D27";
"VSS<428>":   PN = "D25"  !CDS_PN = "D25";
"VSS<429>":   PN = "D19"  !CDS_PN = "D19";
"VSS<430>":   PN = "D16"  !CDS_PN = "D16";
"VSS<431>":   PN = "D12"  !CDS_PN = "D12";
"VSS<432>":   PN = "C65"  !CDS_PN = "C65";
"VSS<433>":   PN = "C41"  !CDS_PN = "C41";
"VSS<434>":   PN = "C37"  !CDS_PN = "C37";
"VSS<435>":   PN = "C34"  !CDS_PN = "C34";
"VSS<436>":   PN = "C30"  !CDS_PN = "C30";
"VSS<437>":   PN = "C22"  !CDS_PN = "C22";
"VSS<438>":   PN = "B47"  !CDS_PN = "B47";
"VSS<439>":   PN = "B27"  !CDS_PN = "B27";
"VSS<440>":   PN = "B25"  !CDS_PN = "B25";
"VSS<441>":   PN = "B19"  !CDS_PN = "B19";
"VSS<442>":   PN = "B12"  !CDS_PN = "B12";
"VSS<443>":   PN = "A41"  !CDS_PN = "A41";
"VSS<444>":   PN = "A37"  !CDS_PN = "A37";
"VSS<445>":   PN = "A34"  !CDS_PN = "A34";
"VSS<446>":   PN = "A30"  !CDS_PN = "A30";
"VSS<447>":   PN = "A22"  !CDS_PN = "A22";
"VSS<448>":   PN = "A18"  !CDS_PN = "A18";
"VSS<449>":   PN = "Y70"  !CDS_PN = "Y70";
"VSS<450>":   PN = "Y72"  !CDS_PN = "Y72";
"VSS<451>":   PN = "AT37"  !CDS_PN = "AT37";
"VSS<452>":   PN = "BB48"  !CDS_PN = "BB48";
"VSS<453>":   PN = "CA70"  !CDS_PN = "CA70";
"VSS<454>":   PN = "BW72"  !CDS_PN = "BW72";
"VSS<455>":   PN = "BW70"  !CDS_PN = "BW70";
"VSS<456>":   PN = "BU72"  !CDS_PN = "BU72";
"VSS<457>":   PN = "BR72"  !CDS_PN = "BR72";
"VSS<458>":   PN = "G72"  !CDS_PN = "G72";
"VSS<459>":   PN = "G1"  !CDS_PN = "G1";
"VSS<460>":   PN = "E72"  !CDS_PN = "E72";
"VSS<461>":   PN = "E1"  !CDS_PN = "E1";
"VSS<462>":   PN = "C72"  !CDS_PN = "C72";
"VSS<463>":   PN = "C3"  !CDS_PN = "C3";
"VSS<464>":   PN = "BR1"  !CDS_PN = "BR1";
"VSS<465>":   PN = "BU1"  !CDS_PN = "BU1";
"VSS<466>":   PN = "BW1"  !CDS_PN = "BW1";
"VSS<467>":   PN = "CA3"  !CDS_PN = "CA3";
"VSS<468>":   PN = "A70"  !CDS_PN = "A70";
"VSS<469>":   PN = "CA5"  !CDS_PN = "CA5";
"VSS<470>":   PN = "CA7"  !CDS_PN = "CA7";
"VSS<471>":   PN = "CA9"  !CDS_PN = "CA9";
"VSS<472>":   PN = "CA65"  !CDS_PN = "CA65";
"VSS<473>":   PN = "CA66"  !CDS_PN = "CA66";
"VSS<474>":   PN = "CA68"  !CDS_PN = "CA68";
"VSS<475>":   PN = "BN72"  !CDS_PN = "BN72";
"VSS<476>":   PN = "BN1"  !CDS_PN = "BN1";
"VSS<477>":   PN = "J72"  !CDS_PN = "J72";
"VSS<478>":   PN = "J1"  !CDS_PN = "J1";
"VSS<479>":   PN = "A68"  !CDS_PN = "A68";
"VSS<480>":   PN = "A66"  !CDS_PN = "A66";
"VSS<481>":   PN = "A65"  !CDS_PN = "A65";
"VSS<482>":   PN = "A9"  !CDS_PN = "A9";
"VSS<483>":   PN = "A7"  !CDS_PN = "A7";
"VSS<484>":   PN = "A5"  !CDS_PN = "A5";
"VSS<485>":   PN = "E3"  !CDS_PN = "E3";
"VSS<486>":   PN = "F3"  !CDS_PN = "F3";
"VSS<487>":   PN = "BR3"  !CDS_PN = "BR3";
"VSS<488>":   PN = "BU3"  !CDS_PN = "BU3";
"VSS<489>":   PN = "E70"  !CDS_PN = "E70";
"VSS<490>":   PN = "F70"  !CDS_PN = "F70";
"VSS<491>":   PN = "BR70"  !CDS_PN = "BR70";
"VSS<492>":   PN = "BU70"  !CDS_PN = "BU70";
"VSS<493>":   PN = "BT69"  !CDS_PN = "BT69";
"VSS<494>":   PN = "BP69"  !CDS_PN = "BP69";
BODY = "LBG_CORE_QAT_EXT_D","I21": #LOCATION = "U7C1" !CDS_LOCATION = "U7C1" #SEC = "10" !CDS_SEC = "10";
"VCCMPHY_1P05<13>":   PN = "AE27"  !CDS_PN = "AE27";
"VCCPRIM_AVID<0>":   PN = "AU36"  !CDS_PN = "AU36";
"VCCPRIM_AVID<1>":   PN = "AU34"  !CDS_PN = "AU34";
"VCCPRIM_AVID<2>":   PN = "AU32"  !CDS_PN = "AU32";
"VCCPRIM_AVID<3>":   PN = "AT36"  !CDS_PN = "AT36";
"VCCPRIM_AVID<4>":   PN = "AT34"  !CDS_PN = "AT34";
"VCCPRIM_AVID<5>":   PN = "AT32"  !CDS_PN = "AT32";
"VCCPRIM_AVID<6>":   PN = "AP39"  !CDS_PN = "AP39";
"VCCPRIM_AVID<7>":   PN = "AP37"  !CDS_PN = "AP37";
"VCCPRIM_AVID<8>":   PN = "AP36"  !CDS_PN = "AP36";
"VCCPRIM_AVID<9>":   PN = "AP34"  !CDS_PN = "AP34";
"VCCPRIM_AVID<10>":   PN = "AP32"  !CDS_PN = "AP32";
"VCCPRIM_AVID<11>":   PN = "AM39"  !CDS_PN = "AM39";
"VCCPRIM_AVID<12>":   PN = "AM37"  !CDS_PN = "AM37";
"VCCPRIM_AVID<13>":   PN = "AM36"  !CDS_PN = "AM36";
"VCCPRIM_AVID<14>":   PN = "AM34"  !CDS_PN = "AM34";
"VCCPRIM_AVID<15>":   PN = "AM32"  !CDS_PN = "AM32";
"VCCPRIM_AVID<16>":   PN = "AK39"  !CDS_PN = "AK39";
"VCCPRIM_AVID<17>":   PN = "AK37"  !CDS_PN = "AK37";
"VCCPRIM_AVID<18>":   PN = "AK34"  !CDS_PN = "AK34";
"VCCPRIM_AVID<19>":   PN = "AG39"  !CDS_PN = "AG39";
"VCCPRIM_AVID<20>":   PN = "AG37"  !CDS_PN = "AG37";
"VCCPRIM_AVID<21>":   PN = "AG36"  !CDS_PN = "AG36";
"VCCPRIM_AVID<22>":   PN = "AG34"  !CDS_PN = "AG34";
"VCCPRIM_AVID<23>":   PN = "AG32"  !CDS_PN = "AG32";
"VCCPRIM_AVID<24>":   PN = "AE41"  !CDS_PN = "AE41";
"VCCPRIM_AVID<25>":   PN = "AE39"  !CDS_PN = "AE39";
"VCCPRIM_AVID<26>":   PN = "AE37"  !CDS_PN = "AE37";
"VCCPRIM_AVID<27>":   PN = "AE36"  !CDS_PN = "AE36";
"VCCPRIM_AVID<28>":   PN = "AE34"  !CDS_PN = "AE34";
"VCCPRIM_AVID<29>":   PN = "AE32"  !CDS_PN = "AE32";
"VCCPRIM_AVID<30>":   PN = "AE30"  !CDS_PN = "AE30";
"VCCPRIM_AVID<31>":   PN = "U27"  !CDS_PN = "U27";
"VCCPRIM_AVID<32>":   PN = "AC41"  !CDS_PN = "AC41";
"VCCPRIM_AVID<33>":   PN = "AC39"  !CDS_PN = "AC39";
"VCCPRIM_AVID<34>":   PN = "AC37"  !CDS_PN = "AC37";
"VCCPRIM_AVID<35>":   PN = "AC36"  !CDS_PN = "AC36";
"VCCPRIM_AVID<36>":   PN = "AC34"  !CDS_PN = "AC34";
"VCCPRIM_AVID<37>":   PN = "AC32"  !CDS_PN = "AC32";
"VCCPRIM_AVID<38>":   PN = "AC30"  !CDS_PN = "AC30";
"VCCPRIM_AVID<39>":   PN = "AC29"  !CDS_PN = "AC29";
"VCCPRIM_AVID<40>":   PN = "AA41"  !CDS_PN = "AA41";
"VCCPRIM_AVID<41>":   PN = "AA39"  !CDS_PN = "AA39";
"VCCPRIM_AVID<42>":   PN = "AA37"  !CDS_PN = "AA37";
"VCCPRIM_AVID<43>":   PN = "AA36"  !CDS_PN = "AA36";
"VCCPRIM_AVID<44>":   PN = "AA34"  !CDS_PN = "AA34";
"VCCPRIM_AVID<45>":   PN = "AA32"  !CDS_PN = "AA32";
"VCCPRIM_AVID<46>":   PN = "AA30"  !CDS_PN = "AA30";
"VCCPRIM_AVID<47>":   PN = "AA29"  !CDS_PN = "AA29";
"VCCPRIM_AVID<48>":   PN = "Y41"  !CDS_PN = "Y41";
"VCCPRIM_AVID<49>":   PN = "Y39"  !CDS_PN = "Y39";
"VCCPRIM_AVID<50>":   PN = "Y37"  !CDS_PN = "Y37";
"VCCPRIM_AVID<51>":   PN = "Y36"  !CDS_PN = "Y36";
"VCCPRIM_AVID<52>":   PN = "Y34"  !CDS_PN = "Y34";
"VCCPRIM_AVID<53>":   PN = "Y32"  !CDS_PN = "Y32";
"VCCPRIM_AVID<54>":   PN = "Y30"  !CDS_PN = "Y30";
"VCCPRIM_AVID<55>":   PN = "Y29"  !CDS_PN = "Y29";
"VCCPRIM_AVID<56>":   PN = "V40"  !CDS_PN = "V40";
"VCCPRIM_AVID<57>":   PN = "V33"  !CDS_PN = "V33";
"VCCPRIM_AVID<58>":   PN = "V29"  !CDS_PN = "V29";
"VCCPRIM_AVID<59>":   PN = "U38"  !CDS_PN = "U38";
"VCCPRIM_AVID<60>":   PN = "U35"  !CDS_PN = "U35";
"VCCPRIM_AVID<61>":   PN = "U31"  !CDS_PN = "U31";
"VCCPRIM_AVID<62>":   PN = "AK32"  !CDS_PN = "AK32";
"VCCPRIM_AVID_QAT_SENSE":   PN = "V37"  !CDS_PN = "V37";
"VCCPRIM_AVID_SENSE":   PN = "AK36"  !CDS_PN = "AK36";
DRAWING = "@baseboard_fab2_lib.baseboard_fab2(sch_1):page124";
BODY = "LBG_CORE_QAT_EXT_D","I15": #LOCATION = "U7C1" !CDS_LOCATION = "U7C1" #SEC = "14" !CDS_SEC = "14";
"VSS<0>":   PN = "CA52"  !CDS_PN = "CA52";
"VSS<1>":   PN = "CA50"  !CDS_PN = "CA50";
"VSS<2>":   PN = "CA26"  !CDS_PN = "CA26";
"VSS<3>":   PN = "CA18"  !CDS_PN = "CA18";
"VSS<4>":   PN = "CA15"  !CDS_PN = "CA15";
"VSS<5>":   PN = "BY49"  !CDS_PN = "BY49";
"VSS<6>":   PN = "BY40"  !CDS_PN = "BY40";
"VSS<7>":   PN = "BW52"  !CDS_PN = "BW52";
"VSS<8>":   PN = "BW26"  !CDS_PN = "BW26";
"VSS<9>":   PN = "BW18"  !CDS_PN = "BW18";
"VSS<10>":   PN = "BW15"  !CDS_PN = "BW15";
"VSS<11>":   PN = "BV40"  !CDS_PN = "BV40";
"VSS<12>":   PN = "BU9"  !CDS_PN = "BU9";
"VSS<13>":   PN = "BU63"  !CDS_PN = "BU63";
"VSS<14>":   PN = "BU61"  !CDS_PN = "BU61";
"VSS<15>":   PN = "BU59"  !CDS_PN = "BU59";
"VSS<16>":   PN = "BU57"  !CDS_PN = "BU57";
"VSS<17>":   PN = "BU54"  !CDS_PN = "BU54";
"VSS<18>":   PN = "BU52"  !CDS_PN = "BU52";
"VSS<19>":   PN = "BU50"  !CDS_PN = "BU50";
"VSS<20>":   PN = "BU48"  !CDS_PN = "BU48";
"VSS<21>":   PN = "BU45"  !CDS_PN = "BU45";
"VSS<22>":   PN = "BU43"  !CDS_PN = "BU43";
"VSS<23>":   PN = "BU41"  !CDS_PN = "BU41";
"VSS<24>":   PN = "BU39"  !CDS_PN = "BU39";
"VSS<25>":   PN = "BU37"  !CDS_PN = "BU37";
"VSS<26>":   PN = "BU34"  !CDS_PN = "BU34";
"VSS<27>":   PN = "BU32"  !CDS_PN = "BU32";
"VSS<28>":   PN = "BU30"  !CDS_PN = "BU30";
"VSS<29>":   PN = "BU28"  !CDS_PN = "BU28";
"VSS<30>":   PN = "BU26"  !CDS_PN = "BU26";
"VSS<31>":   PN = "BU24"  !CDS_PN = "BU24";
"VSS<32>":   PN = "BU22"  !CDS_PN = "BU22";
"VSS<33>":   PN = "BU20"  !CDS_PN = "BU20";
"VSS<34>":   PN = "BU18"  !CDS_PN = "BU18";
"VSS<35>":   PN = "BU15"  !CDS_PN = "BU15";
"VSS<36>":   PN = "BV49"  !CDS_PN = "BV49";
"VSS<37>":   PN = "BU11"  !CDS_PN = "BU11";
"VSS<38>":   PN = "BU13"  !CDS_PN = "BU13";
"VSS<39>":   PN = "BT66"  !CDS_PN = "BT66";
"VSS<40>":   PN = "BR6"  !CDS_PN = "BR6";
"VSS<41>":   PN = "BR58"  !CDS_PN = "BR58";
"VSS<42>":   PN = "BR54"  !CDS_PN = "BR54";
"VSS<43>":   PN = "BT8"  !CDS_PN = "BT8";
"VSS<44>":   PN = "BR50"  !CDS_PN = "BR50";
"VSS<45>":   PN = "BR20"  !CDS_PN = "BR20";
"VSS<46>":   PN = "BN66"  !CDS_PN = "BN66";
"VSS<47>":   PN = "BN52"  !CDS_PN = "BN52";
"VSS<48>":   PN = "BN5"  !CDS_PN = "BN5";
"VSS<49>":   PN = "BN59"  !CDS_PN = "BN59";
"VSS<50>":   PN = "BN22"  !CDS_PN = "BN22";
"VSS<51>":   PN = "BM9"  !CDS_PN = "BM9";
"VSS<52>":   PN = "BM71"  !CDS_PN = "BM71";
"VSS<53>":   PN = "BM69"  !CDS_PN = "BM69";
"VSS<54>":   PN = "BM58"  !CDS_PN = "BM58";
"VSS<55>":   PN = "BM50"  !CDS_PN = "BM50";
"VSS<56>":   PN = "BM46"  !CDS_PN = "BM46";
"VSS<57>":   PN = "BN37"  !CDS_PN = "BN37";
"VSS<58>":   PN = "BM17"  !CDS_PN = "BM17";
"VSS<59>":   PN = "BM13"  !CDS_PN = "BM13";
"VSS<60>":   PN = "BL72"  !CDS_PN = "BL72";
"VSS<61>":   PN = "BL70"  !CDS_PN = "BL70";
"VSS<62>":   PN = "BL63"  !CDS_PN = "BL63";
"VSS<63>":   PN = "BL5"  !CDS_PN = "BL5";
"VSS<64>":   PN = "BL37"  !CDS_PN = "BL37";
"VSS<65>":   PN = "BL68"  !CDS_PN = "BL68";
"VSS<66>":   PN = "BL40"  !CDS_PN = "BL40";
"VSS<67>":   PN = "BL22"  !CDS_PN = "BL22";
"VSS<68>":   PN = "BK50"  !CDS_PN = "BK50";
"VSS<69>":   PN = "BK42"  !CDS_PN = "BK42";
"VSS<70>":   PN = "BK38"  !CDS_PN = "BK38";
"VSS<71>":   PN = "BK35"  !CDS_PN = "BK35";
"VSS<72>":   PN = "BK31"  !CDS_PN = "BK31";
"VSS<73>":   PN = "BK27"  !CDS_PN = "BK27";
"VSS<74>":   PN = "BK24"  !CDS_PN = "BK24";
BODY = "LBG_CORE_QAT_EXT_D","I16": #LOCATION = "U7C1" !CDS_LOCATION = "U7C1" #SEC = "13" !CDS_SEC = "13";
"VSS<75>":   PN = "BJ68"  !CDS_PN = "BJ68";
"VSS<76>":   PN = "BJ52"  !CDS_PN = "BJ52";
"VSS<77>":   PN = "BJ33"  !CDS_PN = "BJ33";
"VSS<78>":   PN = "BJ3"  !CDS_PN = "BJ3";
"VSS<79>":   PN = "BJ26"  !CDS_PN = "BJ26";
"VSS<80>":   PN = "BJ18"  !CDS_PN = "BJ18";
"VSS<81>":   PN = "BJ15"  !CDS_PN = "BJ15";
"VSS<82>":   PN = "BJ7"  !CDS_PN = "BJ7";
"VSS<83>":   PN = "BJ5"  !CDS_PN = "BJ5";
"VSS<84>":   PN = "BJ11"  !CDS_PN = "BJ11";
"VSS<85>":   PN = "BJ1"  !CDS_PN = "BJ1";
"VSS<86>":   PN = "BH54"  !CDS_PN = "BH54";
"VSS<87>":   PN = "BH46"  !CDS_PN = "BH46";
"VSS<88>":   PN = "BH42"  !CDS_PN = "BH42";
"VSS<89>":   PN = "BH38"  !CDS_PN = "BH38";
"VSS<90>":   PN = "BH27"  !CDS_PN = "BH27";
"VSS<91>":   PN = "BG63"  !CDS_PN = "BG63";
"VSS<92>":   PN = "BG59"  !CDS_PN = "BG59";
"VSS<93>":   PN = "BG48"  !CDS_PN = "BG48";
"VSS<94>":   PN = "BG33"  !CDS_PN = "BG33";
"VSS<95>":   PN = "BF9"  !CDS_PN = "BF9";
"VSS<96>":   PN = "BF68"  !CDS_PN = "BF68";
"VSS<97>":   PN = "BF65"  !CDS_PN = "BF65";
"VSS<98>":   PN = "BF61"  !CDS_PN = "BF61";
"VSS<99>":   PN = "BF58"  !CDS_PN = "BF58";
"VSS<100>":   PN = "BF50"  !CDS_PN = "BF50";
"VSS<101>":   PN = "BF5"  !CDS_PN = "BF5";
"VSS<102>":   PN = "BF42"  !CDS_PN = "BF42";
"VSS<103>":   PN = "BF38"  !CDS_PN = "BF38";
"VSS<104>":   PN = "BF27"  !CDS_PN = "BF27";
"VSS<105>":   PN = "BF24"  !CDS_PN = "BF24";
"VSS<106>":   PN = "BF20"  !CDS_PN = "BF20";
"VSS<107>":   PN = "BG44"  !CDS_PN = "BG44";
"VSS<108>":   PN = "BF54"  !CDS_PN = "BF54";
"VSS<109>":   PN = "BF17"  !CDS_PN = "BF17";
"VSS<110>":   PN = "BF13"  !CDS_PN = "BF13";
"VSS<111>":   PN = "BE66"  !CDS_PN = "BE66";
"VSS<112>":   PN = "BE63"  !CDS_PN = "BE63";
"VSS<113>":   PN = "BE59"  !CDS_PN = "BE59";
"VSS<114>":   PN = "BE56"  !CDS_PN = "BE56";
"VSS<115>":   PN = "BE37"  !CDS_PN = "BE37";
"VSS<116>":   PN = "BE33"  !CDS_PN = "BE33";
"VSS<117>":   PN = "BE29"  !CDS_PN = "BE29";
"VSS<118>":   PN = "BD68"  !CDS_PN = "BD68";
"VSS<119>":   PN = "BD54"  !CDS_PN = "BD54";
"VSS<120>":   PN = "BD50"  !CDS_PN = "BD50";
"VSS<121>":   PN = "BD5"  !CDS_PN = "BD5";
"VSS<122>":   PN = "BD35"  !CDS_PN = "BD35";
"VSS<123>":   PN = "BD31"  !CDS_PN = "BD31";
"VSS<124>":   PN = "BD27"  !CDS_PN = "BD27";
"VSS<125>":   PN = "BD24"  !CDS_PN = "BD24";
"VSS<126>":   PN = "BC71"  !CDS_PN = "BC71";
"VSS<127>":   PN = "BC69"  !CDS_PN = "BC69";
"VSS<128>":   PN = "BB72"  !CDS_PN = "BB72";
"VSS<129>":   PN = "BB70"  !CDS_PN = "BB70";
"VSS<130>":   PN = "BB68"  !CDS_PN = "BB68";
"VSS<131>":   PN = "BB66"  !CDS_PN = "BB66";
"VSS<132>":   PN = "BB59"  !CDS_PN = "BB59";
"VSS<133>":   PN = "BB44"  !CDS_PN = "BB44";
"VSS<134>":   PN = "BB22"  !CDS_PN = "BB22";
"VSS<135>":   PN = "BB18"  !CDS_PN = "BB18";
"VSS<136>":   PN = "BB15"  !CDS_PN = "BB15";
"VSS<137>":   PN = "BB11"  !CDS_PN = "BB11";
"VSS<138>":   PN = "BB7"  !CDS_PN = "BB7";
"VSS<139>":   PN = "BB5"  !CDS_PN = "BB5";
"VSS<140>":   PN = "BA58"  !CDS_PN = "BA58";
"VSS<141>":   PN = "BA54"  !CDS_PN = "BA54";
"VSS<142>":   PN = "BA50"  !CDS_PN = "BA50";
"VSS<143>":   PN = "AY68"  !CDS_PN = "AY68";
"VSS<144>":   PN = "AY63"  !CDS_PN = "AY63";
"VSS<145>":   PN = "AY56"  !CDS_PN = "AY56";
"VSS<146>":   PN = "AY22"  !CDS_PN = "AY22";
"VSS<147>":   PN = "AY5"  !CDS_PN = "AY5";
"VSS<148>":   PN = "AW61"  !CDS_PN = "AW61";
"VSS<149>":   PN = "AW58"  !CDS_PN = "AW58";
"VSS<150>":   PN = "AW50"  !CDS_PN = "AW50";
"VSS<151>":   PN = "AW46"  !CDS_PN = "AW46";
"VSS<152>":   PN = "AW41"  !CDS_PN = "AW41";
"VSS<153>":   PN = "AW39"  !CDS_PN = "AW39";
"VSS<154>":   PN = "AW37"  !CDS_PN = "AW37";
"VSS<155>":   PN = "AW36"  !CDS_PN = "AW36";
"VSS<156>":   PN = "AW34"  !CDS_PN = "AW34";
"VSS<157>":   PN = "AW32"  !CDS_PN = "AW32";
"VSS<158>":   PN = "AW30"  !CDS_PN = "AW30";
"VSS<159>":   PN = "AW26"  !CDS_PN = "AW26";
"VSS<160>":   PN = "AW17"  !CDS_PN = "AW17";
"VSS<161>":   PN = "AW13"  !CDS_PN = "AW13";
"VSS<162>":   PN = "AW9"  !CDS_PN = "AW9";
"VSS<163>":   PN = "AV68"  !CDS_PN = "AV68";
"VSS<164>":   PN = "AV59"  !CDS_PN = "AV59";
"VSS<165>":   PN = "AV22"  !CDS_PN = "AV22";
"VSS<166>":   PN = "AV5"  !CDS_PN = "AV5";
"VSS<167>":   PN = "AU61"  !CDS_PN = "AU61";
"VSS<168>":   PN = "AU54"  !CDS_PN = "AU54";
"VSS<169>":   PN = "AU50"  !CDS_PN = "AU50";
"VSS<170>":   PN = "AU46"  !CDS_PN = "AU46";
"VSS<171>":   PN = "AU41"  !CDS_PN = "AU41";
"VSS<172>":   PN = "AE22"  !CDS_PN = "AE22";
"VSS<173>":   PN = "AU30"  !CDS_PN = "AU30";
"VSS<174>":   PN = "AU26"  !CDS_PN = "AU26";
"VSS<175>":   PN = "AT59"  !CDS_PN = "AT59";
"VSS<176>":   PN = "AT46"  !CDS_PN = "AT46";
"VSS<177>":   PN = "AT41"  !CDS_PN = "AT41";
"VSS<178>":   PN = "AT30"  !CDS_PN = "AT30";
"VSS<179>":   PN = "AT26"  !CDS_PN = "AT26";
"VSS<180>":   PN = "AT22"  !CDS_PN = "AT22";
"VSS<181>":   PN = "AT18"  !CDS_PN = "AT18";
"VSS<182>":   PN = "AT15"  !CDS_PN = "AT15";
"VSS<183>":   PN = "AT11"  !CDS_PN = "AT11";
"VSS<184>":   PN = "AT7"  !CDS_PN = "AT7";
"VSS<185>":   PN = "AR72"  !CDS_PN = "AR72";
"VSS<186>":   PN = "AR70"  !CDS_PN = "AR70";
"VSS<187>":   PN = "AR68"  !CDS_PN = "AR68";
"VSS<188>":   PN = "AR65"  !CDS_PN = "AR65";
"VSS<189>":   PN = "AR58"  !CDS_PN = "AR58";
"VSS<190>":   PN = "AR50"  !CDS_PN = "AR50";
"VSS<191>":   PN = "AR5"  !CDS_PN = "AR5";
"VSS<192>":   PN = "AP66"  !CDS_PN = "AP66";
"VSS<193>":   PN = "AP52"  !CDS_PN = "AP52";
"VSS<194>":   PN = "AP46"  !CDS_PN = "AP46";
"VSS<195>":   PN = "AP41"  !CDS_PN = "AP41";
"VSS<196>":   PN = "AP4"  !CDS_PN = "AP4";
"VSS<197>":   PN = "AP30"  !CDS_PN = "AP30";
"VSS<198>":   PN = "AP26"  !CDS_PN = "AP26";
"VSS<199>":   PN = "AP2"  !CDS_PN = "AP2";
"VSS<200>":   PN = "AN9"  !CDS_PN = "AN9";
"VSS<201>":   PN = "AN58"  !CDS_PN = "AN58";
"VSS<202>":   PN = "AN5"  !CDS_PN = "AN5";
"VSS<203>":   PN = "AN20"  !CDS_PN = "AN20";
"VSS<204>":   PN = "AP22"  !CDS_PN = "AP22";
"VSS<205>":   PN = "AN68"  !CDS_PN = "AN68";
"VSS<206>":   PN = "AN17"  !CDS_PN = "AN17";
"VSS<207>":   PN = "AN13"  !CDS_PN = "AN13";
"VSS<208>":   PN = "AM46"  !CDS_PN = "AM46";
"VSS<209>":   PN = "AM41"  !CDS_PN = "AM41";
"VSS<210>":   PN = "AM30"  !CDS_PN = "AM30";
"VSS<211>":   PN = "AM26"  !CDS_PN = "AM26";
"VSS<212>":   PN = "AL72"  !CDS_PN = "AL72";
"VSS<213>":   PN = "AL70"  !CDS_PN = "AL70";
"VSS<214>":   PN = "AL68"  !CDS_PN = "AL68";
BODY = "LBG_CORE_QAT_EXT_D","I17": #LOCATION = "U7C1" !CDS_LOCATION = "U7C1" #SEC = "12" !CDS_SEC = "12";
"VSS<215>":   PN = "AL59"  !CDS_PN = "AL59";
"VSS<216>":   PN = "AL52"  !CDS_PN = "AL52";
"VSS<217>":   PN = "AL5"  !CDS_PN = "AL5";
"VSS<218>":   PN = "AL22"  !CDS_PN = "AL22";
"VSS<219>":   PN = "AK71"  !CDS_PN = "AK71";
"VSS<220>":   PN = "AK69"  !CDS_PN = "AK69";
"VSS<221>":   PN = "AK61"  !CDS_PN = "AK61";
"VSS<222>":   PN = "AK58"  !CDS_PN = "AK58";
"VSS<223>":   PN = "AK48"  !CDS_PN = "AK48";
"VSS<224>":   PN = "AK46"  !CDS_PN = "AK46";
"VSS<225>":   PN = "AK41"  !CDS_PN = "AK41";
"VSS<226>":   PN = "AK26"  !CDS_PN = "AK26";
"VSS<227>":   PN = "AJ7"  !CDS_PN = "AJ7";
"VSS<228>":   PN = "AJ68"  !CDS_PN = "AJ68";
"VSS<229>":   PN = "AJ66"  !CDS_PN = "AJ66";
"VSS<230>":   PN = "AJ59"  !CDS_PN = "AJ59";
"VSS<231>":   PN = "AJ52"  !CDS_PN = "AJ52";
"VSS<232>":   PN = "AJ5"  !CDS_PN = "AJ5";
"VSS<233>":   PN = "AJ41"  !CDS_PN = "AJ41";
"VSS<234>":   PN = "AJ39"  !CDS_PN = "AJ39";
"VSS<235>":   PN = "AJ37"  !CDS_PN = "AJ37";
"VSS<236>":   PN = "AJ36"  !CDS_PN = "AJ36";
"VSS<237>":   PN = "AJ34"  !CDS_PN = "AJ34";
"VSS<238>":   PN = "AJ30"  !CDS_PN = "AJ30";
"VSS<239>":   PN = "AJ26"  !CDS_PN = "AJ26";
"VSS<240>":   PN = "AJ22"  !CDS_PN = "AJ22";
"VSS<241>":   PN = "AJ18"  !CDS_PN = "AJ18";
"VSS<242>":   PN = "AJ15"  !CDS_PN = "AJ15";
"VSS<243>":   PN = "AK30"  !CDS_PN = "AK30";
"VSS<244>":   PN = "AJ56"  !CDS_PN = "AJ56";
"VSS<245>":   PN = "AJ32"  !CDS_PN = "AJ32";
"VSS<246>":   PN = "AJ11"  !CDS_PN = "AJ11";
"VSS<247>":   PN = "AH20"  !CDS_PN = "AH20";
"VSS<248>":   PN = "AG66"  !CDS_PN = "AG66";
"VSS<249>":   PN = "AG59"  !CDS_PN = "AG59";
"VSS<250>":   PN = "AG56"  !CDS_PN = "AG56";
"VSS<251>":   PN = "AG52"  !CDS_PN = "AG52";
"VSS<252>":   PN = "AG43"  !CDS_PN = "AG43";
"VSS<253>":   PN = "AG41"  !CDS_PN = "AG41";
"VSS<254>":   PN = "AG30"  !CDS_PN = "AG30";
"VSS<255>":   PN = "AG26"  !CDS_PN = "AG26";
"VSS<256>":   PN = "AF68"  !CDS_PN = "AF68";
"VSS<257>":   PN = "AF3"  !CDS_PN = "AF3";
"VSS<258>":   PN = "AF24"  !CDS_PN = "AF24";
"VSS<259>":   PN = "AF17"  !CDS_PN = "AF17";
"VSS<260>":   PN = "AF9"  !CDS_PN = "AF9";
"VSS<261>":   PN = "AF5"  !CDS_PN = "AF5";
"VSS<262>":   PN = "AF13"  !CDS_PN = "AF13";
"VSS<263>":   PN = "AF1"  !CDS_PN = "AF1";
"VSS<264>":   PN = "AE66"  !CDS_PN = "AE66";
"VSS<265>":   PN = "AE63"  !CDS_PN = "AE63";
"VSS<266>":   PN = "AE59"  !CDS_PN = "AE59";
"VSS<267>":   PN = "AE56"  !CDS_PN = "AE56";
"VSS<268>":   PN = "AE52"  !CDS_PN = "AE52";
"VSS<269>":   PN = "AE48"  !CDS_PN = "AE48";
"VSS<270>":   PN = "J18"  !CDS_PN = "J18";
"VSS<271>":   PN = "AE29"  !CDS_PN = "AE29";
"VSS<272>":   PN = "AD68"  !CDS_PN = "AD68";
"VSS<273>":   PN = "AD65"  !CDS_PN = "AD65";
"VSS<274>":   PN = "AD5"  !CDS_PN = "AD5";
"VSS<275>":   PN = "AC7"  !CDS_PN = "AC7";
"VSS<276>":   PN = "AC66"  !CDS_PN = "AC66";
"VSS<277>":   PN = "AC63"  !CDS_PN = "AC63";
"VSS<278>":   PN = "AC59"  !CDS_PN = "AC59";
"VSS<279>":   PN = "AC52"  !CDS_PN = "AC52";
"VSS<280>":   PN = "AC48"  !CDS_PN = "AC48";
"VSS<281>":   PN = "AC46"  !CDS_PN = "AC46";
"VSS<282>":   PN = "AC43"  !CDS_PN = "AC43";
"VSS<283>":   PN = "AC27"  !CDS_PN = "AC27";
"VSS<284>":   PN = "AD58"  !CDS_PN = "AD58";
"VSS<285>":   PN = "AC45"  !CDS_PN = "AC45";
"VSS<286>":   PN = "AC22"  !CDS_PN = "AC22";
"VSS<287>":   PN = "AC18"  !CDS_PN = "AC18";
"VSS<288>":   PN = "AC15"  !CDS_PN = "AC15";
"VSS<289>":   PN = "AC11"  !CDS_PN = "AC11";
"VSS<290>":   PN = "AB72"  !CDS_PN = "AB72";
"VSS<291>":   PN = "AB70"  !CDS_PN = "AB70";
"VSS<292>":   PN = "AB68"  !CDS_PN = "AB68";
"VSS<293>":   PN = "AB5"  !CDS_PN = "AB5";
"VSS<294>":   PN = "AA48"  !CDS_PN = "AA48";
"VSS<295>":   PN = "AA43"  !CDS_PN = "AA43";
"VSS<296>":   PN = "AA27"  !CDS_PN = "AA27";
"VSS<297>":   PN = "AA26"  !CDS_PN = "AA26";
"VSS<298>":   PN = "Y68"  !CDS_PN = "Y68";
"VSS<299>":   PN = "Y63"  !CDS_PN = "Y63";
"VSS<300>":   PN = "Y59"  !CDS_PN = "Y59";
"VSS<301>":   PN = "Y52"  !CDS_PN = "Y52";
"VSS<302>":   PN = "Y5"  !CDS_PN = "Y5";
"VSS<303>":   PN = "Y48"  !CDS_PN = "Y48";
"VSS<304>":   PN = "Y27"  !CDS_PN = "Y27";
"VSS<305>":   PN = "Y22"  !CDS_PN = "Y22";
"VSS<306>":   PN = "W9"  !CDS_PN = "W9";
"VSS<307>":   PN = "W61"  !CDS_PN = "W61";
"VSS<308>":   PN = "Y43"  !CDS_PN = "Y43";
"VSS<309>":   PN = "AA50"  !CDS_PN = "AA50";
"VSS<310>":   PN = "W24"  !CDS_PN = "W24";
"VSS<311>":   PN = "W20"  !CDS_PN = "W20";
"VSS<312>":   PN = "W17"  !CDS_PN = "W17";
"VSS<313>":   PN = "W13"  !CDS_PN = "W13";
"VSS<314>":   PN = "V68"  !CDS_PN = "V68";
"VSS<315>":   PN = "V66"  !CDS_PN = "V66";
"VSS<316>":   PN = "W58"  !CDS_PN = "W58";
"VSS<317>":   PN = "V52"  !CDS_PN = "V52";
"VSS<318>":   PN = "V5"  !CDS_PN = "V5";
"VSS<319>":   PN = "V48"  !CDS_PN = "V48";
"VSS<320>":   PN = "V26"  !CDS_PN = "V26";
"VSS<321>":   PN = "U58"  !CDS_PN = "U58";
"VSS<322>":   PN = "AG46"  !CDS_PN = "AG46";
"VSS<323>":   PN = "AF50"  !CDS_PN = "AF50";
"VSS<324>":   PN = "T7"  !CDS_PN = "T7";
"VSS<325>":   PN = "T66"  !CDS_PN = "T66";
"VSS<326>":   PN = "T52"  !CDS_PN = "T52";
"VSS<327>":   PN = "T48"  !CDS_PN = "T48";
"VSS<328>":   PN = "AJ45"  !CDS_PN = "AJ45";
"VSS<329>":   PN = "T40"  !CDS_PN = "T40";
"VSS<330>":   PN = "T37"  !CDS_PN = "T37";
"VSS<331>":   PN = "T33"  !CDS_PN = "T33";
"VSS<332>":   PN = "T29"  !CDS_PN = "T29";
"VSS<333>":   PN = "T26"  !CDS_PN = "T26";
"VSS<334>":   PN = "T22"  !CDS_PN = "T22";
"VSS<335>":   PN = "T18"  !CDS_PN = "T18";
"VSS<336>":   PN = "T15"  !CDS_PN = "T15";
"VSS<337>":   PN = "T11"  !CDS_PN = "T11";
"VSS<338>":   PN = "R68"  !CDS_PN = "R68";
"VSS<339>":   PN = "R58"  !CDS_PN = "R58";
"VSS<340>":   PN = "T56"  !CDS_PN = "T56";
"VSS<341>":   PN = "R54"  !CDS_PN = "R54";
"VSS<342>":   PN = "R50"  !CDS_PN = "R50";
"VSS<343>":   PN = "R5"  !CDS_PN = "R5";
"VSS<344>":   PN = "U42"  !CDS_PN = "U42";
"VSS<345>":   PN = "R27"  !CDS_PN = "R27";
"VSS<346>":   PN = "P63"  !CDS_PN = "P63";
"VSS<347>":   PN = "AE43"  !CDS_PN = "AE43";
"VSS<348>":   PN = "N9"  !CDS_PN = "N9";
"VSS<349>":   PN = "N68"  !CDS_PN = "N68";
"VSS<350>":   PN = "R38"  !CDS_PN = "R38";
"VSS<351>":   PN = "N5"  !CDS_PN = "N5";
"VSS<352>":   PN = "N46"  !CDS_PN = "N46";
"VSS<353>":   PN = "N38"  !CDS_PN = "N38";
"VSS<354>":   PN = "N35"  !CDS_PN = "N35";
DRAWING = "@baseboard_fab2_lib.baseboard_fab2(sch_1):page125";
BODY = "RES","I11": #LOCATION = "R2R11" !CDS_LOCATION = "R2R11" &SEC = "1" #&CDS_SEC = "1";
"A":   PN = "1"  !CDS_PN = "1";
"B":   PN = "2"  !CDS_PN = "2";
BODY = "RES","I21": #LOCATION = "R8E6" !CDS_LOCATION = "R8E6" #SEC = "1" !CDS_SEC = "1";
"A":   PN = "1"  !CDS_PN = "1";
"B":   PN = "2"  !CDS_PN = "2";
BODY = "RES","I24": #LOCATION = "R8E4" !CDS_LOCATION = "R8E4" &SEC = "1" #&CDS_SEC = "1";
"A":   PN = "1"  !CDS_PN = "1";
"B":   PN = "2"  !CDS_PN = "2";
BODY = "RES","I40": #LOCATION = "R8C18" !CDS_LOCATION = "R8C18" &SEC = "1" #&CDS_SEC = "1";
"A":   PN = "1"  !CDS_PN = "1";
"B":   PN = "2"  !CDS_PN = "2";
BODY = "RES","I41": #LOCATION = "R8C17" !CDS_LOCATION = "R8C17" #SEC = "1" !CDS_SEC = "1";
"A":   PN = "1"  !CDS_PN = "1";
"B":   PN = "2"  !CDS_PN = "2";
BODY = "RES","I50": #LOCATION = "R8D5" !CDS_LOCATION = "R8D5" &SEC = "1" #&CDS_SEC = "1";
"A":   PN = "1"  !CDS_PN = "1";
"B":   PN = "2"  !CDS_PN = "2";
BODY = "RES","I60": #LOCATION = "R7D13" !CDS_LOCATION = "R7D13" &SEC = "1" #&CDS_SEC = "1";
"A":   PN = "1"  !CDS_PN = "1";
"B":   PN = "2"  !CDS_PN = "2";
BODY = "RES","I72": #LOCATION = "R3N2" !CDS_LOCATION = "R3N2" #SEC = "1" !CDS_SEC = "1";
"A":   PN = "1"  !CDS_PN = "1";
"B":   PN = "2"  !CDS_PN = "2";
BODY = "RES","I78": #LOCATION = "R3N17" !CDS_LOCATION = "R3N17" #SEC = "1" !CDS_SEC = "1";
"A":   PN = "1"  !CDS_PN = "1";
"B":   PN = "2"  !CDS_PN = "2";
BODY = "RES","I83": #LOCATION = "R2N14" !CDS_LOCATION = "R2N14" #SEC = "1" !CDS_SEC = "1";
"A":   PN = "1"  !CDS_PN = "1";
"B":   PN = "2"  !CDS_PN = "2";
BODY = "RES","I85": #LOCATION = "R8D16" !CDS_LOCATION = "R8D16" &SEC = "1" #&CDS_SEC = "1";
"A":   PN = "1"  !CDS_PN = "1";
"B":   PN = "2"  !CDS_PN = "2";
BODY = "RES","I86": #LOCATION = "R7D1" !CDS_LOCATION = "R7D1" &SEC = "1" #&CDS_SEC = "1";
"A":   PN = "1"  !CDS_PN = "1";
"B":   PN = "2"  !CDS_PN = "2";
BODY = "RES","I87": #LOCATION = "R8D13" !CDS_LOCATION = "R8D13" #SEC = "1" !CDS_SEC = "1";
"A":   PN = "1"  !CDS_PN = "1";
"B":   PN = "2"  !CDS_PN = "2";
BODY = "RES","I88": #LOCATION = "R2U30" !CDS_LOCATION = "R2U30" #SEC = "1" !CDS_SEC = "1";
"A":   PN = "1"  !CDS_PN = "1";
"B":   PN = "2"  !CDS_PN = "2";
BODY = "RES","I89": #LOCATION = "R2T1" !CDS_LOCATION = "R2T1" #SEC = "1" !CDS_SEC = "1";
"A":   PN = "1"  !CDS_PN = "1";
"B":   PN = "2"  !CDS_PN = "2";
DRAWING = "@baseboard_fab2_lib.baseboard_fab2(sch_1):page126";
BODY = "RES","I6": #LOCATION = "R7D19" !CDS_LOCATION = "R7D19" #SEC = "1" !CDS_SEC = "1";
"A":   PN = "1"  !CDS_PN = "1";
"B":   PN = "2"  !CDS_PN = "2";
BODY = "RES","I12": #LOCATION = "R1D35" !CDS_LOCATION = "R1D35" #SEC = "1" !CDS_SEC = "1";
"A":   PN = "1"  !CDS_PN = "1";
"B":   PN = "2"  !CDS_PN = "2";
BODY = "FET_N","I13": #LOCATION = "Q8E2" !CDS_LOCATION = "Q8E2" #SEC = "1" !CDS_SEC = "1";
"DRN":   PN = "3"  !CDS_PN = "3";
"GATE":   PN = "1"  !CDS_PN = "1";
"SRC":   PN = "2"  !CDS_PN = "2";
BODY = "RES","I20": #LOCATION = "R8C9" !CDS_LOCATION = "R8C9" #SEC = "1" !CDS_SEC = "1";
"A":   PN = "1"  !CDS_PN = "1";
"B":   PN = "2"  !CDS_PN = "2";
BODY = "RES","I22": #LOCATION = "R3P62" !CDS_LOCATION = "R3P62" #SEC = "1" !CDS_SEC = "1";
"A":   PN = "1"  !CDS_PN = "1";
"B":   PN = "2"  !CDS_PN = "2";
BODY = "RES","I23": #LOCATION = "R3P64" !CDS_LOCATION = "R3P64" #SEC = "1" !CDS_SEC = "1";
"A":   PN = "1"  !CDS_PN = "1";
"B":   PN = "2"  !CDS_PN = "2";
BODY = "RES","I27": #LOCATION = "R2N10" !CDS_LOCATION = "R2N10" #SEC = "1" !CDS_SEC = "1";
"A":   PN = "1"  !CDS_PN = "1";
"B":   PN = "2"  !CDS_PN = "2";
DRAWING = "@baseboard_fab2_lib.baseboard_fab2(sch_1):page127";
BODY = "FERRITE","I8": #LOCATION = "FB3M1" !CDS_LOCATION = "FB3M1" #SEC = "1" !CDS_SEC = "1";
"A":   PN = "1"  !CDS_PN = "1";
"B":   PN = "2"  !CDS_PN = "2";
BODY = "CAP_A","I9": #LOCATION = "C3M21" !CDS_LOCATION = "C3M21" #SEC = "1" !CDS_SEC = "1";
"A":   PN = "1"  !CDS_PN = "1";
"B":   PN = "2"  !CDS_PN = "2";
BODY = "FERRITE","I17": #LOCATION = "FB3M2" !CDS_LOCATION = "FB3M2" #SEC = "1" !CDS_SEC = "1";
"A":   PN = "1"  !CDS_PN = "1";
"B":   PN = "2"  !CDS_PN = "2";
BODY = "CAP_A","I18": #LOCATION = "C3M22" !CDS_LOCATION = "C3M22" #SEC = "1" !CDS_SEC = "1";
"A":   PN = "1"  !CDS_PN = "1";
"B":   PN = "2"  !CDS_PN = "2";
BODY = "FERRITE","I26": #LOCATION = "FB3M3" !CDS_LOCATION = "FB3M3" #SEC = "1" !CDS_SEC = "1";
"A":   PN = "1"  !CDS_PN = "1";
"B":   PN = "2"  !CDS_PN = "2";
BODY = "CAP_A","I27": #LOCATION = "C3M30" !CDS_LOCATION = "C3M30" #SEC = "1" !CDS_SEC = "1";
"A":   PN = "1"  !CDS_PN = "1";
"B":   PN = "2"  !CDS_PN = "2";
BODY = "CAP","I43": #LOCATION = "C2M5" !CDS_LOCATION = "C2M5" #SEC = "1" !CDS_SEC = "1";
"A":   PN = "1"  !CDS_PN = "1";
"B":   PN = "2"  !CDS_PN = "2";
BODY = "CAP_A","I44": #LOCATION = "C2M7" !CDS_LOCATION = "C2M7" #SEC = "1" !CDS_SEC = "1";
"A":   PN = "1"  !CDS_PN = "1";
"B":   PN = "2"  !CDS_PN = "2";
BODY = "FERRITE","I46": #LOCATION = "FB2M1" !CDS_LOCATION = "FB2M1" #SEC = "1" !CDS_SEC = "1";
"A":   PN = "1"  !CDS_PN = "1";
"B":   PN = "2"  !CDS_PN = "2";
BODY = "CAP","I49": #LOCATION = "C2M10" !CDS_LOCATION = "C2M10" #SEC = "1" !CDS_SEC = "1";
"A":   PN = "1"  !CDS_PN = "1";
"B":   PN = "2"  !CDS_PN = "2";
BODY = "CAP_A","I50": #LOCATION = "C2M9" !CDS_LOCATION = "C2M9" #SEC = "1" !CDS_SEC = "1";
"A":   PN = "1"  !CDS_PN = "1";
"B":   PN = "2"  !CDS_PN = "2";
BODY = "FERRITE","I56": #LOCATION = "FB3M4" !CDS_LOCATION = "FB3M4" #SEC = "1" !CDS_SEC = "1";
"A":   PN = "1"  !CDS_PN = "1";
"B":   PN = "2"  !CDS_PN = "2";
BODY = "CAP_A","I57": #LOCATION = "C3M31" !CDS_LOCATION = "C3M31" #SEC = "1" !CDS_SEC = "1";
"A":   PN = "1"  !CDS_PN = "1";
"B":   PN = "2"  !CDS_PN = "2";
BODY = "CAP","I64": #LOCATION = "C2N6" !CDS_LOCATION = "C2N6" #SEC = "1" !CDS_SEC = "1";
"A":   PN = "1"  !CDS_PN = "1";
"B":   PN = "2"  !CDS_PN = "2";
BODY = "CAP_A","I65": #LOCATION = "C2N5" !CDS_LOCATION = "C2N5" #SEC = "1" !CDS_SEC = "1";
"A":   PN = "1"  !CDS_PN = "1";
"B":   PN = "2"  !CDS_PN = "2";
BODY = "FERRITE","I69": #LOCATION = "FB2M2" !CDS_LOCATION = "FB2M2" #SEC = "1" !CDS_SEC = "1";
"A":   PN = "1"  !CDS_PN = "1";
"B":   PN = "2"  !CDS_PN = "2";
BODY = "INDUCTOR","I71": #LOCATION = "L2M1" !CDS_LOCATION = "L2M1" #SEC = "1" !CDS_SEC = "1";
"INA":   PN = "1"  !CDS_PN = "1";
"INB":   PN = "2"  !CDS_PN = "2";
BODY = "CAP_A","I74": #LOCATION = "C2M8" !CDS_LOCATION = "C2M8" #SEC = "1" !CDS_SEC = "1";
"A":   PN = "1"  !CDS_PN = "1";
"B":   PN = "2"  !CDS_PN = "2";
BODY = "CAP_A","I76": #LOCATION = "C2M6" !CDS_LOCATION = "C2M6" #SEC = "1" !CDS_SEC = "1";
"A":   PN = "1"  !CDS_PN = "1";
"B":   PN = "2"  !CDS_PN = "2";
BODY = "CAP_A","I78": #LOCATION = "C2M25" !CDS_LOCATION = "C2M25" #SEC = "1" !CDS_SEC = "1";
"A":   PN = "1"  !CDS_PN = "1";
"B":   PN = "2"  !CDS_PN = "2";
BODY = "CAP_A","I80": #LOCATION = "C3M29" !CDS_LOCATION = "C3M29" #SEC = "1" !CDS_SEC = "1";
"A":   PN = "1"  !CDS_PN = "1";
"B":   PN = "2"  !CDS_PN = "2";
BODY = "CAP","I81": #LOCATION = "C3M24" !CDS_LOCATION = "C3M24" #SEC = "1" !CDS_SEC = "1";
"A":   PN = "1"  !CDS_PN = "1";
"B":   PN = "2"  !CDS_PN = "2";
BODY = "CAP","I82": #LOCATION = "C3M23" !CDS_LOCATION = "C3M23" #SEC = "1" !CDS_SEC = "1";
"A":   PN = "1"  !CDS_PN = "1";
"B":   PN = "2"  !CDS_PN = "2";
BODY = "CAP_A","I83": #LOCATION = "C3M27" !CDS_LOCATION = "C3M27" #SEC = "1" !CDS_SEC = "1";
"A":   PN = "1"  !CDS_PN = "1";
"B":   PN = "2"  !CDS_PN = "2";
BODY = "CAP_A","I84": #LOCATION = "C3M20" !CDS_LOCATION = "C3M20" #SEC = "1" !CDS_SEC = "1";
"A":   PN = "1"  !CDS_PN = "1";
"B":   PN = "2"  !CDS_PN = "2";
BODY = "CAP","I85": #LOCATION = "C3M18" !CDS_LOCATION = "C3M18" #SEC = "1" !CDS_SEC = "1";
"A":   PN = "1"  !CDS_PN = "1";
"B":   PN = "2"  !CDS_PN = "2";
BODY = "CAP","I86": #LOCATION = "C3M17" !CDS_LOCATION = "C3M17" #SEC = "1" !CDS_SEC = "1";
"A":   PN = "1"  !CDS_PN = "1";
"B":   PN = "2"  !CDS_PN = "2";
BODY = "CAP_A","I87": #LOCATION = "C3M19" !CDS_LOCATION = "C3M19" #SEC = "1" !CDS_SEC = "1";
"A":   PN = "1"  !CDS_PN = "1";
"B":   PN = "2"  !CDS_PN = "2";
DRAWING = "@baseboard_fab2_lib.baseboard_fab2(sch_1):page129";
BODY = "CAP","I35": #LOCATION = "C7B25" !CDS_LOCATION = "C7B25" &SEC = "1" #&CDS_SEC = "1";
"A":   PN = "1"  !CDS_PN = "1";
"B":   PN = "2"  !CDS_PN = "2";
BODY = "CAP","I69": #LOCATION = "C7B27" !CDS_LOCATION = "C7B27" &SEC = "1" #&CDS_SEC = "1";
"A":   PN = "1"  !CDS_PN = "1";
"B":   PN = "2"  !CDS_PN = "2";
BODY = "CAP","I70": #LOCATION = "C7B28" !CDS_LOCATION = "C7B28" &SEC = "1" #&CDS_SEC = "1";
"A":   PN = "1"  !CDS_PN = "1";
"B":   PN = "2"  !CDS_PN = "2";
BODY = "CAP","I71": #LOCATION = "C7C2" !CDS_LOCATION = "C7C2" &SEC = "1" #&CDS_SEC = "1";
"A":   PN = "1"  !CDS_PN = "1";
"B":   PN = "2"  !CDS_PN = "2";
BODY = "CAP","I72": #LOCATION = "C3M40" !CDS_LOCATION = "C3M40" &SEC = "1" #&CDS_SEC = "1";
"A":   PN = "1"  !CDS_PN = "1";
"B":   PN = "2"  !CDS_PN = "2";
BODY = "CAP","I73": #LOCATION = "C3M37" !CDS_LOCATION = "C3M37" &SEC = "1" #&CDS_SEC = "1";
"A":   PN = "1"  !CDS_PN = "1";
"B":   PN = "2"  !CDS_PN = "2";
BODY = "CAP","I74": #LOCATION = "C3N9" !CDS_LOCATION = "C3N9" &SEC = "1" #&CDS_SEC = "1";
"A":   PN = "1"  !CDS_PN = "1";
"B":   PN = "2"  !CDS_PN = "2";
BODY = "CAP","I75": #LOCATION = "C3N8" !CDS_LOCATION = "C3N8" &SEC = "1" #&CDS_SEC = "1";
"A":   PN = "1"  !CDS_PN = "1";
"B":   PN = "2"  !CDS_PN = "2";
BODY = "CAP","I76": #LOCATION = "C7C3" !CDS_LOCATION = "C7C3" &SEC = "1" #&CDS_SEC = "1";
"A":   PN = "1"  !CDS_PN = "1";
"B":   PN = "2"  !CDS_PN = "2";
BODY = "CAP","I77": #LOCATION = "C7C1" !CDS_LOCATION = "C7C1" &SEC = "1" #&CDS_SEC = "1";
"A":   PN = "1"  !CDS_PN = "1";
"B":   PN = "2"  !CDS_PN = "2";
BODY = "CAP","I78": #LOCATION = "C7B29" !CDS_LOCATION = "C7B29" &SEC = "1" #&CDS_SEC = "1";
"A":   PN = "1"  !CDS_PN = "1";
"B":   PN = "2"  !CDS_PN = "2";
BODY = "CAP","I79": #LOCATION = "C7B26" !CDS_LOCATION = "C7B26" &SEC = "1" #&CDS_SEC = "1";
"A":   PN = "1"  !CDS_PN = "1";
"B":   PN = "2"  !CDS_PN = "2";
BODY = "CAP","I80": #LOCATION = "C3M44" !CDS_LOCATION = "C3M44" &SEC = "1" #&CDS_SEC = "1";
"A":   PN = "1"  !CDS_PN = "1";
"B":   PN = "2"  !CDS_PN = "2";
BODY = "CAP","I81": #LOCATION = "C3M41" !CDS_LOCATION = "C3M41" &SEC = "1" #&CDS_SEC = "1";
"A":   PN = "1"  !CDS_PN = "1";
"B":   PN = "2"  !CDS_PN = "2";
BODY = "CAP","I82": #LOCATION = "C3M45" !CDS_LOCATION = "C3M45" &SEC = "1" #&CDS_SEC = "1";
"A":   PN = "1"  !CDS_PN = "1";
"B":   PN = "2"  !CDS_PN = "2";
BODY = "CAP","I83": #LOCATION = "C3N13" !CDS_LOCATION = "C3N13" &SEC = "1" #&CDS_SEC = "1";
"A":   PN = "1"  !CDS_PN = "1";
"B":   PN = "2"  !CDS_PN = "2";
DRAWING = "@baseboard_fab2_lib.baseboard_fab2(sch_1):page130";
BODY = "CAP","I2": #LOCATION = "C7D2" !CDS_LOCATION = "C7D2" #SEC = "1" !CDS_SEC = "1";
"A":   PN = "1"  !CDS_PN = "1";
"B":   PN = "2"  !CDS_PN = "2";
BODY = "CAP_A","I4": #LOCATION = "C2N26" !CDS_LOCATION = "C2N26" &SEC = "1" #&CDS_SEC = "1";
"A":   PN = "1"  !CDS_PN = "1";
"B":   PN = "2"  !CDS_PN = "2";
BODY = "CAP_A","I7": #LOCATION = "C2N19" !CDS_LOCATION = "C2N19" &SEC = "1" #&CDS_SEC = "1";
"A":   PN = "1"  !CDS_PN = "1";
"B":   PN = "2"  !CDS_PN = "2";
BODY = "CAP","I8": #LOCATION = "C2N24" !CDS_LOCATION = "C2N24" &SEC = "1" #&CDS_SEC = "1";
"A":   PN = "1"  !CDS_PN = "1";
"B":   PN = "2"  !CDS_PN = "2";
BODY = "CAP","I9": #LOCATION = "C2N22" !CDS_LOCATION = "C2N22" &SEC = "1" #&CDS_SEC = "1";
"A":   PN = "1"  !CDS_PN = "1";
"B":   PN = "2"  !CDS_PN = "2";
BODY = "CAP_A","I12": #LOCATION = "C2N20" !CDS_LOCATION = "C2N20" &SEC = "1" #&CDS_SEC = "1";
"A":   PN = "1"  !CDS_PN = "1";
"B":   PN = "2"  !CDS_PN = "2";
BODY = "CAP","I15": #LOCATION = "C2N21" !CDS_LOCATION = "C2N21" &SEC = "1" #&CDS_SEC = "1";
"A":   PN = "1"  !CDS_PN = "1";
"B":   PN = "2"  !CDS_PN = "2";
BODY = "CAP_A","I16": #LOCATION = "C3N29" !CDS_LOCATION = "C3N29" &SEC = "1" #&CDS_SEC = "1";
"A":   PN = "1"  !CDS_PN = "1";
"B":   PN = "2"  !CDS_PN = "2";
BODY = "CAP","I19": #LOCATION = "C8C3" !CDS_LOCATION = "C8C3" &SEC = "1" #&CDS_SEC = "1";
"A":   PN = "1"  !CDS_PN = "1";
"B":   PN = "2"  !CDS_PN = "2";
BODY = "CAP","I20": #LOCATION = "C8C4" !CDS_LOCATION = "C8C4" &SEC = "1" #&CDS_SEC = "1";
"A":   PN = "1"  !CDS_PN = "1";
"B":   PN = "2"  !CDS_PN = "2";
BODY = "CAP","I21": #LOCATION = "C8C5" !CDS_LOCATION = "C8C5" &SEC = "1" #&CDS_SEC = "1";
"A":   PN = "1"  !CDS_PN = "1";
"B":   PN = "2"  !CDS_PN = "2";
BODY = "CAP","I22": #LOCATION = "C8C6" !CDS_LOCATION = "C8C6" &SEC = "1" #&CDS_SEC = "1";
"A":   PN = "1"  !CDS_PN = "1";
"B":   PN = "2"  !CDS_PN = "2";
BODY = "CAP","I24": #LOCATION = "C2N23" !CDS_LOCATION = "C2N23" &SEC = "1" #&CDS_SEC = "1";
"A":   PN = "1"  !CDS_PN = "1";
"B":   PN = "2"  !CDS_PN = "2";
BODY = "CAP","I25": #LOCATION = "C2N14" !CDS_LOCATION = "C2N14" &SEC = "1" #&CDS_SEC = "1";
"A":   PN = "1"  !CDS_PN = "1";
"B":   PN = "2"  !CDS_PN = "2";
BODY = "CAP","I28": #LOCATION = "C2N17" !CDS_LOCATION = "C2N17" &SEC = "1" #&CDS_SEC = "1";
"A":   PN = "1"  !CDS_PN = "1";
"B":   PN = "2"  !CDS_PN = "2";
BODY = "CAP_A","I29": #LOCATION = "C2N18" !CDS_LOCATION = "C2N18" &SEC = "1" #&CDS_SEC = "1";
"A":   PN = "1"  !CDS_PN = "1";
"B":   PN = "2"  !CDS_PN = "2";
BODY = "CAP_A","I30": #LOCATION = "C8B2" !CDS_LOCATION = "C8B2" &SEC = "1" #&CDS_SEC = "1";
"A":   PN = "1"  !CDS_PN = "1";
"B":   PN = "2"  !CDS_PN = "2";
BODY = "CAP_A","I32": #LOCATION = "C8B3" !CDS_LOCATION = "C8B3" &SEC = "1" #&CDS_SEC = "1";
"A":   PN = "1"  !CDS_PN = "1";
"B":   PN = "2"  !CDS_PN = "2";
BODY = "CAP_A","I34": #LOCATION = "C2N25" !CDS_LOCATION = "C2N25" &SEC = "1" #&CDS_SEC = "1";
"A":   PN = "1"  !CDS_PN = "1";
"B":   PN = "2"  !CDS_PN = "2";
BODY = "CAP_A","I37": #LOCATION = "C2M16" !CDS_LOCATION = "C2M16" &SEC = "1" #&CDS_SEC = "1";
"A":   PN = "1"  !CDS_PN = "1";
"B":   PN = "2"  !CDS_PN = "2";
BODY = "CAP_A","I38": #LOCATION = "C7D3" !CDS_LOCATION = "C7D3" &SEC = "1" #&CDS_SEC = "1";
"A":   PN = "1"  !CDS_PN = "1";
"B":   PN = "2"  !CDS_PN = "2";
BODY = "CAP_A","I39": #LOCATION = "C8B4" !CDS_LOCATION = "C8B4" &SEC = "1" #&CDS_SEC = "1";
"A":   PN = "1"  !CDS_PN = "1";
"B":   PN = "2"  !CDS_PN = "2";
BODY = "CAP_A","I41": #LOCATION = "C8B1" !CDS_LOCATION = "C8B1" &SEC = "1" #&CDS_SEC = "1";
"A":   PN = "1"  !CDS_PN = "1";
"B":   PN = "2"  !CDS_PN = "2";
BODY = "CAP_A","I42": #LOCATION = "C3N23" !CDS_LOCATION = "C3N23" &SEC = "1" #&CDS_SEC = "1";
"A":   PN = "1"  !CDS_PN = "1";
"B":   PN = "2"  !CDS_PN = "2";
BODY = "CAP_A","I43": #LOCATION = "C2M1" !CDS_LOCATION = "C2M1" &SEC = "1" #&CDS_SEC = "1";
"A":   PN = "1"  !CDS_PN = "1";
"B":   PN = "2"  !CDS_PN = "2";
BODY = "CAP_A","I45": #LOCATION = "C2M2" !CDS_LOCATION = "C2M2" &SEC = "1" #&CDS_SEC = "1";
"A":   PN = "1"  !CDS_PN = "1";
"B":   PN = "2"  !CDS_PN = "2";
BODY = "CAP_A","I47": #LOCATION = "C2N15" !CDS_LOCATION = "C2N15" &SEC = "1" #&CDS_SEC = "1";
"A":   PN = "1"  !CDS_PN = "1";
"B":   PN = "2"  !CDS_PN = "2";
BODY = "CAP_A","I49": #LOCATION = "C3N21" !CDS_LOCATION = "C3N21" &SEC = "1" #&CDS_SEC = "1";
"A":   PN = "1"  !CDS_PN = "1";
"B":   PN = "2"  !CDS_PN = "2";
BODY = "CAP_A","I50": #LOCATION = "C3N25" !CDS_LOCATION = "C3N25" &SEC = "1" #&CDS_SEC = "1";
"A":   PN = "1"  !CDS_PN = "1";
"B":   PN = "2"  !CDS_PN = "2";
BODY = "CAP_A","I52": #LOCATION = "C2N16" !CDS_LOCATION = "C2N16" &SEC = "1" #&CDS_SEC = "1";
"A":   PN = "1"  !CDS_PN = "1";
"B":   PN = "2"  !CDS_PN = "2";
BODY = "CAP_A","I53": #LOCATION = "C3N22" !CDS_LOCATION = "C3N22" &SEC = "1" #&CDS_SEC = "1";
"A":   PN = "1"  !CDS_PN = "1";
"B":   PN = "2"  !CDS_PN = "2";
DRAWING = "@baseboard_fab2_lib.baseboard_fab2(sch_1):page131";
BODY = "CAP_A","I1": #LOCATION = "C7B15" !CDS_LOCATION = "C7B15" &SEC = "1" #&CDS_SEC = "1";
"A":   PN = "1"  !CDS_PN = "1";
"B":   PN = "2"  !CDS_PN = "2";
BODY = "CAP_A","I2": #LOCATION = "C7B19" !CDS_LOCATION = "C7B19" &SEC = "1" #&CDS_SEC = "1";
"A":   PN = "1"  !CDS_PN = "1";
"B":   PN = "2"  !CDS_PN = "2";
BODY = "CAP_A","I3": #LOCATION = "C7B16" !CDS_LOCATION = "C7B16" &SEC = "1" #&CDS_SEC = "1";
"A":   PN = "1"  !CDS_PN = "1";
"B":   PN = "2"  !CDS_PN = "2";
BODY = "CAP_A","I4": #LOCATION = "C7B21" !CDS_LOCATION = "C7B21" &SEC = "1" #&CDS_SEC = "1";
"A":   PN = "1"  !CDS_PN = "1";
"B":   PN = "2"  !CDS_PN = "2";
BODY = "CAP_A","I6": #LOCATION = "C7B20" !CDS_LOCATION = "C7B20" &SEC = "1" #&CDS_SEC = "1";
"A":   PN = "1"  !CDS_PN = "1";
"B":   PN = "2"  !CDS_PN = "2";
BODY = "CAP_A","I7": #LOCATION = "C7B23" !CDS_LOCATION = "C7B23" &SEC = "1" #&CDS_SEC = "1";
"A":   PN = "1"  !CDS_PN = "1";
"B":   PN = "2"  !CDS_PN = "2";
BODY = "CAP_A","I8": #LOCATION = "C8B10" !CDS_LOCATION = "C8B10" &SEC = "1" #&CDS_SEC = "1";
"A":   PN = "1"  !CDS_PN = "1";
"B":   PN = "2"  !CDS_PN = "2";
BODY = "CAP_A","I10": #LOCATION = "C7B22" !CDS_LOCATION = "C7B22" &SEC = "1" #&CDS_SEC = "1";
"A":   PN = "1"  !CDS_PN = "1";
"B":   PN = "2"  !CDS_PN = "2";
BODY = "CAP_A","I11": #LOCATION = "C7B24" !CDS_LOCATION = "C7B24" &SEC = "1" #&CDS_SEC = "1";
"A":   PN = "1"  !CDS_PN = "1";
"B":   PN = "2"  !CDS_PN = "2";
BODY = "CAP_A","I12": #LOCATION = "C7B18" !CDS_LOCATION = "C7B18" &SEC = "1" #&CDS_SEC = "1";
"A":   PN = "1"  !CDS_PN = "1";
"B":   PN = "2"  !CDS_PN = "2";
BODY = "CAP_A","I14": #LOCATION = "C8B9" !CDS_LOCATION = "C8B9" &SEC = "1" #&CDS_SEC = "1";
"A":   PN = "1"  !CDS_PN = "1";
"B":   PN = "2"  !CDS_PN = "2";
BODY = "CAP_A","I15": #LOCATION = "C8B11" !CDS_LOCATION = "C8B11" &SEC = "1" #&CDS_SEC = "1";
"A":   PN = "1"  !CDS_PN = "1";
"B":   PN = "2"  !CDS_PN = "2";
BODY = "CAP_A","I16": #LOCATION = "C8B14" !CDS_LOCATION = "C8B14" &SEC = "1" #&CDS_SEC = "1";
"A":   PN = "1"  !CDS_PN = "1";
"B":   PN = "2"  !CDS_PN = "2";
BODY = "CAP_A","I18": #LOCATION = "C7B17" !CDS_LOCATION = "C7B17" &SEC = "1" #&CDS_SEC = "1";
"A":   PN = "1"  !CDS_PN = "1";
"B":   PN = "2"  !CDS_PN = "2";
BODY = "CAP_A","I20": #LOCATION = "C8B13" !CDS_LOCATION = "C8B13" &SEC = "1" #&CDS_SEC = "1";
"A":   PN = "1"  !CDS_PN = "1";
"B":   PN = "2"  !CDS_PN = "2";
BODY = "CAP","I22": #LOCATION = "C8B16" !CDS_LOCATION = "C8B16" &SEC = "1" #&CDS_SEC = "1";
"A":   PN = "1"  !CDS_PN = "1";
"B":   PN = "2"  !CDS_PN = "2";
BODY = "CAP","I24": #LOCATION = "C8B15" !CDS_LOCATION = "C8B15" &SEC = "1" #&CDS_SEC = "1";
"A":   PN = "1"  !CDS_PN = "1";
"B":   PN = "2"  !CDS_PN = "2";
BODY = "CAP_A","I27": #LOCATION = "C2M22" !CDS_LOCATION = "C2M22" &SEC = "1" #&CDS_SEC = "1";
"A":   PN = "1"  !CDS_PN = "1";
"B":   PN = "2"  !CDS_PN = "2";
BODY = "CAP_A","I28": #LOCATION = "C2M21" !CDS_LOCATION = "C2M21" &SEC = "1" #&CDS_SEC = "1";
"A":   PN = "1"  !CDS_PN = "1";
"B":   PN = "2"  !CDS_PN = "2";
BODY = "CAP_A","I29": #LOCATION = "C2M18" !CDS_LOCATION = "C2M18" &SEC = "1" #&CDS_SEC = "1";
"A":   PN = "1"  !CDS_PN = "1";
"B":   PN = "2"  !CDS_PN = "2";
BODY = "CAP_A","I31": #LOCATION = "C2M19" !CDS_LOCATION = "C2M19" &SEC = "1" #&CDS_SEC = "1";
"A":   PN = "1"  !CDS_PN = "1";
"B":   PN = "2"  !CDS_PN = "2";
BODY = "CAP_A","I32": #LOCATION = "C3M38" !CDS_LOCATION = "C3M38" &SEC = "1" #&CDS_SEC = "1";
"A":   PN = "1"  !CDS_PN = "1";
"B":   PN = "2"  !CDS_PN = "2";
BODY = "CAP","I34": #LOCATION = "C2M17" !CDS_LOCATION = "C2M17" &SEC = "1" #&CDS_SEC = "1";
"A":   PN = "1"  !CDS_PN = "1";
"B":   PN = "2"  !CDS_PN = "2";
BODY = "CAP","I35": #LOCATION = "C2M11" !CDS_LOCATION = "C2M11" &SEC = "1" #&CDS_SEC = "1";
"A":   PN = "1"  !CDS_PN = "1";
"B":   PN = "2"  !CDS_PN = "2";
BODY = "CAP","I37": #LOCATION = "C8A13" !CDS_LOCATION = "C8A13" &SEC = "1" #&CDS_SEC = "1";
"A":   PN = "1"  !CDS_PN = "1";
"B":   PN = "2"  !CDS_PN = "2";
BODY = "CAP_A","I39": #LOCATION = "C2M20" !CDS_LOCATION = "C2M20" &SEC = "1" #&CDS_SEC = "1";
"A":   PN = "1"  !CDS_PN = "1";
"B":   PN = "2"  !CDS_PN = "2";
BODY = "CAP_A","I40": #LOCATION = "C2N13" !CDS_LOCATION = "C2N13" &SEC = "1" #&CDS_SEC = "1";
"A":   PN = "1"  !CDS_PN = "1";
"B":   PN = "2"  !CDS_PN = "2";
BODY = "CAP_A","I41": #LOCATION = "C2N2" !CDS_LOCATION = "C2N2" &SEC = "1" #&CDS_SEC = "1";
"A":   PN = "1"  !CDS_PN = "1";
"B":   PN = "2"  !CDS_PN = "2";
BODY = "CAP_A","I42": #LOCATION = "C3M43" !CDS_LOCATION = "C3M43" &SEC = "1" #&CDS_SEC = "1";
"A":   PN = "1"  !CDS_PN = "1";
"B":   PN = "2"  !CDS_PN = "2";
BODY = "CAP_A","I43": #LOCATION = "C2N7" !CDS_LOCATION = "C2N7" &SEC = "1" #&CDS_SEC = "1";
"A":   PN = "1"  !CDS_PN = "1";
"B":   PN = "2"  !CDS_PN = "2";
BODY = "CAP_A","I44": #LOCATION = "C3M39" !CDS_LOCATION = "C3M39" &SEC = "1" #&CDS_SEC = "1";
"A":   PN = "1"  !CDS_PN = "1";
"B":   PN = "2"  !CDS_PN = "2";
BODY = "CAP_A","I45": #LOCATION = "C3M42" !CDS_LOCATION = "C3M42" &SEC = "1" #&CDS_SEC = "1";
"A":   PN = "1"  !CDS_PN = "1";
"B":   PN = "2"  !CDS_PN = "2";
BODY = "CAP_A","I47": #LOCATION = "C2N8" !CDS_LOCATION = "C2N8" &SEC = "1" #&CDS_SEC = "1";
"A":   PN = "1"  !CDS_PN = "1";
"B":   PN = "2"  !CDS_PN = "2";
BODY = "CAP_A","I48": #LOCATION = "C2M13" !CDS_LOCATION = "C2M13" &SEC = "1" #&CDS_SEC = "1";
"A":   PN = "1"  !CDS_PN = "1";
"B":   PN = "2"  !CDS_PN = "2";
BODY = "CAP_A","I50": #LOCATION = "C2N10" !CDS_LOCATION = "C2N10" &SEC = "1" #&CDS_SEC = "1";
"A":   PN = "1"  !CDS_PN = "1";
"B":   PN = "2"  !CDS_PN = "2";
BODY = "CAP_A","I52": #LOCATION = "C2M12" !CDS_LOCATION = "C2M12" &SEC = "1" #&CDS_SEC = "1";
"A":   PN = "1"  !CDS_PN = "1";
"B":   PN = "2"  !CDS_PN = "2";
DRAWING = "@baseboard_fab2_lib.baseboard_fab2(sch_1):page132";
BODY = "CAP_A","I1": #LOCATION = "C3L25" !CDS_LOCATION = "C3L25" &SEC = "1" #&CDS_SEC = "1";
"A":   PN = "1"  !CDS_PN = "1";
"B":   PN = "2"  !CDS_PN = "2";
BODY = "CAP_A","I2": #LOCATION = "C3M7" !CDS_LOCATION = "C3M7" &SEC = "1" #&CDS_SEC = "1";
"A":   PN = "1"  !CDS_PN = "1";
"B":   PN = "2"  !CDS_PN = "2";
BODY = "CAP_A","I3": #LOCATION = "C3L26" !CDS_LOCATION = "C3L26" &SEC = "1" #&CDS_SEC = "1";
"A":   PN = "1"  !CDS_PN = "1";
"B":   PN = "2"  !CDS_PN = "2";
BODY = "CAP_A","I4": #LOCATION = "C3L27" !CDS_LOCATION = "C3L27" &SEC = "1" #&CDS_SEC = "1";
"A":   PN = "1"  !CDS_PN = "1";
"B":   PN = "2"  !CDS_PN = "2";
BODY = "CAP_A","I6": #LOCATION = "C3M6" !CDS_LOCATION = "C3M6" &SEC = "1" #&CDS_SEC = "1";
"A":   PN = "1"  !CDS_PN = "1";
"B":   PN = "2"  !CDS_PN = "2";
BODY = "CAP_A","I7": #LOCATION = "C7C9" !CDS_LOCATION = "C7C9" &SEC = "1" #&CDS_SEC = "1";
"A":   PN = "1"  !CDS_PN = "1";
"B":   PN = "2"  !CDS_PN = "2";
BODY = "CAP_A","I8": #LOCATION = "C3N27" !CDS_LOCATION = "C3N27" &SEC = "1" #&CDS_SEC = "1";
"A":   PN = "1"  !CDS_PN = "1";
"B":   PN = "2"  !CDS_PN = "2";
BODY = "CAP_A","I9": #LOCATION = "C3N30" !CDS_LOCATION = "C3N30" &SEC = "1" #&CDS_SEC = "1";
"A":   PN = "1"  !CDS_PN = "1";
"B":   PN = "2"  !CDS_PN = "2";
BODY = "CAP_A","I11": #LOCATION = "C7A36" !CDS_LOCATION = "C7A36" &SEC = "1" #&CDS_SEC = "1";
"A":   PN = "1"  !CDS_PN = "1";
"B":   PN = "2"  !CDS_PN = "2";
BODY = "CAP_A","I12": #LOCATION = "C3N12" !CDS_LOCATION = "C3N12" &SEC = "1" #&CDS_SEC = "1";
"A":   PN = "1"  !CDS_PN = "1";
"B":   PN = "2"  !CDS_PN = "2";
BODY = "CAP_A","I13": #LOCATION = "C3N10" !CDS_LOCATION = "C3N10" &SEC = "1" #&CDS_SEC = "1";
"A":   PN = "1"  !CDS_PN = "1";
"B":   PN = "2"  !CDS_PN = "2";
BODY = "CAP_A","I16": #LOCATION = "C3N24" !CDS_LOCATION = "C3N24" &SEC = "1" #&CDS_SEC = "1";
"A":   PN = "1"  !CDS_PN = "1";
"B":   PN = "2"  !CDS_PN = "2";
BODY = "CAP_A","I17": #LOCATION = "C3N28" !CDS_LOCATION = "C3N28" &SEC = "1" #&CDS_SEC = "1";
"A":   PN = "1"  !CDS_PN = "1";
"B":   PN = "2"  !CDS_PN = "2";
BODY = "CAP_A","I19": #LOCATION = "C3N11" !CDS_LOCATION = "C3N11" &SEC = "1" #&CDS_SEC = "1";
"A":   PN = "1"  !CDS_PN = "1";
"B":   PN = "2"  !CDS_PN = "2";
BODY = "CAP_A","I20": #LOCATION = "C3N31" !CDS_LOCATION = "C3N31" &SEC = "1" #&CDS_SEC = "1";
"A":   PN = "1"  !CDS_PN = "1";
"B":   PN = "2"  !CDS_PN = "2";
BODY = "CAP","I23": #LOCATION = "C7A33" !CDS_LOCATION = "C7A33" &SEC = "1" #&CDS_SEC = "1";
"A":   PN = "1"  !CDS_PN = "1";
"B":   PN = "2"  !CDS_PN = "2";
BODY = "CAP","I24": #LOCATION = "C7B4" !CDS_LOCATION = "C7B4" &SEC = "1" #&CDS_SEC = "1";
"A":   PN = "1"  !CDS_PN = "1";
"B":   PN = "2"  !CDS_PN = "2";
BODY = "CAP_A","I26": #LOCATION = "C2N9" !CDS_LOCATION = "C2N9" &SEC = "1" #&CDS_SEC = "1";
"A":   PN = "1"  !CDS_PN = "1";
"B":   PN = "2"  !CDS_PN = "2";
BODY = "CAP_A","I27": #LOCATION = "C2N3" !CDS_LOCATION = "C2N3" &SEC = "1" #&CDS_SEC = "1";
"A":   PN = "1"  !CDS_PN = "1";
"B":   PN = "2"  !CDS_PN = "2";
BODY = "CAP_A","I28": #LOCATION = "C2N4" !CDS_LOCATION = "C2N4" &SEC = "1" #&CDS_SEC = "1";
"A":   PN = "1"  !CDS_PN = "1";
"B":   PN = "2"  !CDS_PN = "2";
BODY = "CAP_A","I29": #LOCATION = "C2N12" !CDS_LOCATION = "C2N12" &SEC = "1" #&CDS_SEC = "1";
"A":   PN = "1"  !CDS_PN = "1";
"B":   PN = "2"  !CDS_PN = "2";
BODY = "CAP_A","I30": #LOCATION = "C2N11" !CDS_LOCATION = "C2N11" &SEC = "1" #&CDS_SEC = "1";
"A":   PN = "1"  !CDS_PN = "1";
"B":   PN = "2"  !CDS_PN = "2";
BODY = "CAP_A","I31": #LOCATION = "C3N19" !CDS_LOCATION = "C3N19" &SEC = "1" #&CDS_SEC = "1";
"A":   PN = "1"  !CDS_PN = "1";
"B":   PN = "2"  !CDS_PN = "2";
BODY = "CAP_A","I32": #LOCATION = "C3N3" !CDS_LOCATION = "C3N3" &SEC = "1" #&CDS_SEC = "1";
"A":   PN = "1"  !CDS_PN = "1";
"B":   PN = "2"  !CDS_PN = "2";
BODY = "CAP_A","I34": #LOCATION = "C3N1" !CDS_LOCATION = "C3N1" &SEC = "1" #&CDS_SEC = "1";
"A":   PN = "1"  !CDS_PN = "1";
"B":   PN = "2"  !CDS_PN = "2";
BODY = "CAP_A","I35": #LOCATION = "C3N7" !CDS_LOCATION = "C3N7" &SEC = "1" #&CDS_SEC = "1";
"A":   PN = "1"  !CDS_PN = "1";
"B":   PN = "2"  !CDS_PN = "2";
BODY = "CAP_A","I36": #LOCATION = "C3N16" !CDS_LOCATION = "C3N16" &SEC = "1" #&CDS_SEC = "1";
"A":   PN = "1"  !CDS_PN = "1";
"B":   PN = "2"  !CDS_PN = "2";
BODY = "CAP","I38": #LOCATION = "C7A32" !CDS_LOCATION = "C7A32" &SEC = "1" #&CDS_SEC = "1";
"A":   PN = "1"  !CDS_PN = "1";
"B":   PN = "2"  !CDS_PN = "2";
BODY = "CAP","I40": #LOCATION = "C7A31" !CDS_LOCATION = "C7A31" &SEC = "1" #&CDS_SEC = "1";
"A":   PN = "1"  !CDS_PN = "1";
"B":   PN = "2"  !CDS_PN = "2";
BODY = "CAP_A","I42": #LOCATION = "C3N18" !CDS_LOCATION = "C3N18" &SEC = "1" #&CDS_SEC = "1";
"A":   PN = "1"  !CDS_PN = "1";
"B":   PN = "2"  !CDS_PN = "2";
BODY = "CAP_A","I43": #LOCATION = "C3N2" !CDS_LOCATION = "C3N2" &SEC = "1" #&CDS_SEC = "1";
"A":   PN = "1"  !CDS_PN = "1";
"B":   PN = "2"  !CDS_PN = "2";
BODY = "CAP_A","I44": #LOCATION = "C3N6" !CDS_LOCATION = "C3N6" &SEC = "1" #&CDS_SEC = "1";
"A":   PN = "1"  !CDS_PN = "1";
"B":   PN = "2"  !CDS_PN = "2";
BODY = "CAP_A","I45": #LOCATION = "C3N17" !CDS_LOCATION = "C3N17" &SEC = "1" #&CDS_SEC = "1";
"A":   PN = "1"  !CDS_PN = "1";
"B":   PN = "2"  !CDS_PN = "2";
BODY = "CAP_A","I46": #LOCATION = "C3N4" !CDS_LOCATION = "C3N4" &SEC = "1" #&CDS_SEC = "1";
"A":   PN = "1"  !CDS_PN = "1";
"B":   PN = "2"  !CDS_PN = "2";
BODY = "CAP_A","I48": #LOCATION = "C3N5" !CDS_LOCATION = "C3N5" &SEC = "1" #&CDS_SEC = "1";
"A":   PN = "1"  !CDS_PN = "1";
"B":   PN = "2"  !CDS_PN = "2";
BODY = "CAP_A","I49": #LOCATION = "C3N15" !CDS_LOCATION = "C3N15" &SEC = "1" #&CDS_SEC = "1";
"A":   PN = "1"  !CDS_PN = "1";
"B":   PN = "2"  !CDS_PN = "2";
BODY = "CAP_A","I51": #LOCATION = "C3N20" !CDS_LOCATION = "C3N20" &SEC = "1" #&CDS_SEC = "1";
"A":   PN = "1"  !CDS_PN = "1";
"B":   PN = "2"  !CDS_PN = "2";
BODY = "CAP_A","I52": #LOCATION = "C3L23" !CDS_LOCATION = "C3L23" &SEC = "1" #&CDS_SEC = "1";
"A":   PN = "1"  !CDS_PN = "1";
"B":   PN = "2"  !CDS_PN = "2";
BODY = "CAP_A","I54": #LOCATION = "C3L22" !CDS_LOCATION = "C3L22" &SEC = "1" #&CDS_SEC = "1";
"A":   PN = "1"  !CDS_PN = "1";
"B":   PN = "2"  !CDS_PN = "2";
BODY = "CAP_A","I56": #LOCATION = "C3L24" !CDS_LOCATION = "C3L24" &SEC = "1" #&CDS_SEC = "1";
"A":   PN = "1"  !CDS_PN = "1";
"B":   PN = "2"  !CDS_PN = "2";
DRAWING = "@baseboard_fab2_lib.baseboard_fab2(sch_1):page133";
BODY = "RES","I120": #LOCATION = "R3N3" !CDS_LOCATION = "R3N3" &SEC = "1" #&CDS_SEC = "1";
"A":   PN = "1"  !CDS_PN = "1";
"B":   PN = "2"  !CDS_PN = "2";
BODY = "RES","I122": #LOCATION = "R2N12" !CDS_LOCATION = "R2N12" &SEC = "1" #&CDS_SEC = "1";
"A":   PN = "1"  !CDS_PN = "1";
"B":   PN = "2"  !CDS_PN = "2";
BODY = "RES","I200": #LOCATION = "R7D8" !CDS_LOCATION = "R7D8" #SEC = "1" !CDS_SEC = "1";
"A":   PN = "1"  !CDS_PN = "1";
"B":   PN = "2"  !CDS_PN = "2";
BODY = "RES","I202": #LOCATION = "R7D10" !CDS_LOCATION = "R7D10" #SEC = "1" !CDS_SEC = "1";
"A":   PN = "1"  !CDS_PN = "1";
"B":   PN = "2"  !CDS_PN = "2";
BODY = "RES","I237": #LOCATION = "R7D12" !CDS_LOCATION = "R7D12" #SEC = "1" !CDS_SEC = "1";
"A":   PN = "1"  !CDS_PN = "1";
"B":   PN = "2"  !CDS_PN = "2";
BODY = "RES","I243": #LOCATION = "R7D3" !CDS_LOCATION = "R7D3" #SEC = "1" !CDS_SEC = "1";
"A":   PN = "1"  !CDS_PN = "1";
"B":   PN = "2"  !CDS_PN = "2";
BODY = "RES","I245": #LOCATION = "R7D4" !CDS_LOCATION = "R7D4" #SEC = "1" !CDS_SEC = "1";
"A":   PN = "1"  !CDS_PN = "1";
"B":   PN = "2"  !CDS_PN = "2";
BODY = "RES","I247": #LOCATION = "R2N16" !CDS_LOCATION = "R2N16" &SEC = "1" #&CDS_SEC = "1";
"A":   PN = "1"  !CDS_PN = "1";
"B":   PN = "2"  !CDS_PN = "2";
BODY = "RES","I258": #LOCATION = "R2R5" !CDS_LOCATION = "R2R5" #SEC = "1" !CDS_SEC = "1";
"A":   PN = "1"  !CDS_PN = "1";
"B":   PN = "2"  !CDS_PN = "2";
BODY = "RES","I267": #LOCATION = "R2N9" !CDS_LOCATION = "R2N9" #SEC = "1" !CDS_SEC = "1";
"A":   PN = "1"  !CDS_PN = "1";
"B":   PN = "2"  !CDS_PN = "2";
BODY = "RES","I280": #LOCATION = "R8B23" !CDS_LOCATION = "R8B23" #SEC = "1" !CDS_SEC = "1";
"A":   PN = "1"  !CDS_PN = "1";
"B":   PN = "2"  !CDS_PN = "2";
BODY = "RES","I282": #LOCATION = "R8B30" !CDS_LOCATION = "R8B30" #SEC = "1" !CDS_SEC = "1";
"A":   PN = "1"  !CDS_PN = "1";
"B":   PN = "2"  !CDS_PN = "2";
BODY = "RES","I284": #LOCATION = "R2M4" !CDS_LOCATION = "R2M4" #SEC = "1" !CDS_SEC = "1";
"A":   PN = "1"  !CDS_PN = "1";
"B":   PN = "2"  !CDS_PN = "2";
BODY = "RES","I286": #LOCATION = "R8C4" !CDS_LOCATION = "R8C4" #SEC = "1" !CDS_SEC = "1";
"A":   PN = "1"  !CDS_PN = "1";
"B":   PN = "2"  !CDS_PN = "2";
BODY = "RES","I295": #LOCATION = "R7B6" !CDS_LOCATION = "R7B6" #SEC = "1" !CDS_SEC = "1";
"A":   PN = "1"  !CDS_PN = "1";
"B":   PN = "2"  !CDS_PN = "2";
BODY = "RES","I296": #LOCATION = "R7C8" !CDS_LOCATION = "R7C8" #SEC = "1" !CDS_SEC = "1";
"A":   PN = "1"  !CDS_PN = "1";
"B":   PN = "2"  !CDS_PN = "2";
BODY = "RES","I297": #LOCATION = "R7C5" !CDS_LOCATION = "R7C5" #SEC = "1" !CDS_SEC = "1";
"A":   PN = "1"  !CDS_PN = "1";
"B":   PN = "2"  !CDS_PN = "2";
BODY = "RES","I301": #LOCATION = "R8D14" !CDS_LOCATION = "R8D14" #SEC = "1" !CDS_SEC = "1";
"A":   PN = "1"  !CDS_PN = "1";
"B":   PN = "2"  !CDS_PN = "2";
BODY = "RES","I303": #LOCATION = "R8C6" !CDS_LOCATION = "R8C6" #SEC = "1" !CDS_SEC = "1";
"A":   PN = "1"  !CDS_PN = "1";
"B":   PN = "2"  !CDS_PN = "2";
BODY = "RES","I304": #LOCATION = "R8C2" !CDS_LOCATION = "R8C2" #SEC = "1" !CDS_SEC = "1";
"A":   PN = "1"  !CDS_PN = "1";
"B":   PN = "2"  !CDS_PN = "2";
BODY = "RES","I306": #LOCATION = "R7D6" !CDS_LOCATION = "R7D6" #SEC = "1" !CDS_SEC = "1";
"A":   PN = "1"  !CDS_PN = "1";
"B":   PN = "2"  !CDS_PN = "2";
BODY = "RES","I307": #LOCATION = "R8B31" !CDS_LOCATION = "R8B31" #SEC = "1" !CDS_SEC = "1";
"A":   PN = "1"  !CDS_PN = "1";
"B":   PN = "2"  !CDS_PN = "2";
BODY = "RES","I309": #LOCATION = "R2N7" !CDS_LOCATION = "R2N7" #SEC = "1" !CDS_SEC = "1";
"A":   PN = "1"  !CDS_PN = "1";
"B":   PN = "2"  !CDS_PN = "2";
BODY = "RES","I322": #LOCATION = "R3P8" !CDS_LOCATION = "R3P8" #SEC = "1" !CDS_SEC = "1";
"A":   PN = "1"  !CDS_PN = "1";
"B":   PN = "2"  !CDS_PN = "2";
BODY = "RES","I326": #LOCATION = "R8C1" !CDS_LOCATION = "R8C1" #SEC = "1" !CDS_SEC = "1";
"A":   PN = "1"  !CDS_PN = "1";
"B":   PN = "2"  !CDS_PN = "2";
BODY = "RES","I327": #LOCATION = "R8C7" !CDS_LOCATION = "R8C7" #SEC = "1" !CDS_SEC = "1";
"A":   PN = "1"  !CDS_PN = "1";
"B":   PN = "2"  !CDS_PN = "2";
BODY = "RES","I331": #LOCATION = "R7D7" !CDS_LOCATION = "R7D7" #SEC = "1" !CDS_SEC = "1";
"A":   PN = "1"  !CDS_PN = "1";
"B":   PN = "2"  !CDS_PN = "2";
BODY = "RES","I332": #LOCATION = "R7D2" !CDS_LOCATION = "R7D2" #SEC = "1" !CDS_SEC = "1";
"A":   PN = "1"  !CDS_PN = "1";
"B":   PN = "2"  !CDS_PN = "2";
BODY = "RES","I333": #LOCATION = "R8C25" !CDS_LOCATION = "R8C25" #SEC = "1" !CDS_SEC = "1";
"A":   PN = "1"  !CDS_PN = "1";
"B":   PN = "2"  !CDS_PN = "2";
BODY = "RES","I341": #LOCATION = "R2N32" !CDS_LOCATION = "R2N32" #SEC = "1" !CDS_SEC = "1";
"A":   PN = "1"  !CDS_PN = "1";
"B":   PN = "2"  !CDS_PN = "2";
BODY = "RES","I349": #LOCATION = "R2M8" !CDS_LOCATION = "R2M8" #SEC = "1" !CDS_SEC = "1";
"A":   PN = "1"  !CDS_PN = "1";
"B":   PN = "2"  !CDS_PN = "2";
BODY = "RES","I352": #LOCATION = "R2N29" !CDS_LOCATION = "R2N29" #SEC = "1" !CDS_SEC = "1";
"A":   PN = "1"  !CDS_PN = "1";
"B":   PN = "2"  !CDS_PN = "2";
BODY = "RES","I356": #LOCATION = "R7D44" !CDS_LOCATION = "R7D44" #SEC = "1" !CDS_SEC = "1";
"A":   PN = "1"  !CDS_PN = "1";
"B":   PN = "2"  !CDS_PN = "2";
BODY = "RES","I360": #LOCATION = "R2P22" !CDS_LOCATION = "R2P22" #SEC = "1" !CDS_SEC = "1";
"A":   PN = "1"  !CDS_PN = "1";
"B":   PN = "2"  !CDS_PN = "2";
BODY = "RES","I362": #LOCATION = "R8D44" !CDS_LOCATION = "R8D44" #SEC = "1" !CDS_SEC = "1";
"A":   PN = "1"  !CDS_PN = "1";
"B":   PN = "2"  !CDS_PN = "2";
BODY = "RES","I365": #LOCATION = "R3P53" !CDS_LOCATION = "R3P53" &SEC = "1" #&CDS_SEC = "1";
"A":   PN = "1"  !CDS_PN = "1";
"B":   PN = "2"  !CDS_PN = "2";
BODY = "RES","I366": #LOCATION = "R3P5" !CDS_LOCATION = "R3P5" #SEC = "1" !CDS_SEC = "1";
"A":   PN = "1"  !CDS_PN = "1";
"B":   PN = "2"  !CDS_PN = "2";
BODY = "RES","I367": #LOCATION = "R3P6" !CDS_LOCATION = "R3P6" #SEC = "1" !CDS_SEC = "1";
"A":   PN = "1"  !CDS_PN = "1";
"B":   PN = "2"  !CDS_PN = "2";
BODY = "RES","I368": #LOCATION = "R3N15" !CDS_LOCATION = "R3N15" #SEC = "1" !CDS_SEC = "1";
"A":   PN = "1"  !CDS_PN = "1";
"B":   PN = "2"  !CDS_PN = "2";
BODY = "RES","I369": #LOCATION = "R3N16" !CDS_LOCATION = "R3N16" #SEC = "1" !CDS_SEC = "1";
"A":   PN = "1"  !CDS_PN = "1";
"B":   PN = "2"  !CDS_PN = "2";
BODY = "RES","I370": #LOCATION = "R3P7" !CDS_LOCATION = "R3P7" #SEC = "1" !CDS_SEC = "1";
"A":   PN = "1"  !CDS_PN = "1";
"B":   PN = "2"  !CDS_PN = "2";
BODY = "RES","I371": #LOCATION = "R8E3" !CDS_LOCATION = "R8E3" #SEC = "1" !CDS_SEC = "1";
"A":   PN = "1"  !CDS_PN = "1";
"B":   PN = "2"  !CDS_PN = "2";
DRAWING = "@baseboard_fab2_lib.baseboard_fab2(sch_1):page134";
BODY = "RES","I3": #LOCATION = "R2P17" !CDS_LOCATION = "R2P17" #SEC = "1" !CDS_SEC = "1";
"A":   PN = "1"  !CDS_PN = "1";
"B":   PN = "2"  !CDS_PN = "2";
BODY = "RES","I9": #LOCATION = "R7C21" !CDS_LOCATION = "R7C21" #SEC = "1" !CDS_SEC = "1";
"A":   PN = "1"  !CDS_PN = "1";
"B":   PN = "2"  !CDS_PN = "2";
BODY = "RES","I11": #LOCATION = "R7D18" !CDS_LOCATION = "R7D18" #SEC = "1" !CDS_SEC = "1";
"A":   PN = "1"  !CDS_PN = "1";
"B":   PN = "2"  !CDS_PN = "2";
BODY = "FET_N","I14": #LOCATION = "Q7D1" !CDS_LOCATION = "Q7D1" &SEC = "1" #&CDS_SEC = "1";
"DRN":   PN = "3"  !CDS_PN = "3";
"GATE":   PN = "1"  !CDS_PN = "1";
"SRC":   PN = "2"  !CDS_PN = "2";
BODY = "FET_N","I15": #LOCATION = "Q8D2" !CDS_LOCATION = "Q8D2" &SEC = "1" #&CDS_SEC = "1";
"DRN":   PN = "3"  !CDS_PN = "3";
"GATE":   PN = "1"  !CDS_PN = "1";
"SRC":   PN = "2"  !CDS_PN = "2";
DRAWING = "@baseboard_fab2_lib.baseboard_fab2(sch_1):page135";
BODY = "RES","I107": #LOCATION = "R2P19" !CDS_LOCATION = "R2P19" #SEC = "1" !CDS_SEC = "1";
"A":   PN = "1"  !CDS_PN = "1";
"B":   PN = "2"  !CDS_PN = "2";
BODY = "RES","I112": #LOCATION = "R2N23" !CDS_LOCATION = "R2N23" &SEC = "1" #&CDS_SEC = "1";
"A":   PN = "1"  !CDS_PN = "1";
"B":   PN = "2"  !CDS_PN = "2";
BODY = "RES","I113": #LOCATION = "R2N24" !CDS_LOCATION = "R2N24" #SEC = "1" !CDS_SEC = "1";
"A":   PN = "1"  !CDS_PN = "1";
"B":   PN = "2"  !CDS_PN = "2";
BODY = "RES","I117": #LOCATION = "R9A12" !CDS_LOCATION = "R9A12" &SEC = "1" #&CDS_SEC = "1";
"A":   PN = "1"  !CDS_PN = "1";
"B":   PN = "2"  !CDS_PN = "2";
BODY = "RES","I118": #LOCATION = "R9A13" !CDS_LOCATION = "R9A13" &SEC = "1" #&CDS_SEC = "1";
"A":   PN = "1"  !CDS_PN = "1";
"B":   PN = "2"  !CDS_PN = "2";
BODY = "RES","I120": #LOCATION = "R8D21" !CDS_LOCATION = "R8D21" #SEC = "1" !CDS_SEC = "1";
"A":   PN = "1"  !CDS_PN = "1";
"B":   PN = "2"  !CDS_PN = "2";
BODY = "RES","I121": #LOCATION = "R7D30" !CDS_LOCATION = "R7D30" #SEC = "1" !CDS_SEC = "1";
"A":   PN = "1"  !CDS_PN = "1";
"B":   PN = "2"  !CDS_PN = "2";
BODY = "CONN12_C73564003","I124": #LOCATION = "J8G2" !CDS_LOCATION = "J8G2" #SEC = "1" !CDS_SEC = "1";
"IO1":   PN = "1"  !CDS_PN = "1";
"IO2":   PN = "2"  !CDS_PN = "2";
"IO3":   PN = "3"  !CDS_PN = "3";
"IO4":   PN = "4"  !CDS_PN = "4";
"IO5":   PN = "5"  !CDS_PN = "5";
"IO6":   PN = "6"  !CDS_PN = "6";
"IO7":   PN = "7"  !CDS_PN = "7";
"IO8":   PN = "8"  !CDS_PN = "8";
"IO9":   PN = "9"  !CDS_PN = "9";
"IO10":   PN = "10"  !CDS_PN = "10";
"IO11":   PN = "11"  !CDS_PN = "11";
"IO12":   PN = "12"  !CDS_PN = "12";
BODY = "RES","I129": #LOCATION = "R9A16" !CDS_LOCATION = "R9A16" &SEC = "1" #&CDS_SEC = "1";
"A":   PN = "1"  !CDS_PN = "1";
"B":   PN = "2"  !CDS_PN = "2";
BODY = "CONN4_D42317002","I131": #LOCATION = "J9A1" !CDS_LOCATION = "J9A1" &SEC = "1" #&CDS_SEC = "1";
"IO1":   PN = "1"  !CDS_PN = "1";
"IO2":   PN = "2"  !CDS_PN = "2";
"IO3":   PN = "3"  !CDS_PN = "3";
"IO4":   PN = "4"  !CDS_PN = "4";
DRAWING = "@baseboard_fab2_lib.baseboard_fab2(sch_1):page136";
BODY = "RES","I101": #LOCATION = "R7G26" !CDS_LOCATION = "R7G26" #SEC = "1" !CDS_SEC = "1";
"A":   PN = "1"  !CDS_PN = "1";
"B":   PN = "2"  !CDS_PN = "2";
BODY = "RES","I102": #LOCATION = "R7G28" !CDS_LOCATION = "R7G28" #SEC = "1" !CDS_SEC = "1";
"A":   PN = "1"  !CDS_PN = "1";
"B":   PN = "2"  !CDS_PN = "2";
BODY = "RES","I126": #LOCATION = "R8E20" !CDS_LOCATION = "R8E20" #SEC = "1" !CDS_SEC = "1";
"A":   PN = "1"  !CDS_PN = "1";
"B":   PN = "2"  !CDS_PN = "2";
BODY = "CAP_A","I128": #LOCATION = "C8E8" !CDS_LOCATION = "C8E8" #SEC = "1" !CDS_SEC = "1";
"A":   PN = "1"  !CDS_PN = "1";
"B":   PN = "2"  !CDS_PN = "2";
BODY = "TTL1G126_A","I130": #LOCATION = "U8E3" !CDS_LOCATION = "U8E3" #SEC = "1" !CDS_SEC = "1";
"A":   PN = "2"  !CDS_PN = "2";
"OE":   PN = "1"  !CDS_PN = "1";
"Y":   PN = "4"  !CDS_PN = "4";
BODY = "RES","I133": #LOCATION = "R8E14" !CDS_LOCATION = "R8E14" #SEC = "1" !CDS_SEC = "1";
"A":   PN = "1"  !CDS_PN = "1";
"B":   PN = "2"  !CDS_PN = "2";
BODY = "FET_N","I134": #LOCATION = "Q8E1" !CDS_LOCATION = "Q8E1" #SEC = "1" !CDS_SEC = "1";
"DRN":   PN = "3"  !CDS_PN = "3";
"GATE":   PN = "1"  !CDS_PN = "1";
"SRC":   PN = "2"  !CDS_PN = "2";
BODY = "RES","I139": #LOCATION = "R7G31" !CDS_LOCATION = "R7G31" #SEC = "1" !CDS_SEC = "1";
"A":   PN = "1"  !CDS_PN = "1";
"B":   PN = "2"  !CDS_PN = "2";
BODY = "RES","I140": #LOCATION = "R8E16" !CDS_LOCATION = "R8E16" #SEC = "1" !CDS_SEC = "1";
"A":   PN = "1"  !CDS_PN = "1";
"B":   PN = "2"  !CDS_PN = "2";
BODY = "RES","I147": #LOCATION = "R2N28" !CDS_LOCATION = "R2N28" #SEC = "1" !CDS_SEC = "1";
"A":   PN = "1"  !CDS_PN = "1";
"B":   PN = "2"  !CDS_PN = "2";
BODY = "RES","I148": #LOCATION = "R7G29" !CDS_LOCATION = "R7G29" #SEC = "1" !CDS_SEC = "1";
"A":   PN = "1"  !CDS_PN = "1";
"B":   PN = "2"  !CDS_PN = "2";
BODY = "RES","I155": #LOCATION = "R7G27" !CDS_LOCATION = "R7G27" #SEC = "1" !CDS_SEC = "1";
"A":   PN = "1"  !CDS_PN = "1";
"B":   PN = "2"  !CDS_PN = "2";
BODY = "RES","I156": #LOCATION = "R3T14" !CDS_LOCATION = "R3T14" #SEC = "1" !CDS_SEC = "1";
"A":   PN = "1"  !CDS_PN = "1";
"B":   PN = "2"  !CDS_PN = "2";
BODY = "CONN12_C73564003","I174": #LOCATION = "J7G3" !CDS_LOCATION = "J7G3" #SEC = "1" !CDS_SEC = "1";
"IO1":   PN = "1"  !CDS_PN = "1";
"IO2":   PN = "2"  !CDS_PN = "2";
"IO3":   PN = "3"  !CDS_PN = "3";
"IO4":   PN = "4"  !CDS_PN = "4";
"IO5":   PN = "5"  !CDS_PN = "5";
"IO6":   PN = "6"  !CDS_PN = "6";
"IO7":   PN = "7"  !CDS_PN = "7";
"IO8":   PN = "8"  !CDS_PN = "8";
"IO9":   PN = "9"  !CDS_PN = "9";
"IO10":   PN = "10"  !CDS_PN = "10";
"IO11":   PN = "11"  !CDS_PN = "11";
"IO12":   PN = "12"  !CDS_PN = "12";
DRAWING = "@baseboard_fab2_lib.baseboard_fab2(sch_1):page137";
BODY = "RES","I11": #LOCATION = "R7C11" !CDS_LOCATION = "R7C11" &SEC = "1" #&CDS_SEC = "1";
"A":   PN = "1"  !CDS_PN = "1";
"B":   PN = "2"  !CDS_PN = "2";
BODY = "RES","I13": #LOCATION = "R7C10" !CDS_LOCATION = "R7C10" #SEC = "1" !CDS_SEC = "1";
"A":   PN = "1"  !CDS_PN = "1";
"B":   PN = "2"  !CDS_PN = "2";
BODY = "CAP_A","I14": #LOCATION = "C7C19" !CDS_LOCATION = "C7C19" #SEC = "1" !CDS_SEC = "1";
"A":   PN = "1"  !CDS_PN = "1";
"B":   PN = "2"  !CDS_PN = "2";
BODY = "RES","I15": #LOCATION = "R1U63" !CDS_LOCATION = "R1U63" #SEC = "1" !CDS_SEC = "1";
"A":   PN = "1"  !CDS_PN = "1";
"B":   PN = "2"  !CDS_PN = "2";
BODY = "RES","I19": #LOCATION = "R3N4" !CDS_LOCATION = "R3N4" &SEC = "1" #&CDS_SEC = "1";
"A":   PN = "1"  !CDS_PN = "1";
"B":   PN = "2"  !CDS_PN = "2";
BODY = "CAP_A","I20": #LOCATION = "C3N32" !CDS_LOCATION = "C3N32" #SEC = "1" !CDS_SEC = "1";
"A":   PN = "1"  !CDS_PN = "1";
"B":   PN = "2"  !CDS_PN = "2";
BODY = "RES","I67": #LOCATION = "R7C13" !CDS_LOCATION = "R7C13" #SEC = "1" !CDS_SEC = "1";
"A":   PN = "1"  !CDS_PN = "1";
"B":   PN = "2"  !CDS_PN = "2";
BODY = "RES","I69": #LOCATION = "R1U64" !CDS_LOCATION = "R1U64" #SEC = "1" !CDS_SEC = "1";
"A":   PN = "1"  !CDS_PN = "1";
"B":   PN = "2"  !CDS_PN = "2";
BODY = "CONN12_C73564003","I128": #LOCATION = "J9G1" !CDS_LOCATION = "J9G1" #SEC = "1" !CDS_SEC = "1";
"IO1":   PN = "1"  !CDS_PN = "1";
"IO2":   PN = "2"  !CDS_PN = "2";
"IO3":   PN = "3"  !CDS_PN = "3";
"IO4":   PN = "4"  !CDS_PN = "4";
"IO5":   PN = "5"  !CDS_PN = "5";
"IO6":   PN = "6"  !CDS_PN = "6";
"IO7":   PN = "7"  !CDS_PN = "7";
"IO8":   PN = "8"  !CDS_PN = "8";
"IO9":   PN = "9"  !CDS_PN = "9";
"IO10":   PN = "10"  !CDS_PN = "10";
"IO11":   PN = "11"  !CDS_PN = "11";
"IO12":   PN = "12"  !CDS_PN = "12";
BODY = "RES","I133": #LOCATION = "R25W154" !CDS_LOCATION = "R25W154" #SEC = "1" !CDS_SEC = "1";
"A":   PN = "1"  !CDS_PN = "1";
"B":   PN = "2"  !CDS_PN = "2";
BODY = "RES","I140": #LOCATION = "R25W94" !CDS_LOCATION = "R25W94" #SEC = "1" !CDS_SEC = "1";
"A":   PN = "1"  !CDS_PN = "1";
"B":   PN = "2"  !CDS_PN = "2";
BODY = "RES","I142": #LOCATION = "RN8F1" !CDS_LOCATION = "RN8F1" #SEC = "1" !CDS_SEC = "1";
"A":   PN = "1"  !CDS_PN = "1";
"B":   PN = "2"  !CDS_PN = "2";
BODY = "RES","I144": #LOCATION = "R6W2" !CDS_LOCATION = "R6W2" &SEC = "1" #&CDS_SEC = "1";
"A":   PN = "1"  !CDS_PN = "1";
"B":   PN = "2"  !CDS_PN = "2";
BODY = "RES","I149": #LOCATION = "R6W1" !CDS_LOCATION = "R6W1" #SEC = "1" !CDS_SEC = "1";
"A":   PN = "1"  !CDS_PN = "1";
"B":   PN = "2"  !CDS_PN = "2";
DRAWING = "@baseboard_fab2_lib.baseboard_fab2(sch_1):page138";
BODY = "RES","I83": #LOCATION = "R2T53" !CDS_LOCATION = "R2T53" #SEC = "1" !CDS_SEC = "1";
"A":   PN = "1"  !CDS_PN = "1";
"B":   PN = "2"  !CDS_PN = "2";
BODY = "RES","I84": #LOCATION = "R2T54" !CDS_LOCATION = "R2T54" #SEC = "1" !CDS_SEC = "1";
"A":   PN = "1"  !CDS_PN = "1";
"B":   PN = "2"  !CDS_PN = "2";
BODY = "RES","I87": #LOCATION = "R8D17" !CDS_LOCATION = "R8D17" #SEC = "1" !CDS_SEC = "1";
"A":   PN = "1"  !CDS_PN = "1";
"B":   PN = "2"  !CDS_PN = "2";
BODY = "RES","I88": #LOCATION = "R8D15" !CDS_LOCATION = "R8D15" #SEC = "1" !CDS_SEC = "1";
"A":   PN = "1"  !CDS_PN = "1";
"B":   PN = "2"  !CDS_PN = "2";
BODY = "RES","I89": #LOCATION = "R2N8" !CDS_LOCATION = "R2N8" #SEC = "1" !CDS_SEC = "1";
"A":   PN = "1"  !CDS_PN = "1";
"B":   PN = "2"  !CDS_PN = "2";
BODY = "RES","I90": #LOCATION = "R2N5" !CDS_LOCATION = "R2N5" #SEC = "1" !CDS_SEC = "1";
"A":   PN = "1"  !CDS_PN = "1";
"B":   PN = "2"  !CDS_PN = "2";
BODY = "RES","I97": #LOCATION = "R2U11" !CDS_LOCATION = "R2U11" #SEC = "1" !CDS_SEC = "1";
"A":   PN = "1"  !CDS_PN = "1";
"B":   PN = "2"  !CDS_PN = "2";
BODY = "RES","I98": #LOCATION = "R2U3" !CDS_LOCATION = "R2U3" #SEC = "1" !CDS_SEC = "1";
"A":   PN = "1"  !CDS_PN = "1";
"B":   PN = "2"  !CDS_PN = "2";
BODY = "RES","I158": #LOCATION = "R2U8" !CDS_LOCATION = "R2U8" &SEC = "1" #&CDS_SEC = "1";
"A":   PN = "1"  !CDS_PN = "1";
"B":   PN = "2"  !CDS_PN = "2";
BODY = "RES","I159": #LOCATION = "R2U12" !CDS_LOCATION = "R2U12" &SEC = "1" #&CDS_SEC = "1";
"A":   PN = "1"  !CDS_PN = "1";
"B":   PN = "2"  !CDS_PN = "2";
BODY = "RES","I163": #LOCATION = "R8D7" !CDS_LOCATION = "R8D7" #SEC = "1" !CDS_SEC = "1";
"A":   PN = "1"  !CDS_PN = "1";
"B":   PN = "2"  !CDS_PN = "2";
BODY = "RES","I164": #LOCATION = "R8D4" !CDS_LOCATION = "R8D4" #SEC = "1" !CDS_SEC = "1";
"A":   PN = "1"  !CDS_PN = "1";
"B":   PN = "2"  !CDS_PN = "2";
BODY = "RES","I165": #LOCATION = "R2U9" !CDS_LOCATION = "R2U9" #SEC = "1" !CDS_SEC = "1";
"A":   PN = "1"  !CDS_PN = "1";
"B":   PN = "2"  !CDS_PN = "2";
BODY = "RES","I166": #LOCATION = "R2U6" !CDS_LOCATION = "R2U6" #SEC = "1" !CDS_SEC = "1";
"A":   PN = "1"  !CDS_PN = "1";
"B":   PN = "2"  !CDS_PN = "2";
BODY = "RES","I167": #LOCATION = "R8C20" !CDS_LOCATION = "R8C20" #SEC = "1" !CDS_SEC = "1";
"A":   PN = "1"  !CDS_PN = "1";
"B":   PN = "2"  !CDS_PN = "2";
BODY = "RES","I168": #LOCATION = "R8C14" !CDS_LOCATION = "R8C14" #SEC = "1" !CDS_SEC = "1";
"A":   PN = "1"  !CDS_PN = "1";
"B":   PN = "2"  !CDS_PN = "2";
BODY = "RES","I169": #LOCATION = "R8C11" !CDS_LOCATION = "R8C11" #SEC = "1" !CDS_SEC = "1";
"A":   PN = "1"  !CDS_PN = "1";
"B":   PN = "2"  !CDS_PN = "2";
BODY = "RES","I170": #LOCATION = "R8C12" !CDS_LOCATION = "R8C12" #SEC = "1" !CDS_SEC = "1";
"A":   PN = "1"  !CDS_PN = "1";
"B":   PN = "2"  !CDS_PN = "2";
BODY = "RES","I171": #LOCATION = "R2N20" !CDS_LOCATION = "R2N20" #SEC = "1" !CDS_SEC = "1";
"A":   PN = "1"  !CDS_PN = "1";
"B":   PN = "2"  !CDS_PN = "2";
BODY = "RES","I175": #LOCATION = "R2N21" !CDS_LOCATION = "R2N21" #SEC = "1" !CDS_SEC = "1";
"A":   PN = "1"  !CDS_PN = "1";
"B":   PN = "2"  !CDS_PN = "2";
BODY = "RES","I186": #LOCATION = "R8B24" !CDS_LOCATION = "R8B24" #SEC = "1" !CDS_SEC = "1";
"A":   PN = "1"  !CDS_PN = "1";
"B":   PN = "2"  !CDS_PN = "2";
BODY = "RES","I187": #LOCATION = "R8B26" !CDS_LOCATION = "R8B26" #SEC = "1" !CDS_SEC = "1";
"A":   PN = "1"  !CDS_PN = "1";
"B":   PN = "2"  !CDS_PN = "2";
BODY = "RES","I194": #LOCATION = "R8W5" !CDS_LOCATION = "R8W5" #SEC = "1" !CDS_SEC = "1";
"A":   PN = "1"  !CDS_PN = "1";
"B":   PN = "2"  !CDS_PN = "2";
BODY = "RES","I195": #LOCATION = "R8W4" !CDS_LOCATION = "R8W4" #SEC = "1" !CDS_SEC = "1";
"A":   PN = "1"  !CDS_PN = "1";
"B":   PN = "2"  !CDS_PN = "2";
BODY = "RES","I198": #LOCATION = "R24W1" !CDS_LOCATION = "R24W1" #SEC = "1" !CDS_SEC = "1";
"A":   PN = "1"  !CDS_PN = "1";
"B":   PN = "2"  !CDS_PN = "2";
BODY = "RES","I199": #LOCATION = "R24W2" !CDS_LOCATION = "R24W2" #SEC = "1" !CDS_SEC = "1";
"A":   PN = "1"  !CDS_PN = "1";
"B":   PN = "2"  !CDS_PN = "2";
BODY = "RES","I202": #LOCATION = "R8W7" !CDS_LOCATION = "R8W7" #SEC = "1" !CDS_SEC = "1";
"A":   PN = "1"  !CDS_PN = "1";
"B":   PN = "2"  !CDS_PN = "2";
BODY = "RES","I205": #LOCATION = "R8W6" !CDS_LOCATION = "R8W6" #SEC = "1" !CDS_SEC = "1";
"A":   PN = "1"  !CDS_PN = "1";
"B":   PN = "2"  !CDS_PN = "2";
DRAWING = "@baseboard_fab2_lib.baseboard_fab2(sch_1):page139";
BODY = "SPRINGVILLE","I72": #LOCATION = "EU9E1" !CDS_LOCATION = "EU9E1" #SEC = "1" !CDS_SEC = "1";
"CBOT":   PN = "37"  !CDS_PN = "37";
"CTOP":   PN = "40"  !CDS_PN = "40";
"DEV_OFF_N":   PN = "28"  !CDS_PN = "28";
"GND":   PN = "65"  !CDS_PN = "65";
"JTAG_CLK":   PN = "19"  !CDS_PN = "19";
"JTAG_TDI":   PN = "29"  !CDS_PN = "29";
"JTAG_TDO":   PN = "4"  !CDS_PN = "4";
"JTAG_TMS":   PN = "18"  !CDS_PN = "18";
"LAN_PWR_GOOD":   PN = "1"  !CDS_PN = "1";
"LED0":   PN = "31"  !CDS_PN = "31";
"LED1":   PN = "30"  !CDS_PN = "30";
"LED2":   PN = "33"  !CDS_PN = "33";
"MDI_MINUS0_SFP_I2C_DATA":   PN = "57"  !CDS_PN = "57";
"MDI_MINUS1_SRDS_SIG_DET":   PN = "54"  !CDS_PN = "54";
"MDI_MINUS2_SETN":   PN = "52"  !CDS_PN = "52";
"MDI_MINUS3_SERN":   PN = "49"  !CDS_PN = "49";
"MDI_PLUS0_NC":   PN = "58"  !CDS_PN = "58";
"MDI_PLUS1_SFP_I2C_CLK":   PN = "55"  !CDS_PN = "55";
"MDI_PLUS2_SETP":   PN = "53"  !CDS_PN = "53";
"MDI_PLUS3_SERP":   PN = "50"  !CDS_PN = "50";
"NC":   PN = "22"  !CDS_PN = "22";
"NC_SI_ARB_IN":   PN = "43"  !CDS_PN = "43";
"NC_SI_ARB_OUT":   PN = "44"  !CDS_PN = "44";
"NC_SI_CLK_IN":   PN = "2"  !CDS_PN = "2";
"NC_SI_CRS_DV":   PN = "3"  !CDS_PN = "3";
"NC_SI_RXD0":   PN = "6"  !CDS_PN = "6";
"NC_SI_RXD1":   PN = "5"  !CDS_PN = "5";
"NC_SI_TX_EN":   PN = "7"  !CDS_PN = "7";
"NC_SI_TXD0":   PN = "9"  !CDS_PN = "9";
"NC_SI_TXD1":   PN = "8"  !CDS_PN = "8";
"NVM_CS_N":   PN = "15"  !CDS_PN = "15";
"NVM_SI":   PN = "12"  !CDS_PN = "12";
"NVM_SK":   PN = "13"  !CDS_PN = "13";
"NVM_SO":   PN = "14"  !CDS_PN = "14";
"PE_RN":   PN = "23"  !CDS_PN = "23";
"PE_RP":   PN = "24"  !CDS_PN = "24";
"PE_RST_N":   PN = "17"  !CDS_PN = "17";
"PE_TN":   PN = "20"  !CDS_PN = "20";
"PE_TP":   PN = "21"  !CDS_PN = "21";
"PE_WAKE_N":   PN = "16"  !CDS_PN = "16";
"PECLKN":   PN = "25"  !CDS_PN = "25";
"PECLKP":   PN = "26"  !CDS_PN = "26";
"RSET":   PN = "48"  !CDS_PN = "48";
"SDP0":   PN = "63"  !CDS_PN = "63";
"SDP1_PCIE_DIS_SDP1":   PN = "61"  !CDS_PN = "61";
"SDP2":   PN = "62"  !CDS_PN = "62";
"SDP3":   PN = "60"  !CDS_PN = "60";
"SMB_ALRT_N":   PN = "35"  !CDS_PN = "35";
"SMB_CLK":   PN = "34"  !CDS_PN = "34";
"SMB_DATA":   PN = "36"  !CDS_PN = "36";
"VDD0P9<0>":   PN = "59"  !CDS_PN = "59";
"VDD0P9<1>":   PN = "32"  !CDS_PN = "32";
"VDD0P9<2>":   PN = "11"  !CDS_PN = "11";
"VDD0P9<3>":   PN = "42"  !CDS_PN = "42";
"VDD0P9_OUT":   PN = "38"  !CDS_PN = "38";
"VDD1P5<0>":   PN = "56"  !CDS_PN = "56";
"VDD1P5<1>":   PN = "47"  !CDS_PN = "47";
"VDD1P5_OUT":   PN = "39"  !CDS_PN = "39";
"VDD3P3<0>":   PN = "64"  !CDS_PN = "64";
"VDD3P3<1>":   PN = "51"  !CDS_PN = "51";
"VDD3P3<2>":   PN = "41"  !CDS_PN = "41";
"VDD3P3<3>":   PN = "27"  !CDS_PN = "27";
"VDD3P3<4>":   PN = "10"  !CDS_PN = "10";
"XTAL1":   PN = "46"  !CDS_PN = "46";
"XTAL2":   PN = "45"  !CDS_PN = "45";
BODY = "CAP","I76": #LOCATION = "C9E7" !CDS_LOCATION = "C9E7" #SEC = "1" !CDS_SEC = "1";
"A":   PN = "1"  !CDS_PN = "1";
"B":   PN = "2"  !CDS_PN = "2";
BODY = "CAP_A","I87": #LOCATION = "C9E5" !CDS_LOCATION = "C9E5" #SEC = "1" !CDS_SEC = "1";
"A":   PN = "1"  !CDS_PN = "1";
"B":   PN = "2"  !CDS_PN = "2";
BODY = "CAP_A","I88": #LOCATION = "C9E4" !CDS_LOCATION = "C9E4" #SEC = "1" !CDS_SEC = "1";
"A":   PN = "1"  !CDS_PN = "1";
"B":   PN = "2"  !CDS_PN = "2";
BODY = "CAP_A","I89": #LOCATION = "C2M23" !CDS_LOCATION = "C2M23" #SEC = "1" !CDS_SEC = "1";
"A":   PN = "1"  !CDS_PN = "1";
"B":   PN = "2"  !CDS_PN = "2";
BODY = "CAP_A","I90": #LOCATION = "C2M24" !CDS_LOCATION = "C2M24" #SEC = "1" !CDS_SEC = "1";
"A":   PN = "1"  !CDS_PN = "1";
"B":   PN = "2"  !CDS_PN = "2";
BODY = "CRYSTAL","I109": #LOCATION = "Y9E1" !CDS_LOCATION = "Y9E1" #SEC = "1" !CDS_SEC = "1";
"A":   PN = "1"  !CDS_PN = "1";
"B":   PN = "3"  !CDS_PN = "3";
BODY = "RES","I110": #LOCATION = "R9E20" !CDS_LOCATION = "R9E20" #SEC = "1" !CDS_SEC = "1";
"A":   PN = "1"  !CDS_PN = "1";
"B":   PN = "2"  !CDS_PN = "2";
BODY = "RES","I128": #LOCATION = "R9E9" !CDS_LOCATION = "R9E9" #SEC = "1" !CDS_SEC = "1";
"A":   PN = "1"  !CDS_PN = "1";
"B":   PN = "2"  !CDS_PN = "2";
BODY = "RES","I129": #LOCATION = "R9E5" !CDS_LOCATION = "R9E5" #SEC = "1" !CDS_SEC = "1";
"A":   PN = "1"  !CDS_PN = "1";
"B":   PN = "2"  !CDS_PN = "2";
BODY = "RES","I130": #LOCATION = "R9E8" !CDS_LOCATION = "R9E8" #SEC = "1" !CDS_SEC = "1";
"A":   PN = "1"  !CDS_PN = "1";
"B":   PN = "2"  !CDS_PN = "2";
BODY = "CAP","I134": #LOCATION = "C1T4" !CDS_LOCATION = "C1T4" #SEC = "1" !CDS_SEC = "1";
"A":   PN = "1"  !CDS_PN = "1";
"B":   PN = "2"  !CDS_PN = "2";
BODY = "CAP","I135": #LOCATION = "C1R30" !CDS_LOCATION = "C1R30" #SEC = "1" !CDS_SEC = "1";
"A":   PN = "1"  !CDS_PN = "1";
"B":   PN = "2"  !CDS_PN = "2";
BODY = "CAP","I136": #LOCATION = "C1R22" !CDS_LOCATION = "C1R22" #SEC = "1" !CDS_SEC = "1";
"A":   PN = "1"  !CDS_PN = "1";
"B":   PN = "2"  !CDS_PN = "2";
BODY = "CAP","I142": #LOCATION = "C1R13" !CDS_LOCATION = "C1R13" &SEC = "1" #&CDS_SEC = "1";
"A":   PN = "1"  !CDS_PN = "1";
"B":   PN = "2"  !CDS_PN = "2";
BODY = "CAP_A","I143": #LOCATION = "C1R20" !CDS_LOCATION = "C1R20" &SEC = "1" #&CDS_SEC = "1";
"A":   PN = "1"  !CDS_PN = "1";
"B":   PN = "2"  !CDS_PN = "2";
BODY = "CAP_A","I144": #LOCATION = "C1T3" !CDS_LOCATION = "C1T3" &SEC = "1" #&CDS_SEC = "1";
"A":   PN = "1"  !CDS_PN = "1";
"B":   PN = "2"  !CDS_PN = "2";
BODY = "CAP_A","I145": #LOCATION = "C1R14" !CDS_LOCATION = "C1R14" &SEC = "1" #&CDS_SEC = "1";
"A":   PN = "1"  !CDS_PN = "1";
"B":   PN = "2"  !CDS_PN = "2";
BODY = "CAP_A","I146": #LOCATION = "C1R21" !CDS_LOCATION = "C1R21" &SEC = "1" #&CDS_SEC = "1";
"A":   PN = "1"  !CDS_PN = "1";
"B":   PN = "2"  !CDS_PN = "2";
BODY = "CAP_A","I149": #LOCATION = "C1R26" !CDS_LOCATION = "C1R26" &SEC = "1" #&CDS_SEC = "1";
"A":   PN = "1"  !CDS_PN = "1";
"B":   PN = "2"  !CDS_PN = "2";
BODY = "CAP_A","I150": #LOCATION = "C1R29" !CDS_LOCATION = "C1R29" &SEC = "1" #&CDS_SEC = "1";
"A":   PN = "1"  !CDS_PN = "1";
"B":   PN = "2"  !CDS_PN = "2";
BODY = "CAP_A","I151": #LOCATION = "C1R19" !CDS_LOCATION = "C1R19" &SEC = "1" #&CDS_SEC = "1";
"A":   PN = "1"  !CDS_PN = "1";
"B":   PN = "2"  !CDS_PN = "2";
BODY = "CAP_A","I152": #LOCATION = "C1R31" !CDS_LOCATION = "C1R31" &SEC = "1" #&CDS_SEC = "1";
"A":   PN = "1"  !CDS_PN = "1";
"B":   PN = "2"  !CDS_PN = "2";
BODY = "CAP","I153": #LOCATION = "C1R17" !CDS_LOCATION = "C1R17" &SEC = "1" #&CDS_SEC = "1";
"A":   PN = "1"  !CDS_PN = "1";
"B":   PN = "2"  !CDS_PN = "2";
BODY = "CAP_A","I157": #LOCATION = "C1R18" !CDS_LOCATION = "C1R18" &SEC = "1" #&CDS_SEC = "1";
"A":   PN = "1"  !CDS_PN = "1";
"B":   PN = "2"  !CDS_PN = "2";
BODY = "CAP_A","I158": #LOCATION = "C1T5" !CDS_LOCATION = "C1T5" &SEC = "1" #&CDS_SEC = "1";
"A":   PN = "1"  !CDS_PN = "1";
"B":   PN = "2"  !CDS_PN = "2";
BODY = "CAP_A","I159": #LOCATION = "C1R24" !CDS_LOCATION = "C1R24" &SEC = "1" #&CDS_SEC = "1";
"A":   PN = "1"  !CDS_PN = "1";
"B":   PN = "2"  !CDS_PN = "2";
BODY = "CAP_A","I160": #LOCATION = "C1R15" !CDS_LOCATION = "C1R15" &SEC = "1" #&CDS_SEC = "1";
"A":   PN = "1"  !CDS_PN = "1";
"B":   PN = "2"  !CDS_PN = "2";
BODY = "CAP","I161": #LOCATION = "C1R16" !CDS_LOCATION = "C1R16" &SEC = "1" #&CDS_SEC = "1";
"A":   PN = "1"  !CDS_PN = "1";
"B":   PN = "2"  !CDS_PN = "2";
BODY = "CAP_A","I163": #LOCATION = "C9E1" !CDS_LOCATION = "C9E1" #SEC = "1" !CDS_SEC = "1";
"A":   PN = "1"  !CDS_PN = "1";
"B":   PN = "2"  !CDS_PN = "2";
BODY = "RES","I173": #LOCATION = "R9F5" !CDS_LOCATION = "R9F5" &SEC = "1" #&CDS_SEC = "1";
"A":   PN = "1"  !CDS_PN = "1";
"B":   PN = "2"  !CDS_PN = "2";
BODY = "RES","I174": #LOCATION = "R9E23" !CDS_LOCATION = "R9E23" #SEC = "1" !CDS_SEC = "1";
"A":   PN = "1"  !CDS_PN = "1";
"B":   PN = "2"  !CDS_PN = "2";
BODY = "RES","I177": #LOCATION = "R9E2" !CDS_LOCATION = "R9E2" #SEC = "1" !CDS_SEC = "1";
"A":   PN = "1"  !CDS_PN = "1";
"B":   PN = "2"  !CDS_PN = "2";
BODY = "RES","I178": #LOCATION = "R9E3" !CDS_LOCATION = "R9E3" #SEC = "1" !CDS_SEC = "1";
"A":   PN = "1"  !CDS_PN = "1";
"B":   PN = "2"  !CDS_PN = "2";
BODY = "RES","I179": #LOCATION = "R9E1" !CDS_LOCATION = "R9E1" #SEC = "1" !CDS_SEC = "1";
"A":   PN = "1"  !CDS_PN = "1";
"B":   PN = "2"  !CDS_PN = "2";
BODY = "RES","I181": #LOCATION = "R9E22" !CDS_LOCATION = "R9E22" #SEC = "1" !CDS_SEC = "1";
"A":   PN = "1"  !CDS_PN = "1";
"B":   PN = "2"  !CDS_PN = "2";
BODY = "RES","I193": #LOCATION = "R9E7" !CDS_LOCATION = "R9E7" &SEC = "1" #&CDS_SEC = "1";
"A":   PN = "1"  !CDS_PN = "1";
"B":   PN = "2"  !CDS_PN = "2";
BODY = "RES","I195": #LOCATION = "R1R1" !CDS_LOCATION = "R1R1" #SEC = "1" !CDS_SEC = "1";
"A":   PN = "1"  !CDS_PN = "1";
"B":   PN = "2"  !CDS_PN = "2";
BODY = "RES","I200": #LOCATION = "R9E4" !CDS_LOCATION = "R9E4" #SEC = "1" !CDS_SEC = "1";
"A":   PN = "1"  !CDS_PN = "1";
"B":   PN = "2"  !CDS_PN = "2";
BODY = "RES","I201": #LOCATION = "R9E18" !CDS_LOCATION = "R9E18" #SEC = "1" !CDS_SEC = "1";
"A":   PN = "1"  !CDS_PN = "1";
"B":   PN = "2"  !CDS_PN = "2";
BODY = "RES","I212": #LOCATION = "R9E13" !CDS_LOCATION = "R9E13" &SEC = "1" #&CDS_SEC = "1";
"A":   PN = "1"  !CDS_PN = "1";
"B":   PN = "2"  !CDS_PN = "2";
BODY = "RES","I213": #LOCATION = "R1R12" !CDS_LOCATION = "R1R12" &SEC = "1" #&CDS_SEC = "1";
"A":   PN = "1"  !CDS_PN = "1";
"B":   PN = "2"  !CDS_PN = "2";
BODY = "RES","I214": #LOCATION = "R1T1" !CDS_LOCATION = "R1T1" &SEC = "1" #&CDS_SEC = "1";
"A":   PN = "1"  !CDS_PN = "1";
"B":   PN = "2"  !CDS_PN = "2";
BODY = "RES","I225": #LOCATION = "R9F1" !CDS_LOCATION = "R9F1" &SEC = "1" #&CDS_SEC = "1";
"A":   PN = "1"  !CDS_PN = "1";
"B":   PN = "2"  !CDS_PN = "2";
BODY = "RES","I228": #LOCATION = "R9E19" !CDS_LOCATION = "R9E19" #SEC = "1" !CDS_SEC = "1";
"A":   PN = "1"  !CDS_PN = "1";
"B":   PN = "2"  !CDS_PN = "2";
BODY = "RES","I229": #LOCATION = "R9E17" !CDS_LOCATION = "R9E17" #SEC = "1" !CDS_SEC = "1";
"A":   PN = "1"  !CDS_PN = "1";
"B":   PN = "2"  !CDS_PN = "2";
BODY = "RES","I235": #LOCATION = "R9E16" !CDS_LOCATION = "R9E16" #SEC = "1" !CDS_SEC = "1";
"A":   PN = "1"  !CDS_PN = "1";
"B":   PN = "2"  !CDS_PN = "2";
BODY = "RES","I237": #LOCATION = "R1R15" !CDS_LOCATION = "R1R15" #SEC = "1" !CDS_SEC = "1";
"A":   PN = "1"  !CDS_PN = "1";
"B":   PN = "2"  !CDS_PN = "2";
BODY = "RES","I238": #LOCATION = "R1T32" !CDS_LOCATION = "R1T32" #SEC = "1" !CDS_SEC = "1";
"A":   PN = "1"  !CDS_PN = "1";
"B":   PN = "2"  !CDS_PN = "2";
BODY = "RES","I239": #LOCATION = "R1T34" !CDS_LOCATION = "R1T34" #SEC = "1" !CDS_SEC = "1";
"A":   PN = "1"  !CDS_PN = "1";
"B":   PN = "2"  !CDS_PN = "2";
BODY = "RES","I240": #LOCATION = "R1T33" !CDS_LOCATION = "R1T33" #SEC = "1" !CDS_SEC = "1";
"A":   PN = "1"  !CDS_PN = "1";
"B":   PN = "2"  !CDS_PN = "2";
BODY = "CAP_A","I241": #LOCATION = "C9E12" !CDS_LOCATION = "C9E12" #SEC = "1" !CDS_SEC = "1";
"A":   PN = "1"  !CDS_PN = "1";
"B":   PN = "2"  !CDS_PN = "2";
BODY = "SC22U16V5MX-4-GP","I244": #LOCATION = "C22W34" !CDS_LOCATION = "C22W34" #SEC = "1" !CDS_SEC = "1";
"1":   PN = "1"  !CDS_PN = "1";
"2":   PN = "2"  !CDS_PN = "2";
BODY = "SC22U16V5MX-4-GP","I245": #LOCATION = "C9F2" !CDS_LOCATION = "C9F2" #SEC = "1" !CDS_SEC = "1";
"1":   PN = "1"  !CDS_PN = "1";
"2":   PN = "2"  !CDS_PN = "2";
BODY = "SC22U16V5MX-4-GP","I246": #LOCATION = "C22W35" !CDS_LOCATION = "C22W35" #SEC = "1" !CDS_SEC = "1";
"1":   PN = "1"  !CDS_PN = "1";
"2":   PN = "2"  !CDS_PN = "2";
BODY = "SC22U16V5MX-4-GP","I248": #LOCATION = "C9E6" !CDS_LOCATION = "C9E6" #SEC = "1" !CDS_SEC = "1";
"1":   PN = "1"  !CDS_PN = "1";
"2":   PN = "2"  !CDS_PN = "2";
BODY = "CAP","I249": #LOCATION = "C9E9" !CDS_LOCATION = "C9E9" #SEC = "1" !CDS_SEC = "1";
"A":   PN = "1"  !CDS_PN = "1";
"B":   PN = "2"  !CDS_PN = "2";
BODY = "CAP","I250": #LOCATION = "C9E8" !CDS_LOCATION = "C9E8" #SEC = "1" !CDS_SEC = "1";
"A":   PN = "1"  !CDS_PN = "1";
"B":   PN = "2"  !CDS_PN = "2";
BODY = "RES","I252": #LOCATION = "R9W36" !CDS_LOCATION = "R9W36" #SEC = "1" !CDS_SEC = "1";
"A":   PN = "1"  !CDS_PN = "1";
"B":   PN = "2"  !CDS_PN = "2";
DRAWING = "@baseboard_fab2_lib.baseboard_fab2(sch_1):page140";
BODY = "M25PE16","I1": #LOCATION = "U9E1" !CDS_LOCATION = "U9E1" #SEC = "1" !CDS_SEC = "1";
"C":   PN = "6"  !CDS_PN = "6";
"DQ0":   PN = "5"  !CDS_PN = "5";
"DQ1":   PN = "2"  !CDS_PN = "2";
"RESET_N":   PN = "7"  !CDS_PN = "7";
"S_N":   PN = "1"  !CDS_PN = "1";
"VCC":   PN = "8"  !CDS_PN = "8";
"VSS":   PN = "4"  !CDS_PN = "4";
"W_N":   PN = "3"  !CDS_PN = "3";
BODY = "CAP_A","I3": #LOCATION = "C1R25" !CDS_LOCATION = "C1R25" #SEC = "1" !CDS_SEC = "1";
"A":   PN = "1"  !CDS_PN = "1";
"B":   PN = "2"  !CDS_PN = "2";
BODY = "RES","I10": #LOCATION = "R1R9" !CDS_LOCATION = "R1R9" #SEC = "1" !CDS_SEC = "1";
"A":   PN = "1"  !CDS_PN = "1";
"B":   PN = "2"  !CDS_PN = "2";
BODY = "RES","I11": #LOCATION = "R1R3" !CDS_LOCATION = "R1R3" #SEC = "1" !CDS_SEC = "1";
"A":   PN = "1"  !CDS_PN = "1";
"B":   PN = "2"  !CDS_PN = "2";
BODY = "RES","I12": #LOCATION = "R1R7" !CDS_LOCATION = "R1R7" #SEC = "1" !CDS_SEC = "1";
"A":   PN = "1"  !CDS_PN = "1";
"B":   PN = "2"  !CDS_PN = "2";
BODY = "RES","I14": #LOCATION = "R1R6" !CDS_LOCATION = "R1R6" #SEC = "1" !CDS_SEC = "1";
"A":   PN = "1"  !CDS_PN = "1";
"B":   PN = "2"  !CDS_PN = "2";
BODY = "RES","I17": #LOCATION = "R9E6" !CDS_LOCATION = "R9E6" #SEC = "1" !CDS_SEC = "1";
"A":   PN = "1"  !CDS_PN = "1";
"B":   PN = "2"  !CDS_PN = "2";
DRAWING = "@baseboard_fab2_lib.baseboard_fab2(sch_1):page141";
BODY = "CAP_A","I46": #LOCATION = "C9G4" !CDS_LOCATION = "C9G4" #SEC = "1" !CDS_SEC = "1";
"A":   PN = "1"  !CDS_PN = "1";
"B":   PN = "2"  !CDS_PN = "2";
BODY = "CAP_A","I47": #LOCATION = "C9G6" !CDS_LOCATION = "C9G6" #SEC = "1" !CDS_SEC = "1";
"A":   PN = "1"  !CDS_PN = "1";
"B":   PN = "2"  !CDS_PN = "2";
BODY = "CAP","I48": #LOCATION = "C9G5" !CDS_LOCATION = "C9G5" #SEC = "1" !CDS_SEC = "1";
"A":   PN = "1"  !CDS_PN = "1";
"B":   PN = "2"  !CDS_PN = "2";
BODY = "RES","I75": #LOCATION = "R9G9" !CDS_LOCATION = "R9G9" #SEC = "1" !CDS_SEC = "1";
"A":   PN = "1"  !CDS_PN = "1";
"B":   PN = "2"  !CDS_PN = "2";
BODY = "RES","I76": #LOCATION = "R9G11" !CDS_LOCATION = "R9G11" #SEC = "1" !CDS_SEC = "1";
"A":   PN = "1"  !CDS_PN = "1";
"B":   PN = "2"  !CDS_PN = "2";
BODY = "RES","I77": #LOCATION = "R9G18" !CDS_LOCATION = "R9G18" #SEC = "1" !CDS_SEC = "1";
"A":   PN = "1"  !CDS_PN = "1";
"B":   PN = "2"  !CDS_PN = "2";
BODY = "RES","I78": #LOCATION = "R9G17" !CDS_LOCATION = "R9G17" #SEC = "1" !CDS_SEC = "1";
"A":   PN = "1"  !CDS_PN = "1";
"B":   PN = "2"  !CDS_PN = "2";
BODY = "RES","I79": #LOCATION = "R9G19" !CDS_LOCATION = "R9G19" #SEC = "1" !CDS_SEC = "1";
"A":   PN = "1"  !CDS_PN = "1";
"B":   PN = "2"  !CDS_PN = "2";
BODY = "RES","I80": #LOCATION = "R9G20" !CDS_LOCATION = "R9G20" #SEC = "1" !CDS_SEC = "1";
"A":   PN = "1"  !CDS_PN = "1";
"B":   PN = "2"  !CDS_PN = "2";
BODY = "RES","I81": #LOCATION = "R9G24" !CDS_LOCATION = "R9G24" #SEC = "1" !CDS_SEC = "1";
"A":   PN = "1"  !CDS_PN = "1";
"B":   PN = "2"  !CDS_PN = "2";
BODY = "RES","I82": #LOCATION = "R9G22" !CDS_LOCATION = "R9G22" #SEC = "1" !CDS_SEC = "1";
"A":   PN = "1"  !CDS_PN = "1";
"B":   PN = "2"  !CDS_PN = "2";
BODY = "CAP","I99": #LOCATION = "C9G9" !CDS_LOCATION = "C9G9" #SEC = "1" !CDS_SEC = "1";
"A":   PN = "1"  !CDS_PN = "1";
"B":   PN = "2"  !CDS_PN = "2";
BODY = "CAP","I100": #LOCATION = "C9G12" !CDS_LOCATION = "C9G12" &SEC = "1" #&CDS_SEC = "1";
"A":   PN = "1"  !CDS_PN = "1";
"B":   PN = "2"  !CDS_PN = "2";
BODY = "CAP","I101": #LOCATION = "C9G16" !CDS_LOCATION = "C9G16" #SEC = "1" !CDS_SEC = "1";
"A":   PN = "1"  !CDS_PN = "1";
"B":   PN = "2"  !CDS_PN = "2";
BODY = "CAP","I102": #LOCATION = "C9G13" !CDS_LOCATION = "C9G13" #SEC = "1" !CDS_SEC = "1";
"A":   PN = "1"  !CDS_PN = "1";
"B":   PN = "2"  !CDS_PN = "2";
BODY = "SKT-RJ45-LED-XFOR-1-GP","I129": #LOCATION = "JA9G1" !CDS_LOCATION = "JA9G1" #SEC = "1" !CDS_SEC = "1";
"1":   PN = "1"  !CDS_PN = "1";
"2":   PN = "2"  !CDS_PN = "2";
"L1":   PN = "L1"  !CDS_PN = "L1";
"L2":   PN = "L2"  !CDS_PN = "L2";
"L3":   PN = "L3"  !CDS_PN = "L3";
"L4":   PN = "L4"  !CDS_PN = "L4";
"R1":   PN = "R1"  !CDS_PN = "R1";
"R2":   PN = "R2"  !CDS_PN = "R2";
"R3":   PN = "R3"  !CDS_PN = "R3";
"R4":   PN = "R4"  !CDS_PN = "R4";
"R5":   PN = "R5"  !CDS_PN = "R5";
"R6":   PN = "R6"  !CDS_PN = "R6";
"R7":   PN = "R7"  !CDS_PN = "R7";
"R8":   PN = "R8"  !CDS_PN = "R8";
"R9":   PN = "R9"  !CDS_PN = "R9";
"R10":   PN = "R10"  !CDS_PN = "R10";
"R11":   PN = "R11"  !CDS_PN = "R11";
BODY = "RES","I134": #LOCATION = "R9G2" !CDS_LOCATION = "R9G2" &SEC = "1" #&CDS_SEC = "1";
"A":   PN = "1"  !CDS_PN = "1";
"B":   PN = "2"  !CDS_PN = "2";
BODY = "RES","I135": #LOCATION = "R9G3" !CDS_LOCATION = "R9G3" &SEC = "1" #&CDS_SEC = "1";
"A":   PN = "1"  !CDS_PN = "1";
"B":   PN = "2"  !CDS_PN = "2";
BODY = "CAP","I138": #LOCATION = "C9G3" !CDS_LOCATION = "C9G3" #SEC = "1" !CDS_SEC = "1";
"A":   PN = "1"  !CDS_PN = "1";
"B":   PN = "2"  !CDS_PN = "2";
BODY = "CAP","I140": #LOCATION = "C9G1" !CDS_LOCATION = "C9G1" #SEC = "1" !CDS_SEC = "1";
"A":   PN = "1"  !CDS_PN = "1";
"B":   PN = "2"  !CDS_PN = "2";
BODY = "CAP","I152": #LOCATION = "C9G2" !CDS_LOCATION = "C9G2" #SEC = "1" !CDS_SEC = "1";
"A":   PN = "1"  !CDS_PN = "1";
"B":   PN = "2"  !CDS_PN = "2";
BODY = "RES","I156": #LOCATION = "R9G4" !CDS_LOCATION = "R9G4" #SEC = "1" !CDS_SEC = "1";
"A":   PN = "1"  !CDS_PN = "1";
"B":   PN = "2"  !CDS_PN = "2";
BODY = "RES","I157": #LOCATION = "R9G1" !CDS_LOCATION = "R9G1" #SEC = "1" !CDS_SEC = "1";
"A":   PN = "1"  !CDS_PN = "1";
"B":   PN = "2"  !CDS_PN = "2";
BODY = "CAP","I159": #LOCATION = "C9F22" !CDS_LOCATION = "C9F22" #SEC = "1" !CDS_SEC = "1";
"A":   PN = "1"  !CDS_PN = "1";
"B":   PN = "2"  !CDS_PN = "2";
DRAWING = "@baseboard_fab2_lib.baseboard_fab2(sch_1):page142";
BODY = "TTL1G126_A","I1": #LOCATION = "U8E4" !CDS_LOCATION = "U8E4" #SEC = "1" !CDS_SEC = "1";
"A":   PN = "2"  !CDS_PN = "2";
"OE":   PN = "1"  !CDS_PN = "1";
"Y":   PN = "4"  !CDS_PN = "4";
BODY = "RES","I2": #LOCATION = "R8E17" !CDS_LOCATION = "R8E17" #SEC = "1" !CDS_SEC = "1";
"A":   PN = "1"  !CDS_PN = "1";
"B":   PN = "2"  !CDS_PN = "2";
BODY = "RES","I3": #LOCATION = "R8E23" !CDS_LOCATION = "R8E23" #SEC = "1" !CDS_SEC = "1";
"A":   PN = "1"  !CDS_PN = "1";
"B":   PN = "2"  !CDS_PN = "2";
BODY = "RES","I18": #LOCATION = "R8E29" !CDS_LOCATION = "R8E29" #SEC = "1" !CDS_SEC = "1";
"A":   PN = "1"  !CDS_PN = "1";
"B":   PN = "2"  !CDS_PN = "2";
BODY = "CAP_A","I20": #LOCATION = "C8E5" !CDS_LOCATION = "C8E5" #SEC = "1" !CDS_SEC = "1";
"A":   PN = "1"  !CDS_PN = "1";
"B":   PN = "2"  !CDS_PN = "2";
BODY = "RES","I30": #LOCATION = "R8E26" !CDS_LOCATION = "R8E26" #SEC = "1" !CDS_SEC = "1";
"A":   PN = "1"  !CDS_PN = "1";
"B":   PN = "2"  !CDS_PN = "2";
BODY = "RES","I31": #LOCATION = "R8E28" !CDS_LOCATION = "R8E28" #SEC = "1" !CDS_SEC = "1";
"A":   PN = "1"  !CDS_PN = "1";
"B":   PN = "2"  !CDS_PN = "2";
BODY = "RES","I32": #LOCATION = "R8E27" !CDS_LOCATION = "R8E27" #SEC = "1" !CDS_SEC = "1";
"A":   PN = "1"  !CDS_PN = "1";
"B":   PN = "2"  !CDS_PN = "2";
BODY = "RES","I33": #LOCATION = "R8E21" !CDS_LOCATION = "R8E21" #SEC = "1" !CDS_SEC = "1";
"A":   PN = "1"  !CDS_PN = "1";
"B":   PN = "2"  !CDS_PN = "2";
BODY = "2K15R2F-1-GP","I34": #LOCATION = "R8E36" !CDS_LOCATION = "R8E36" #SEC = "1" !CDS_SEC = "1";
"1":   PN = "1"  !CDS_PN = "1";
"2":   PN = "2"  !CDS_PN = "2";
BODY = "2K15R2F-1-GP","I35": #LOCATION = "R8E30" !CDS_LOCATION = "R8E30" #SEC = "1" !CDS_SEC = "1";
"1":   PN = "1"  !CDS_PN = "1";
"2":   PN = "2"  !CDS_PN = "2";
DRAWING = "@baseboard_fab2_lib.baseboard_fab2(sch_1):page152";
BODY = "GTL2014","I1": #LOCATION = "U9G1" !CDS_LOCATION = "U9G1" #SEC = "1" !CDS_SEC = "1";
"A0":   PN = "13"  !CDS_PN = "13";
"A1":   PN = "12"  !CDS_PN = "12";
"A2":   PN = "10"  !CDS_PN = "10";
"A3":   PN = "9"  !CDS_PN = "9";
"B0":   PN = "2"  !CDS_PN = "2";
"B1":   PN = "3"  !CDS_PN = "3";
"B2":   PN = "5"  !CDS_PN = "5";
"B3":   PN = "6"  !CDS_PN = "6";
"DIR":   PN = "1"  !CDS_PN = "1";
"GND<0>":   PN = "7"  !CDS_PN = "7";
"GND<1>":   PN = "8"  !CDS_PN = "8";
"GND<2>":   PN = "11"  !CDS_PN = "11";
"VCC":   PN = "14"  !CDS_PN = "14";
"VREF":   PN = "4"  !CDS_PN = "4";
BODY = "RES","I2": #LOCATION = "R1U30" !CDS_LOCATION = "R1U30" #SEC = "1" !CDS_SEC = "1";
"A":   PN = "1"  !CDS_PN = "1";
"B":   PN = "2"  !CDS_PN = "2";
BODY = "RES","I6": #LOCATION = "R1U46" !CDS_LOCATION = "R1U46" #SEC = "1" !CDS_SEC = "1";
"A":   PN = "1"  !CDS_PN = "1";
"B":   PN = "2"  !CDS_PN = "2";
BODY = "RES","I14": #LOCATION = "R9G31" !CDS_LOCATION = "R9G31" #SEC = "1" !CDS_SEC = "1";
"A":   PN = "1"  !CDS_PN = "1";
"B":   PN = "2"  !CDS_PN = "2";
BODY = "RES","I15": #LOCATION = "R1U36" !CDS_LOCATION = "R1U36" #SEC = "1" !CDS_SEC = "1";
"A":   PN = "1"  !CDS_PN = "1";
"B":   PN = "2"  !CDS_PN = "2";
BODY = "RES","I16": #LOCATION = "R1U34" !CDS_LOCATION = "R1U34" #SEC = "1" !CDS_SEC = "1";
"A":   PN = "1"  !CDS_PN = "1";
"B":   PN = "2"  !CDS_PN = "2";
BODY = "CAP","I18": #LOCATION = "C1U19" !CDS_LOCATION = "C1U19" #SEC = "1" !CDS_SEC = "1";
"A":   PN = "1"  !CDS_PN = "1";
"B":   PN = "2"  !CDS_PN = "2";
BODY = "RES","I26": #LOCATION = "R1U37" !CDS_LOCATION = "R1U37" #SEC = "1" !CDS_SEC = "1";
"A":   PN = "1"  !CDS_PN = "1";
"B":   PN = "2"  !CDS_PN = "2";
BODY = "CAP_A","I27": #LOCATION = "C1U22" !CDS_LOCATION = "C1U22" #SEC = "1" !CDS_SEC = "1";
"A":   PN = "1"  !CDS_PN = "1";
"B":   PN = "2"  !CDS_PN = "2";
BODY = "RES","I45": #LOCATION = "R9G34" !CDS_LOCATION = "R9G34" #SEC = "1" !CDS_SEC = "1";
"A":   PN = "1"  !CDS_PN = "1";
"B":   PN = "2"  !CDS_PN = "2";
BODY = "RES","I47": #LOCATION = "R9G27" !CDS_LOCATION = "R9G27" #SEC = "1" !CDS_SEC = "1";
"A":   PN = "1"  !CDS_PN = "1";
"B":   PN = "2"  !CDS_PN = "2";
BODY = "RES","I49": #LOCATION = "R1U58" !CDS_LOCATION = "R1U58" #SEC = "1" !CDS_SEC = "1";
"A":   PN = "1"  !CDS_PN = "1";
"B":   PN = "2"  !CDS_PN = "2";
BODY = "RES","I50": #LOCATION = "R1U56" !CDS_LOCATION = "R1U56" #SEC = "1" !CDS_SEC = "1";
"A":   PN = "1"  !CDS_PN = "1";
"B":   PN = "2"  !CDS_PN = "2";
BODY = "RES","I51": #LOCATION = "R2U51" !CDS_LOCATION = "R2U51" #SEC = "1" !CDS_SEC = "1";
"A":   PN = "1"  !CDS_PN = "1";
"B":   PN = "2"  !CDS_PN = "2";
BODY = "RES","I53": #LOCATION = "R2U40" !CDS_LOCATION = "R2U40" #SEC = "1" !CDS_SEC = "1";
"A":   PN = "1"  !CDS_PN = "1";
"B":   PN = "2"  !CDS_PN = "2";
BODY = "RES","I54": #LOCATION = "R2U41" !CDS_LOCATION = "R2U41" #SEC = "1" !CDS_SEC = "1";
"A":   PN = "1"  !CDS_PN = "1";
"B":   PN = "2"  !CDS_PN = "2";
BODY = "RES","I56": #LOCATION = "R1U41" !CDS_LOCATION = "R1U41" #SEC = "1" !CDS_SEC = "1";
"A":   PN = "1"  !CDS_PN = "1";
"B":   PN = "2"  !CDS_PN = "2";
BODY = "RES","I57": #LOCATION = "R1U35" !CDS_LOCATION = "R1U35" #SEC = "1" !CDS_SEC = "1";
"A":   PN = "1"  !CDS_PN = "1";
"B":   PN = "2"  !CDS_PN = "2";
BODY = "RES","I58": #LOCATION = "R4P17" !CDS_LOCATION = "R4P17" #SEC = "1" !CDS_SEC = "1";
"A":   PN = "1"  !CDS_PN = "1";
"B":   PN = "2"  !CDS_PN = "2";
BODY = "RES","I59": #LOCATION = "R4P20" !CDS_LOCATION = "R4P20" #SEC = "1" !CDS_SEC = "1";
"A":   PN = "1"  !CDS_PN = "1";
"B":   PN = "2"  !CDS_PN = "2";
BODY = "RES","I61": #LOCATION = "R7P5" !CDS_LOCATION = "R7P5" #SEC = "1" !CDS_SEC = "1";
"A":   PN = "1"  !CDS_PN = "1";
"B":   PN = "2"  !CDS_PN = "2";
BODY = "RES","I62": #LOCATION = "R7P21" !CDS_LOCATION = "R7P21" #SEC = "1" !CDS_SEC = "1";
"A":   PN = "1"  !CDS_PN = "1";
"B":   PN = "2"  !CDS_PN = "2";
BODY = "RES","I64": #LOCATION = "R1U53" !CDS_LOCATION = "R1U53" #SEC = "1" !CDS_SEC = "1";
"A":   PN = "1"  !CDS_PN = "1";
"B":   PN = "2"  !CDS_PN = "2";
BODY = "RES","I65": #LOCATION = "R1U60" !CDS_LOCATION = "R1U60" #SEC = "1" !CDS_SEC = "1";
"A":   PN = "1"  !CDS_PN = "1";
"B":   PN = "2"  !CDS_PN = "2";
BODY = "RES","I66": #LOCATION = "R2U49" !CDS_LOCATION = "R2U49" #SEC = "1" !CDS_SEC = "1";
"A":   PN = "1"  !CDS_PN = "1";
"B":   PN = "2"  !CDS_PN = "2";
BODY = "RES","I67": #LOCATION = "R1U55" !CDS_LOCATION = "R1U55" #SEC = "1" !CDS_SEC = "1";
"A":   PN = "1"  !CDS_PN = "1";
"B":   PN = "2"  !CDS_PN = "2";
BODY = "RES","I68": #LOCATION = "R1U62" !CDS_LOCATION = "R1U62" #SEC = "1" !CDS_SEC = "1";
"A":   PN = "1"  !CDS_PN = "1";
"B":   PN = "2"  !CDS_PN = "2";
BODY = "RES","I69": #LOCATION = "R1U57" !CDS_LOCATION = "R1U57" #SEC = "1" !CDS_SEC = "1";
"A":   PN = "1"  !CDS_PN = "1";
"B":   PN = "2"  !CDS_PN = "2";
BODY = "RES","I70": #LOCATION = "R1U61" !CDS_LOCATION = "R1U61" #SEC = "1" !CDS_SEC = "1";
"A":   PN = "1"  !CDS_PN = "1";
"B":   PN = "2"  !CDS_PN = "2";
BODY = "RES","I71": #LOCATION = "R9G28" !CDS_LOCATION = "R9G28" #SEC = "1" !CDS_SEC = "1";
"A":   PN = "1"  !CDS_PN = "1";
"B":   PN = "2"  !CDS_PN = "2";
BODY = "RES","I72": #LOCATION = "R9G32" !CDS_LOCATION = "R9G32" #SEC = "1" !CDS_SEC = "1";
"A":   PN = "1"  !CDS_PN = "1";
"B":   PN = "2"  !CDS_PN = "2";
BODY = "RES","I73": #LOCATION = "R9G33" !CDS_LOCATION = "R9G33" #SEC = "1" !CDS_SEC = "1";
"A":   PN = "1"  !CDS_PN = "1";
"B":   PN = "2"  !CDS_PN = "2";
BODY = "RES","I74": #LOCATION = "R1U59" !CDS_LOCATION = "R1U59" #SEC = "1" !CDS_SEC = "1";
"A":   PN = "1"  !CDS_PN = "1";
"B":   PN = "2"  !CDS_PN = "2";
BODY = "RES","I79": #LOCATION = "R2U47" !CDS_LOCATION = "R2U47" #SEC = "1" !CDS_SEC = "1";
"A":   PN = "1"  !CDS_PN = "1";
"B":   PN = "2"  !CDS_PN = "2";
BODY = "RES","I92": #LOCATION = "R9G29" !CDS_LOCATION = "R9G29" #SEC = "1" !CDS_SEC = "1";
"A":   PN = "1"  !CDS_PN = "1";
"B":   PN = "2"  !CDS_PN = "2";
BODY = "RES","I93": #LOCATION = "R1U54" !CDS_LOCATION = "R1U54" #SEC = "1" !CDS_SEC = "1";
"A":   PN = "1"  !CDS_PN = "1";
"B":   PN = "2"  !CDS_PN = "2";
BODY = "RES","I94": #LOCATION = "R2U46" !CDS_LOCATION = "R2U46" #SEC = "1" !CDS_SEC = "1";
"A":   PN = "1"  !CDS_PN = "1";
"B":   PN = "2"  !CDS_PN = "2";
BODY = "RES","I95": #LOCATION = "R3N30" !CDS_LOCATION = "R3N30" #SEC = "1" !CDS_SEC = "1";
"A":   PN = "1"  !CDS_PN = "1";
"B":   PN = "2"  !CDS_PN = "2";
BODY = "RES","I98": #LOCATION = "R9G30" !CDS_LOCATION = "R9G30" #SEC = "1" !CDS_SEC = "1";
"A":   PN = "1"  !CDS_PN = "1";
"B":   PN = "2"  !CDS_PN = "2";
BODY = "RES","I100": #LOCATION = "R3P63" !CDS_LOCATION = "R3P63" #SEC = "1" !CDS_SEC = "1";
"A":   PN = "1"  !CDS_PN = "1";
"B":   PN = "2"  !CDS_PN = "2";
BODY = "RES","I102": #LOCATION = "R2U45" !CDS_LOCATION = "R2U45" #SEC = "1" !CDS_SEC = "1";
"A":   PN = "1"  !CDS_PN = "1";
"B":   PN = "2"  !CDS_PN = "2";
BODY = "RES","I105": #LOCATION = "R1W35" !CDS_LOCATION = "R1W35" #SEC = "1" !CDS_SEC = "1";
"A":   PN = "1"  !CDS_PN = "1";
"B":   PN = "2"  !CDS_PN = "2";
BODY = "374R2F-1-GP","I106": #LOCATION = "R1U43" !CDS_LOCATION = "R1U43" &SEC = "1" #&CDS_SEC = "1";
"1":   PN = "1"  !CDS_PN = "1";
"2":   PN = "2"  !CDS_PN = "2";
DRAWING = "@baseboard_fab2_lib.baseboard_fab2(sch_1):page153";
BODY = "RES","I90": #LOCATION = "R7F6" !CDS_LOCATION = "R7F6" #SEC = "1" !CDS_SEC = "1";
"A":   PN = "1"  !CDS_PN = "1";
"B":   PN = "2"  !CDS_PN = "2";
BODY = "RES","I94": #LOCATION = "R7F5" !CDS_LOCATION = "R7F5" #SEC = "1" !CDS_SEC = "1";
"A":   PN = "1"  !CDS_PN = "1";
"B":   PN = "2"  !CDS_PN = "2";
BODY = "RES","I98": #LOCATION = "R7F4" !CDS_LOCATION = "R7F4" #SEC = "1" !CDS_SEC = "1";
"A":   PN = "1"  !CDS_PN = "1";
"B":   PN = "2"  !CDS_PN = "2";
BODY = "RES","I108": #LOCATION = "R7F37" !CDS_LOCATION = "R7F37" #SEC = "1" !CDS_SEC = "1";
"A":   PN = "1"  !CDS_PN = "1";
"B":   PN = "2"  !CDS_PN = "2";
BODY = "RES","I109": #LOCATION = "R7F3" !CDS_LOCATION = "R7F3" #SEC = "1" !CDS_SEC = "1";
"A":   PN = "1"  !CDS_PN = "1";
"B":   PN = "2"  !CDS_PN = "2";
BODY = "CAP_A","I130": #LOCATION = "C7F2" !CDS_LOCATION = "C7F2" #SEC = "1" !CDS_SEC = "1";
"A":   PN = "1"  !CDS_PN = "1";
"B":   PN = "2"  !CDS_PN = "2";
BODY = "CAP_A","I131": #LOCATION = "C7F1" !CDS_LOCATION = "C7F1" #SEC = "1" !CDS_SEC = "1";
"A":   PN = "1"  !CDS_PN = "1";
"B":   PN = "2"  !CDS_PN = "2";
BODY = "CAP_A","I136": #LOCATION = "C3T5" !CDS_LOCATION = "C3T5" #SEC = "1" !CDS_SEC = "1";
"A":   PN = "1"  !CDS_PN = "1";
"B":   PN = "2"  !CDS_PN = "2";
BODY = "CAP_A","I138": #LOCATION = "C3T4" !CDS_LOCATION = "C3T4" #SEC = "1" !CDS_SEC = "1";
"A":   PN = "1"  !CDS_PN = "1";
"B":   PN = "2"  !CDS_PN = "2";
BODY = "RES","I140": #LOCATION = "R7F32" !CDS_LOCATION = "R7F32" #SEC = "1" !CDS_SEC = "1";
"A":   PN = "1"  !CDS_PN = "1";
"B":   PN = "2"  !CDS_PN = "2";
BODY = "W25Q256","I146": #LOCATION = "U7F1" !CDS_LOCATION = "U7F1" #SEC = "1" !CDS_SEC = "1";
"CLK":   PN = "16"  !CDS_PN = "16";
"CS_N":   PN = "7"  !CDS_PN = "7";
"DI_IO<0>":   PN = "15"  !CDS_PN = "15";
"DO_IO<1>":   PN = "8"  !CDS_PN = "8";
"GND":   PN = "10"  !CDS_PN = "10";
"HOLD_N_IO<3>":   PN = "1"  !CDS_PN = "1";
"NC<0>":   PN = "14"  !CDS_PN = "14";
"NC<1>":   PN = "13"  !CDS_PN = "13";
"NC<2>":   PN = "12"  !CDS_PN = "12";
"NC<3>":   PN = "11"  !CDS_PN = "11";
"NC<4>":   PN = "6"  !CDS_PN = "6";
"NC<5>":   PN = "5"  !CDS_PN = "5";
"NC<6>":   PN = "4"  !CDS_PN = "4";
"RESET_N":   PN = "3"  !CDS_PN = "3";
"VCC":   PN = "2"  !CDS_PN = "2";
"WP_N_IO<2>":   PN = "9"  !CDS_PN = "9";
BODY = "RES","I150": #LOCATION = "R3T3" !CDS_LOCATION = "R3T3" #SEC = "1" !CDS_SEC = "1";
"A":   PN = "1"  !CDS_PN = "1";
"B":   PN = "2"  !CDS_PN = "2";
BODY = "RES","I152": #LOCATION = "R3T5" !CDS_LOCATION = "R3T5" #SEC = "1" !CDS_SEC = "1";
"A":   PN = "1"  !CDS_PN = "1";
"B":   PN = "2"  !CDS_PN = "2";
BODY = "RES","I155": #LOCATION = "R3T2" !CDS_LOCATION = "R3T2" #SEC = "1" !CDS_SEC = "1";
"A":   PN = "1"  !CDS_PN = "1";
"B":   PN = "2"  !CDS_PN = "2";
BODY = "RES","I156": #LOCATION = "R3U1" !CDS_LOCATION = "R3U1" #SEC = "1" !CDS_SEC = "1";
"A":   PN = "1"  !CDS_PN = "1";
"B":   PN = "2"  !CDS_PN = "2";
BODY = "RES","I157": #LOCATION = "R3T1" !CDS_LOCATION = "R3T1" #SEC = "1" !CDS_SEC = "1";
"A":   PN = "1"  !CDS_PN = "1";
"B":   PN = "2"  !CDS_PN = "2";
BODY = "RES","I166": #LOCATION = "R8F8" !CDS_LOCATION = "R8F8" &SEC = "1" #&CDS_SEC = "1";
"A":   PN = "1"  !CDS_PN = "1";
"B":   PN = "2"  !CDS_PN = "2";
BODY = "RES","I167": #LOCATION = "R8F7" !CDS_LOCATION = "R8F7" #SEC = "1" !CDS_SEC = "1";
"A":   PN = "1"  !CDS_PN = "1";
"B":   PN = "2"  !CDS_PN = "2";
BODY = "RES","I168": #LOCATION = "R7F28" !CDS_LOCATION = "R7F28" #SEC = "1" !CDS_SEC = "1";
"A":   PN = "1"  !CDS_PN = "1";
"B":   PN = "2"  !CDS_PN = "2";
BODY = "RES","I170": #LOCATION = "R7F30" !CDS_LOCATION = "R7F30" #SEC = "1" !CDS_SEC = "1";
"A":   PN = "1"  !CDS_PN = "1";
"B":   PN = "2"  !CDS_PN = "2";
BODY = "RES","I174": #LOCATION = "R3T4" !CDS_LOCATION = "R3T4" #SEC = "1" !CDS_SEC = "1";
"A":   PN = "1"  !CDS_PN = "1";
"B":   PN = "2"  !CDS_PN = "2";
BODY = "RES","I178": #LOCATION = "R3T12" !CDS_LOCATION = "R3T12" #SEC = "1" !CDS_SEC = "1";
"A":   PN = "1"  !CDS_PN = "1";
"B":   PN = "2"  !CDS_PN = "2";
BODY = "RES","I179": #LOCATION = "R3T9" !CDS_LOCATION = "R3T9" #SEC = "1" !CDS_SEC = "1";
"A":   PN = "1"  !CDS_PN = "1";
"B":   PN = "2"  !CDS_PN = "2";
BODY = "RES","I181": #LOCATION = "R7F29" !CDS_LOCATION = "R7F29" #SEC = "1" !CDS_SEC = "1";
"A":   PN = "1"  !CDS_PN = "1";
"B":   PN = "2"  !CDS_PN = "2";
BODY = "RES","I184": #LOCATION = "R3T10" !CDS_LOCATION = "R3T10" #SEC = "1" !CDS_SEC = "1";
"A":   PN = "1"  !CDS_PN = "1";
"B":   PN = "2"  !CDS_PN = "2";
BODY = "W25Q256FVFIG-GP","I185": #LOCATION = "U3T1" !CDS_LOCATION = "U3T1" #SEC = "1" !CDS_SEC = "1";
"CLK":   PN = "16"  !CDS_PN = "16";
"CS#":   PN = "7"  !CDS_PN = "7";
"DI/IO0":   PN = "15"  !CDS_PN = "15";
"DO/IO1":   PN = "8"  !CDS_PN = "8";
"GND":   PN = "10"  !CDS_PN = "10";
"HOLD#/IO3":   PN = "1"  !CDS_PN = "1";
"NC#4":   PN = "4"  !CDS_PN = "4";
"NC#5":   PN = "5"  !CDS_PN = "5";
"NC#6":   PN = "6"  !CDS_PN = "6";
"NC#11":   PN = "11"  !CDS_PN = "11";
"NC#12":   PN = "12"  !CDS_PN = "12";
"NC#13":   PN = "13"  !CDS_PN = "13";
"NC#14":   PN = "14"  !CDS_PN = "14";
"RESET#":   PN = "3"  !CDS_PN = "3";
"VCC":   PN = "2"  !CDS_PN = "2";
"WP#/IO2":   PN = "9"  !CDS_PN = "9";
BODY = "RES","I187": #LOCATION = "R7W5" !CDS_LOCATION = "R7W5" &SEC = "1" #&CDS_SEC = "1";
"A":   PN = "1"  !CDS_PN = "1";
"B":   PN = "2"  !CDS_PN = "2";
DRAWING = "@baseboard_fab2_lib.baseboard_fab2(sch_1):page154";
BODY = "CAP_A","I14": #LOCATION = "C8E18" !CDS_LOCATION = "C8E18" #SEC = "1" !CDS_SEC = "1";
"A":   PN = "1"  !CDS_PN = "1";
"B":   PN = "2"  !CDS_PN = "2";
BODY = "RES","I62": #LOCATION = "R2T9" !CDS_LOCATION = "R2T9" #SEC = "1" !CDS_SEC = "1";
"A":   PN = "1"  !CDS_PN = "1";
"B":   PN = "2"  !CDS_PN = "2";
BODY = "PI3B3257A","I74": #LOCATION = "U8F1" !CDS_LOCATION = "U8F1" #SEC = "1" !CDS_SEC = "1";
"EN":   PN = "15"  !CDS_PN = "15";
"GND":   PN = "8"  !CDS_PN = "8";
"IA0":   PN = "2"  !CDS_PN = "2";
"IA1":   PN = "3"  !CDS_PN = "3";
"IB0":   PN = "5"  !CDS_PN = "5";
"IB1":   PN = "6"  !CDS_PN = "6";
"IC0":   PN = "11"  !CDS_PN = "11";
"IC1":   PN = "10"  !CDS_PN = "10";
"ID0":   PN = "14"  !CDS_PN = "14";
"ID1":   PN = "13"  !CDS_PN = "13";
"S":   PN = "1"  !CDS_PN = "1";
"VCC":   PN = "16"  !CDS_PN = "16";
"YA":   PN = "4"  !CDS_PN = "4";
"YB":   PN = "7"  !CDS_PN = "7";
"YC":   PN = "9"  !CDS_PN = "9";
"YD":   PN = "12"  !CDS_PN = "12";
BODY = "PI3B3257A","I75": #LOCATION = "U2T1" !CDS_LOCATION = "U2T1" #SEC = "1" !CDS_SEC = "1";
"EN":   PN = "15"  !CDS_PN = "15";
"GND":   PN = "8"  !CDS_PN = "8";
"IA0":   PN = "2"  !CDS_PN = "2";
"IA1":   PN = "3"  !CDS_PN = "3";
"IB0":   PN = "5"  !CDS_PN = "5";
"IB1":   PN = "6"  !CDS_PN = "6";
"IC0":   PN = "11"  !CDS_PN = "11";
"IC1":   PN = "10"  !CDS_PN = "10";
"ID0":   PN = "14"  !CDS_PN = "14";
"ID1":   PN = "13"  !CDS_PN = "13";
"S":   PN = "1"  !CDS_PN = "1";
"VCC":   PN = "16"  !CDS_PN = "16";
"YA":   PN = "4"  !CDS_PN = "4";
"YB":   PN = "7"  !CDS_PN = "7";
"YC":   PN = "9"  !CDS_PN = "9";
"YD":   PN = "12"  !CDS_PN = "12";
BODY = "RES","I92": #LOCATION = "R2T2" !CDS_LOCATION = "R2T2" #SEC = "1" !CDS_SEC = "1";
"A":   PN = "1"  !CDS_PN = "1";
"B":   PN = "2"  !CDS_PN = "2";
BODY = "RES","I93": #LOCATION = "R2R12" !CDS_LOCATION = "R2R12" #SEC = "1" !CDS_SEC = "1";
"A":   PN = "1"  !CDS_PN = "1";
"B":   PN = "2"  !CDS_PN = "2";
BODY = "CAP_A","I94": #LOCATION = "C2T1" !CDS_LOCATION = "C2T1" #SEC = "1" !CDS_SEC = "1";
"A":   PN = "1"  !CDS_PN = "1";
"B":   PN = "2"  !CDS_PN = "2";
BODY = "TTL1G32_A","I99": #LOCATION = "U2T3" !CDS_LOCATION = "U2T3" #SEC = "1" !CDS_SEC = "1";
"A":   PN = "1"  !CDS_PN = "1";
"B":   PN = "2"  !CDS_PN = "2";
"Y":   PN = "4"  !CDS_PN = "4";
BODY = "TTL1G32_A","I100": #LOCATION = "U2T2" !CDS_LOCATION = "U2T2" #SEC = "1" !CDS_SEC = "1";
"A":   PN = "1"  !CDS_PN = "1";
"B":   PN = "2"  !CDS_PN = "2";
"Y":   PN = "4"  !CDS_PN = "4";
BODY = "RES","I101": #LOCATION = "R2T13" !CDS_LOCATION = "R2T13" #SEC = "1" !CDS_SEC = "1";
"A":   PN = "1"  !CDS_PN = "1";
"B":   PN = "2"  !CDS_PN = "2";
BODY = "RES","I105": #LOCATION = "R2T11" !CDS_LOCATION = "R2T11" #SEC = "1" !CDS_SEC = "1";
"A":   PN = "1"  !CDS_PN = "1";
"B":   PN = "2"  !CDS_PN = "2";
BODY = "RES","I106": #LOCATION = "R2T8" !CDS_LOCATION = "R2T8" #SEC = "1" !CDS_SEC = "1";
"A":   PN = "1"  !CDS_PN = "1";
"B":   PN = "2"  !CDS_PN = "2";
BODY = "RES","I119": #LOCATION = "R8F6" !CDS_LOCATION = "R8F6" &SEC = "1" #&CDS_SEC = "1";
"A":   PN = "1"  !CDS_PN = "1";
"B":   PN = "2"  !CDS_PN = "2";
BODY = "FET_N","I126": #LOCATION = "Q8F1" !CDS_LOCATION = "Q8F1" #SEC = "1" !CDS_SEC = "1";
"DRN":   PN = "3"  !CDS_PN = "3";
"GATE":   PN = "1"  !CDS_PN = "1";
"SRC":   PN = "2"  !CDS_PN = "2";
BODY = "RES","I127": #LOCATION = "R2T6" !CDS_LOCATION = "R2T6" #SEC = "1" !CDS_SEC = "1";
"A":   PN = "1"  !CDS_PN = "1";
"B":   PN = "2"  !CDS_PN = "2";
BODY = "RES","I128": #LOCATION = "R1U6" !CDS_LOCATION = "R1U6" #SEC = "1" !CDS_SEC = "1";
"A":   PN = "1"  !CDS_PN = "1";
"B":   PN = "2"  !CDS_PN = "2";
BODY = "CAP_A","I132": #LOCATION = "C2T12" !CDS_LOCATION = "C2T12" #SEC = "1" !CDS_SEC = "1";
"A":   PN = "1"  !CDS_PN = "1";
"B":   PN = "2"  !CDS_PN = "2";
BODY = "CAP_A","I135": #LOCATION = "C2T8" !CDS_LOCATION = "C2T8" #SEC = "1" !CDS_SEC = "1";
"A":   PN = "1"  !CDS_PN = "1";
"B":   PN = "2"  !CDS_PN = "2";
DRAWING = "@baseboard_fab2_lib.baseboard_fab2(sch_1):page155";
BODY = "RES","I53": #LOCATION = "R9A8" !CDS_LOCATION = "R9A8" #SEC = "1" !CDS_SEC = "1";
"A":   PN = "1"  !CDS_PN = "1";
"B":   PN = "2"  !CDS_PN = "2";
BODY = "RES","I65": #LOCATION = "R1L32" !CDS_LOCATION = "R1L32" &SEC = "1" #&CDS_SEC = "1";
"A":   PN = "1"  !CDS_PN = "1";
"B":   PN = "2"  !CDS_PN = "2";
BODY = "RES","I66": #LOCATION = "R1L30" !CDS_LOCATION = "R1L30" &SEC = "1" #&CDS_SEC = "1";
"A":   PN = "1"  !CDS_PN = "1";
"B":   PN = "2"  !CDS_PN = "2";
BODY = "RES","I67": #LOCATION = "R1L25" !CDS_LOCATION = "R1L25" &SEC = "1" #&CDS_SEC = "1";
"A":   PN = "1"  !CDS_PN = "1";
"B":   PN = "2"  !CDS_PN = "2";
BODY = "RES","I68": #LOCATION = "R1L24" !CDS_LOCATION = "R1L24" &SEC = "1" #&CDS_SEC = "1";
"A":   PN = "1"  !CDS_PN = "1";
"B":   PN = "2"  !CDS_PN = "2";
BODY = "RES","I73": #LOCATION = "R1L20" !CDS_LOCATION = "R1L20" &SEC = "1" #&CDS_SEC = "1";
"A":   PN = "1"  !CDS_PN = "1";
"B":   PN = "2"  !CDS_PN = "2";
BODY = "RES","I74": #LOCATION = "R1L18" !CDS_LOCATION = "R1L18" &SEC = "1" #&CDS_SEC = "1";
"A":   PN = "1"  !CDS_PN = "1";
"B":   PN = "2"  !CDS_PN = "2";
BODY = "RES","I75": #LOCATION = "R1L14" !CDS_LOCATION = "R1L14" &SEC = "1" #&CDS_SEC = "1";
"A":   PN = "1"  !CDS_PN = "1";
"B":   PN = "2"  !CDS_PN = "2";
BODY = "RES","I76": #LOCATION = "R1L11" !CDS_LOCATION = "R1L11" &SEC = "1" #&CDS_SEC = "1";
"A":   PN = "1"  !CDS_PN = "1";
"B":   PN = "2"  !CDS_PN = "2";
BODY = "RES","I80": #LOCATION = "R9A7" !CDS_LOCATION = "R9A7" #SEC = "1" !CDS_SEC = "1";
"A":   PN = "1"  !CDS_PN = "1";
"B":   PN = "2"  !CDS_PN = "2";
BODY = "CAP_A","I127": #LOCATION = "C9A1" !CDS_LOCATION = "C9A1" &SEC = "1" #&CDS_SEC = "1";
"A":   PN = "1"  !CDS_PN = "1";
"B":   PN = "2"  !CDS_PN = "2";
BODY = "FUSE","I129": #LOCATION = "F1L1" !CDS_LOCATION = "F1L1" #SEC = "1" !CDS_SEC = "1";
"A<0>":   PN = "1"  !CDS_PN = "1";
"B<0>":   PN = "2"  !CDS_PN = "2";
BODY = "RES","I130": #LOCATION = "R1L9" !CDS_LOCATION = "R1L9" #SEC = "1" !CDS_SEC = "1";
"A":   PN = "1"  !CDS_PN = "1";
"B":   PN = "2"  !CDS_PN = "2";
BODY = "CONN14_H54902001","I171": #LOCATION = "J9A2" !CDS_LOCATION = "J9A2" &SEC = "1" #&CDS_SEC = "1";
"IO1":   PN = "1"  !CDS_PN = "1";
"IO2":   PN = "2"  !CDS_PN = "2";
"IO3":   PN = "3"  !CDS_PN = "3";
"IO4":   PN = "4"  !CDS_PN = "4";
"IO5":   PN = "5"  !CDS_PN = "5";
"IO6":   PN = "6"  !CDS_PN = "6";
"IO7":   PN = "7"  !CDS_PN = "7";
"IO8":   PN = "8"  !CDS_PN = "8";
"IO9":   PN = "9"  !CDS_PN = "9";
"IO10":   PN = "10"  !CDS_PN = "10";
"IO11":   PN = "11"  !CDS_PN = "11";
"IO12":   PN = "12"  !CDS_PN = "12";
"IO13":   PN = "13"  !CDS_PN = "13";
"IO14":   PN = "14"  !CDS_PN = "14";
BODY = "TTL1G07_A","I178": #LOCATION = "U9A1" !CDS_LOCATION = "U9A1" #SEC = "1" !CDS_SEC = "1";
"A":   PN = "2"  !CDS_PN = "2";
"Y":   PN = "4"  !CDS_PN = "4";
BODY = "CAP_A","I184": #LOCATION = "C1T56" !CDS_LOCATION = "C1T56" #SEC = "1" !CDS_SEC = "1";
"A":   PN = "1"  !CDS_PN = "1";
"B":   PN = "2"  !CDS_PN = "2";
BODY = "RES","I186": #LOCATION = "R1L2" !CDS_LOCATION = "R1L2" &SEC = "1" #&CDS_SEC = "1";
"A":   PN = "1"  !CDS_PN = "1";
"B":   PN = "2"  !CDS_PN = "2";
BODY = "FET_N_DUAL","I187": #LOCATION = "Q1L2" !CDS_LOCATION = "Q1L2" #SEC = "2" !CDS_SEC = "2";
"DRAIN<0>":   PN = "3"  !CDS_PN = "3";
"GATE<0>":   PN = "5"  !CDS_PN = "5";
"SOURCE<0>":   PN = "4"  !CDS_PN = "4";
BODY = "FET_N_DUAL","I188": #LOCATION = "Q1L2" !CDS_LOCATION = "Q1L2" #SEC = "1" !CDS_SEC = "1";
"DRAIN<0>":   PN = "6"  !CDS_PN = "6";
"GATE<0>":   PN = "2"  !CDS_PN = "2";
"SOURCE<0>":   PN = "1"  !CDS_PN = "1";
BODY = "RES","I196": #LOCATION = "R6W19" !CDS_LOCATION = "R6W19" #SEC = "1" !CDS_SEC = "1";
"A":   PN = "1"  !CDS_PN = "1";
"B":   PN = "2"  !CDS_PN = "2";
BODY = "RES","I198": #LOCATION = "R9A5" !CDS_LOCATION = "R9A5" #SEC = "1" !CDS_SEC = "1";
"A":   PN = "1"  !CDS_PN = "1";
"B":   PN = "2"  !CDS_PN = "2";
BODY = "RES","I201": #LOCATION = "R6W40" !CDS_LOCATION = "R6W40" #SEC = "1" !CDS_SEC = "1";
"A":   PN = "1"  !CDS_PN = "1";
"B":   PN = "2"  !CDS_PN = "2";
BODY = "DIODE","I202": #LOCATION = "CR9W1" !CDS_LOCATION = "CR9W1" #SEC = "1" !CDS_SEC = "1";
"A":   PN = "2"  !CDS_PN = "2";
"C":   PN = "1"  !CDS_PN = "1";
DRAWING = "@baseboard_fab2_lib.baseboard_fab2(sch_1):page156";
BODY = "RES","I206": #LOCATION = "R2T34" !CDS_LOCATION = "R2T34" #SEC = "1" !CDS_SEC = "1";
"A":   PN = "1"  !CDS_PN = "1";
"B":   PN = "2"  !CDS_PN = "2";
BODY = "RES","I207": #LOCATION = "R2T35" !CDS_LOCATION = "R2T35" #SEC = "1" !CDS_SEC = "1";
"A":   PN = "1"  !CDS_PN = "1";
"B":   PN = "2"  !CDS_PN = "2";
BODY = "RES","I210": #LOCATION = "R2T22" !CDS_LOCATION = "R2T22" #SEC = "1" !CDS_SEC = "1";
"A":   PN = "1"  !CDS_PN = "1";
"B":   PN = "2"  !CDS_PN = "2";
BODY = "RES","I211": #LOCATION = "R8F26" !CDS_LOCATION = "R8F26" #SEC = "1" !CDS_SEC = "1";
"A":   PN = "1"  !CDS_PN = "1";
"B":   PN = "2"  !CDS_PN = "2";
BODY = "RES","I214": #LOCATION = "R8E24" !CDS_LOCATION = "R8E24" #SEC = "1" !CDS_SEC = "1";
"A":   PN = "1"  !CDS_PN = "1";
"B":   PN = "2"  !CDS_PN = "2";
BODY = "RES","I215": #LOCATION = "R8E22" !CDS_LOCATION = "R8E22" #SEC = "1" !CDS_SEC = "1";
"A":   PN = "1"  !CDS_PN = "1";
"B":   PN = "2"  !CDS_PN = "2";
BODY = "RES","I265": #LOCATION = "R2U2" !CDS_LOCATION = "R2U2" #SEC = "1" !CDS_SEC = "1";
"A":   PN = "1"  !CDS_PN = "1";
"B":   PN = "2"  !CDS_PN = "2";
BODY = "RES","I267": #LOCATION = "R8G2" !CDS_LOCATION = "R8G2" #SEC = "1" !CDS_SEC = "1";
"A":   PN = "1"  !CDS_PN = "1";
"B":   PN = "2"  !CDS_PN = "2";
BODY = "CAP_A","I273": #LOCATION = "C2T35" !CDS_LOCATION = "C2T35" #SEC = "1" !CDS_SEC = "1";
"A":   PN = "1"  !CDS_PN = "1";
"B":   PN = "2"  !CDS_PN = "2";
BODY = "CAP_A","I275": #LOCATION = "C8F16" !CDS_LOCATION = "C8F16" #SEC = "1" !CDS_SEC = "1";
"A":   PN = "1"  !CDS_PN = "1";
"B":   PN = "2"  !CDS_PN = "2";
BODY = "RES","I279": #LOCATION = "R8E11" !CDS_LOCATION = "R8E11" #SEC = "1" !CDS_SEC = "1";
"A":   PN = "1"  !CDS_PN = "1";
"B":   PN = "2"  !CDS_PN = "2";
BODY = "CONN3_C95678002","I281": #LOCATION = "J9B2" !CDS_LOCATION = "J9B2" #SEC = "1" !CDS_SEC = "1";
"IO1":   PN = "1"  !CDS_PN = "1";
"IO2":   PN = "2"  !CDS_PN = "2";
"IO3":   PN = "3"  !CDS_PN = "3";
BODY = "CONN3_C95678002","I285": #LOCATION = "J8C1" !CDS_LOCATION = "J8C1" #SEC = "1" !CDS_SEC = "1";
"IO1":   PN = "1"  !CDS_PN = "1";
"IO2":   PN = "2"  !CDS_PN = "2";
"IO3":   PN = "3"  !CDS_PN = "3";
BODY = "RES","I288": #LOCATION = "R2T18" !CDS_LOCATION = "R2T18" #SEC = "1" !CDS_SEC = "1";
"A":   PN = "1"  !CDS_PN = "1";
"B":   PN = "2"  !CDS_PN = "2";
BODY = "RES","I289": #LOCATION = "R2T28" !CDS_LOCATION = "R2T28" #SEC = "1" !CDS_SEC = "1";
"A":   PN = "1"  !CDS_PN = "1";
"B":   PN = "2"  !CDS_PN = "2";
BODY = "RES","I299": #LOCATION = "R6D16" !CDS_LOCATION = "R6D16" #SEC = "1" !CDS_SEC = "1";
"A":   PN = "1"  !CDS_PN = "1";
"B":   PN = "2"  !CDS_PN = "2";
BODY = "RES","I300": #LOCATION = "R3D31" !CDS_LOCATION = "R3D31" #SEC = "1" !CDS_SEC = "1";
"A":   PN = "1"  !CDS_PN = "1";
"B":   PN = "2"  !CDS_PN = "2";
BODY = "RES","I302": #LOCATION = "R6N14" !CDS_LOCATION = "R6N14" #SEC = "1" !CDS_SEC = "1";
"A":   PN = "1"  !CDS_PN = "1";
"B":   PN = "2"  !CDS_PN = "2";
BODY = "RES","I303": #LOCATION = "R6N13" !CDS_LOCATION = "R6N13" #SEC = "1" !CDS_SEC = "1";
"A":   PN = "1"  !CDS_PN = "1";
"B":   PN = "2"  !CDS_PN = "2";
BODY = "RES","I304": #LOCATION = "R6N15" !CDS_LOCATION = "R6N15" #SEC = "1" !CDS_SEC = "1";
"A":   PN = "1"  !CDS_PN = "1";
"B":   PN = "2"  !CDS_PN = "2";
BODY = "RES","I312": #LOCATION = "R1C32" !CDS_LOCATION = "R1C32" #SEC = "1" !CDS_SEC = "1";
"A":   PN = "1"  !CDS_PN = "1";
"B":   PN = "2"  !CDS_PN = "2";
BODY = "RES","I313": #LOCATION = "R1C33" !CDS_LOCATION = "R1C33" #SEC = "1" !CDS_SEC = "1";
"A":   PN = "1"  !CDS_PN = "1";
"B":   PN = "2"  !CDS_PN = "2";
BODY = "RES","I320": #LOCATION = "R1C34" !CDS_LOCATION = "R1C34" #SEC = "1" !CDS_SEC = "1";
"A":   PN = "1"  !CDS_PN = "1";
"B":   PN = "2"  !CDS_PN = "2";
BODY = "RES","I321": #LOCATION = "R9M21" !CDS_LOCATION = "R9M21" #SEC = "1" !CDS_SEC = "1";
"A":   PN = "1"  !CDS_PN = "1";
"B":   PN = "2"  !CDS_PN = "2";
BODY = "RES","I322": #LOCATION = "R4A8" !CDS_LOCATION = "R4A8" #SEC = "1" !CDS_SEC = "1";
"A":   PN = "1"  !CDS_PN = "1";
"B":   PN = "2"  !CDS_PN = "2";
BODY = "RES","I323": #LOCATION = "R9M20" !CDS_LOCATION = "R9M20" #SEC = "1" !CDS_SEC = "1";
"A":   PN = "1"  !CDS_PN = "1";
"B":   PN = "2"  !CDS_PN = "2";
BODY = "RES","I324": #LOCATION = "R4A9" !CDS_LOCATION = "R4A9" #SEC = "1" !CDS_SEC = "1";
"A":   PN = "1"  !CDS_PN = "1";
"B":   PN = "2"  !CDS_PN = "2";
BODY = "RES","I331": #LOCATION = "R3P54" !CDS_LOCATION = "R3P54" #SEC = "1" !CDS_SEC = "1";
"A":   PN = "1"  !CDS_PN = "1";
"B":   PN = "2"  !CDS_PN = "2";
BODY = "RES","I333": #LOCATION = "R3P56" !CDS_LOCATION = "R3P56" #SEC = "1" !CDS_SEC = "1";
"A":   PN = "1"  !CDS_PN = "1";
"B":   PN = "2"  !CDS_PN = "2";
BODY = "RES","I336": #LOCATION = "R1C35" !CDS_LOCATION = "R1C35" #SEC = "1" !CDS_SEC = "1";
"A":   PN = "1"  !CDS_PN = "1";
"B":   PN = "2"  !CDS_PN = "2";
BODY = "RES","I337": #LOCATION = "R1C36" !CDS_LOCATION = "R1C36" #SEC = "1" !CDS_SEC = "1";
"A":   PN = "1"  !CDS_PN = "1";
"B":   PN = "2"  !CDS_PN = "2";
BODY = "SN74LVC2G07DCKR-GP","I340": #LOCATION = "U8F3" !CDS_LOCATION = "U8F3" #SEC = "1" !CDS_SEC = "1";
"1A":   PN = "1"  !CDS_PN = "1";
"1Y":   PN = "6"  !CDS_PN = "6";
"2A":   PN = "3"  !CDS_PN = "3";
"2Y":   PN = "4"  !CDS_PN = "4";
"GND":   PN = "2"  !CDS_PN = "2";
"VCC":   PN = "5"  !CDS_PN = "5";
BODY = "SN74LVC2G07DCKR-GP","I342": #LOCATION = "U8G1" !CDS_LOCATION = "U8G1" #SEC = "1" !CDS_SEC = "1";
"1A":   PN = "1"  !CDS_PN = "1";
"1Y":   PN = "6"  !CDS_PN = "6";
"2A":   PN = "3"  !CDS_PN = "3";
"2Y":   PN = "4"  !CDS_PN = "4";
"GND":   PN = "2"  !CDS_PN = "2";
"VCC":   PN = "5"  !CDS_PN = "5";
DRAWING = "@baseboard_fab2_lib.baseboard_fab2(sch_1):page157";
BODY = "RES","I97": #LOCATION = "R2N27" !CDS_LOCATION = "R2N27" #SEC = "1" !CDS_SEC = "1";
"A":   PN = "1"  !CDS_PN = "1";
"B":   PN = "2"  !CDS_PN = "2";
BODY = "RES","I296": #LOCATION = "R8F23" !CDS_LOCATION = "R8F23" #SEC = "1" !CDS_SEC = "1";
"A":   PN = "1"  !CDS_PN = "1";
"B":   PN = "2"  !CDS_PN = "2";
BODY = "RES","I298": #LOCATION = "R2T29" !CDS_LOCATION = "R2T29" #SEC = "1" !CDS_SEC = "1";
"A":   PN = "1"  !CDS_PN = "1";
"B":   PN = "2"  !CDS_PN = "2";
BODY = "RES","I302": #LOCATION = "R2N25" !CDS_LOCATION = "R2N25" #SEC = "1" !CDS_SEC = "1";
"A":   PN = "1"  !CDS_PN = "1";
"B":   PN = "2"  !CDS_PN = "2";
BODY = "RES","I316": #LOCATION = "R8F24" !CDS_LOCATION = "R8F24" #SEC = "1" !CDS_SEC = "1";
"A":   PN = "1"  !CDS_PN = "1";
"B":   PN = "2"  !CDS_PN = "2";
BODY = "RES","I326": #LOCATION = "R2T5" !CDS_LOCATION = "R2T5" #SEC = "1" !CDS_SEC = "1";
"A":   PN = "1"  !CDS_PN = "1";
"B":   PN = "2"  !CDS_PN = "2";
BODY = "RES","I327": #LOCATION = "R2T7" !CDS_LOCATION = "R2T7" #SEC = "1" !CDS_SEC = "1";
"A":   PN = "1"  !CDS_PN = "1";
"B":   PN = "2"  !CDS_PN = "2";
BODY = "NPN","I330": #LOCATION = "Q2T1" !CDS_LOCATION = "Q2T1" #SEC = "1" !CDS_SEC = "1";
"B":   PN = "1"  !CDS_PN = "1";
"C":   PN = "3"  !CDS_PN = "3";
"E":   PN = "2"  !CDS_PN = "2";
BODY = "RES","I335": #LOCATION = "R8D25" !CDS_LOCATION = "R8D25" #SEC = "1" !CDS_SEC = "1";
"A":   PN = "1"  !CDS_PN = "1";
"B":   PN = "2"  !CDS_PN = "2";
BODY = "FET_N","I340": #LOCATION = "Q2T2" !CDS_LOCATION = "Q2T2" #SEC = "1" !CDS_SEC = "1";
"DRN":   PN = "3"  !CDS_PN = "3";
"GATE":   PN = "1"  !CDS_PN = "1";
"SRC":   PN = "2"  !CDS_PN = "2";
BODY = "RES","I342": #LOCATION = "R3N12" !CDS_LOCATION = "R3N12" #SEC = "1" !CDS_SEC = "1";
"A":   PN = "1"  !CDS_PN = "1";
"B":   PN = "2"  !CDS_PN = "2";
BODY = "RES","I344": #LOCATION = "R3N11" !CDS_LOCATION = "R3N11" #SEC = "1" !CDS_SEC = "1";
"A":   PN = "1"  !CDS_PN = "1";
"B":   PN = "2"  !CDS_PN = "2";
BODY = "RES","I346": #LOCATION = "R2M2" !CDS_LOCATION = "R2M2" #SEC = "1" !CDS_SEC = "1";
"A":   PN = "1"  !CDS_PN = "1";
"B":   PN = "2"  !CDS_PN = "2";
BODY = "RES","I348": #LOCATION = "R2M5" !CDS_LOCATION = "R2M5" #SEC = "1" !CDS_SEC = "1";
"A":   PN = "1"  !CDS_PN = "1";
"B":   PN = "2"  !CDS_PN = "2";
BODY = "SWITCH_D90553001","I351": #LOCATION = "S8E1" !CDS_LOCATION = "S8E1" #SEC = "1" !CDS_SEC = "1";
"A":   PN = "1"  !CDS_PN = "1";
"B":   PN = "2"  !CDS_PN = "2";
BODY = "RES","I352": #LOCATION = "R2R9" !CDS_LOCATION = "R2R9" #SEC = "1" !CDS_SEC = "1";
"A":   PN = "1"  !CDS_PN = "1";
"B":   PN = "2"  !CDS_PN = "2";
BODY = "CAP_A","I353": #LOCATION = "C2R12" !CDS_LOCATION = "C2R12" #SEC = "1" !CDS_SEC = "1";
"A":   PN = "1"  !CDS_PN = "1";
"B":   PN = "2"  !CDS_PN = "2";
BODY = "RES","I361": #LOCATION = "R8E19" !CDS_LOCATION = "R8E19" #SEC = "1" !CDS_SEC = "1";
"A":   PN = "1"  !CDS_PN = "1";
"B":   PN = "2"  !CDS_PN = "2";
BODY = "RES","I367": #LOCATION = "R2U4" !CDS_LOCATION = "R2U4" #SEC = "1" !CDS_SEC = "1";
"A":   PN = "1"  !CDS_PN = "1";
"B":   PN = "2"  !CDS_PN = "2";
BODY = "RES","I368": #LOCATION = "R4R1" !CDS_LOCATION = "R4R1" #SEC = "1" !CDS_SEC = "1";
"A":   PN = "1"  !CDS_PN = "1";
"B":   PN = "2"  !CDS_PN = "2";
BODY = "CAP_A","I370": #LOCATION = "C2T3" !CDS_LOCATION = "C2T3" #SEC = "1" !CDS_SEC = "1";
"A":   PN = "1"  !CDS_PN = "1";
"B":   PN = "2"  !CDS_PN = "2";
BODY = "TTL1G07_A","I374": #LOCATION = "U8D2" !CDS_LOCATION = "U8D2" #SEC = "1" !CDS_SEC = "1";
"A":   PN = "2"  !CDS_PN = "2";
"Y":   PN = "4"  !CDS_PN = "4";
BODY = "CAP_A","I376": #LOCATION = "C8D1" !CDS_LOCATION = "C8D1" #SEC = "1" !CDS_SEC = "1";
"A":   PN = "1"  !CDS_PN = "1";
"B":   PN = "2"  !CDS_PN = "2";
BODY = "RES","I382": #LOCATION = "R1L7" !CDS_LOCATION = "R1L7" #SEC = "1" !CDS_SEC = "1";
"A":   PN = "1"  !CDS_PN = "1";
"B":   PN = "2"  !CDS_PN = "2";
BODY = "RES","I385": #LOCATION = "R8E32" !CDS_LOCATION = "R8E32" #SEC = "1" !CDS_SEC = "1";
"A":   PN = "1"  !CDS_PN = "1";
"B":   PN = "2"  !CDS_PN = "2";
BODY = "RES","I386": #LOCATION = "R8D22" !CDS_LOCATION = "R8D22" #SEC = "1" !CDS_SEC = "1";
"A":   PN = "1"  !CDS_PN = "1";
"B":   PN = "2"  !CDS_PN = "2";
BODY = "RES","I388": #LOCATION = "R8D36" !CDS_LOCATION = "R8D36" #SEC = "1" !CDS_SEC = "1";
"A":   PN = "1"  !CDS_PN = "1";
"B":   PN = "2"  !CDS_PN = "2";
BODY = "TC7PZ14FU-GP","I390": #LOCATION = "U2R1" !CDS_LOCATION = "U2R1" #SEC = "1" !CDS_SEC = "1";
"1A":   PN = "1"  !CDS_PN = "1";
"1Y":   PN = "6"  !CDS_PN = "6";
"2A":   PN = "3"  !CDS_PN = "3";
"2Y":   PN = "4"  !CDS_PN = "4";
"GND":   PN = "2"  !CDS_PN = "2";
"VCC":   PN = "5"  !CDS_PN = "5";
BODY = "RES","I391": #LOCATION = "R2R10" !CDS_LOCATION = "R2R10" #SEC = "1" !CDS_SEC = "1";
"A":   PN = "1"  !CDS_PN = "1";
"B":   PN = "2"  !CDS_PN = "2";
BODY = "RES","I393": #LOCATION = "R9E14" !CDS_LOCATION = "R9E14" #SEC = "1" !CDS_SEC = "1";
"A":   PN = "1"  !CDS_PN = "1";
"B":   PN = "2"  !CDS_PN = "2";
BODY = "TTL1G07_A","I394": #LOCATION = "U25W9" !CDS_LOCATION = "U25W9" #SEC = "1" !CDS_SEC = "1";
"A":   PN = "2"  !CDS_PN = "2";
"Y":   PN = "4"  !CDS_PN = "4";
BODY = "RES","I396": #LOCATION = "R25W153" !CDS_LOCATION = "R25W153" #SEC = "1" !CDS_SEC = "1";
"A":   PN = "1"  !CDS_PN = "1";
"B":   PN = "2"  !CDS_PN = "2";
DRAWING = "@baseboard_fab2_lib.baseboard_fab2(sch_1):page158";
BODY = "CAP_A","I70": #LOCATION = "C1T10" !CDS_LOCATION = "C1T10" #SEC = "1" !CDS_SEC = "1";
"A":   PN = "1"  !CDS_PN = "1";
"B":   PN = "2"  !CDS_PN = "2";
BODY = "FSA3357","I74": #LOCATION = "U9F2" !CDS_LOCATION = "U9F2" #SEC = "1" !CDS_SEC = "1";
"A":   PN = "7"  !CDS_PN = "7";
"B0":   PN = "1"  !CDS_PN = "1";
"B1":   PN = "2"  !CDS_PN = "2";
"B2":   PN = "3"  !CDS_PN = "3";
"GND":   PN = "4"  !CDS_PN = "4";
"S1":   PN = "6"  !CDS_PN = "6";
"S2":   PN = "5"  !CDS_PN = "5";
"VCC":   PN = "8"  !CDS_PN = "8";
BODY = "FSA3357","I75": #LOCATION = "U9F1" !CDS_LOCATION = "U9F1" #SEC = "1" !CDS_SEC = "1";
"A":   PN = "7"  !CDS_PN = "7";
"B0":   PN = "1"  !CDS_PN = "1";
"B1":   PN = "2"  !CDS_PN = "2";
"B2":   PN = "3"  !CDS_PN = "3";
"GND":   PN = "4"  !CDS_PN = "4";
"S1":   PN = "6"  !CDS_PN = "6";
"S2":   PN = "5"  !CDS_PN = "5";
"VCC":   PN = "8"  !CDS_PN = "8";
BODY = "RES","I86": #LOCATION = "R9F25" !CDS_LOCATION = "R9F25" #SEC = "1" !CDS_SEC = "1";
"A":   PN = "1"  !CDS_PN = "1";
"B":   PN = "2"  !CDS_PN = "2";
BODY = "RES","I91": #LOCATION = "R9F27" !CDS_LOCATION = "R9F27" #SEC = "1" !CDS_SEC = "1";
"A":   PN = "1"  !CDS_PN = "1";
"B":   PN = "2"  !CDS_PN = "2";
BODY = "CAP_A","I97": #LOCATION = "C1T11" !CDS_LOCATION = "C1T11" #SEC = "1" !CDS_SEC = "1";
"A":   PN = "1"  !CDS_PN = "1";
"B":   PN = "2"  !CDS_PN = "2";
BODY = "RES","I99": #LOCATION = "R9F26" !CDS_LOCATION = "R9F26" #SEC = "1" !CDS_SEC = "1";
"A":   PN = "1"  !CDS_PN = "1";
"B":   PN = "2"  !CDS_PN = "2";
BODY = "RES","I100": #LOCATION = "R9F24" !CDS_LOCATION = "R9F24" #SEC = "1" !CDS_SEC = "1";
"A":   PN = "1"  !CDS_PN = "1";
"B":   PN = "2"  !CDS_PN = "2";
BODY = "LED","I130": #LOCATION = "DS9A4" !CDS_LOCATION = "DS9A4" #SEC = "1" !CDS_SEC = "1";
"A":   PN = "1"  !CDS_PN = "1";
"C":   PN = "2"  !CDS_PN = "2";
BODY = "RES","I131": #LOCATION = "R1L43" !CDS_LOCATION = "R1L43" #SEC = "1" !CDS_SEC = "1";
"A":   PN = "1"  !CDS_PN = "1";
"B":   PN = "2"  !CDS_PN = "2";
BODY = "LED","I134": #LOCATION = "DS9A7" !CDS_LOCATION = "DS9A7" #SEC = "1" !CDS_SEC = "1";
"A":   PN = "1"  !CDS_PN = "1";
"C":   PN = "2"  !CDS_PN = "2";
BODY = "RES","I136": #LOCATION = "R1L44" !CDS_LOCATION = "R1L44" #SEC = "1" !CDS_SEC = "1";
"A":   PN = "1"  !CDS_PN = "1";
"B":   PN = "2"  !CDS_PN = "2";
BODY = "RES","I148": #LOCATION = "R9F65" !CDS_LOCATION = "R9F65" #SEC = "1" !CDS_SEC = "1";
"A":   PN = "1"  !CDS_PN = "1";
"B":   PN = "2"  !CDS_PN = "2";
BODY = "RES","I149": #LOCATION = "R9F68" !CDS_LOCATION = "R9F68" #SEC = "1" !CDS_SEC = "1";
"A":   PN = "1"  !CDS_PN = "1";
"B":   PN = "2"  !CDS_PN = "2";
BODY = "RES","I150": #LOCATION = "R9F69" !CDS_LOCATION = "R9F69" #SEC = "1" !CDS_SEC = "1";
"A":   PN = "1"  !CDS_PN = "1";
"B":   PN = "2"  !CDS_PN = "2";
BODY = "RES","I152": #LOCATION = "R9F66" !CDS_LOCATION = "R9F66" &SEC = "1" #&CDS_SEC = "1";
"A":   PN = "1"  !CDS_PN = "1";
"B":   PN = "2"  !CDS_PN = "2";
BODY = "RES","I153": #LOCATION = "R9W33" !CDS_LOCATION = "R9W33" #SEC = "1" !CDS_SEC = "1";
"A":   PN = "1"  !CDS_PN = "1";
"B":   PN = "2"  !CDS_PN = "2";
BODY = "RES","I154": #LOCATION = "R9W34" !CDS_LOCATION = "R9W34" #SEC = "1" !CDS_SEC = "1";
"A":   PN = "1"  !CDS_PN = "1";
"B":   PN = "2"  !CDS_PN = "2";
BODY = "RES","I155": #LOCATION = "R9W35" !CDS_LOCATION = "R9W35" #SEC = "1" !CDS_SEC = "1";
"A":   PN = "1"  !CDS_PN = "1";
"B":   PN = "2"  !CDS_PN = "2";
DRAWING = "@baseboard_fab2_lib.baseboard_fab2(sch_1):page159";
BODY = "RES","I210": #LOCATION = "R8G3" !CDS_LOCATION = "R8G3" #SEC = "1" !CDS_SEC = "1";
"A":   PN = "1"  !CDS_PN = "1";
"B":   PN = "2"  !CDS_PN = "2";
BODY = "RES","I212": #LOCATION = "R8G6" !CDS_LOCATION = "R8G6" #SEC = "1" !CDS_SEC = "1";
"A":   PN = "1"  !CDS_PN = "1";
"B":   PN = "2"  !CDS_PN = "2";
BODY = "RES","I214": #LOCATION = "R2U5" !CDS_LOCATION = "R2U5" #SEC = "1" !CDS_SEC = "1";
"A":   PN = "1"  !CDS_PN = "1";
"B":   PN = "2"  !CDS_PN = "2";
BODY = "RES","I216": #LOCATION = "R2U13" !CDS_LOCATION = "R2U13" #SEC = "1" !CDS_SEC = "1";
"A":   PN = "1"  !CDS_PN = "1";
"B":   PN = "2"  !CDS_PN = "2";
BODY = "RES","I218": #LOCATION = "R2U1" !CDS_LOCATION = "R2U1" &SEC = "1" #&CDS_SEC = "1";
"A":   PN = "1"  !CDS_PN = "1";
"B":   PN = "2"  !CDS_PN = "2";
BODY = "RES","I219": #LOCATION = "R2T49" !CDS_LOCATION = "R2T49" &SEC = "1" #&CDS_SEC = "1";
"A":   PN = "1"  !CDS_PN = "1";
"B":   PN = "2"  !CDS_PN = "2";
BODY = "RES","I220": #LOCATION = "R2U7" !CDS_LOCATION = "R2U7" &SEC = "1" #&CDS_SEC = "1";
"A":   PN = "1"  !CDS_PN = "1";
"B":   PN = "2"  !CDS_PN = "2";
BODY = "RES","I221": #LOCATION = "R2U10" !CDS_LOCATION = "R2U10" &SEC = "1" #&CDS_SEC = "1";
"A":   PN = "1"  !CDS_PN = "1";
"B":   PN = "2"  !CDS_PN = "2";
BODY = "RES","I222": #LOCATION = "R1U11" !CDS_LOCATION = "R1U11" &SEC = "1" #&CDS_SEC = "1";
"A":   PN = "1"  !CDS_PN = "1";
"B":   PN = "2"  !CDS_PN = "2";
BODY = "RES","I223": #LOCATION = "R1U8" !CDS_LOCATION = "R1U8" &SEC = "1" #&CDS_SEC = "1";
"A":   PN = "1"  !CDS_PN = "1";
"B":   PN = "2"  !CDS_PN = "2";
BODY = "RES","I224": #LOCATION = "R9G12" !CDS_LOCATION = "R9G12" &SEC = "1" #&CDS_SEC = "1";
"A":   PN = "1"  !CDS_PN = "1";
"B":   PN = "2"  !CDS_PN = "2";
BODY = "RES","I225": #LOCATION = "R1U20" !CDS_LOCATION = "R1U20" &SEC = "1" #&CDS_SEC = "1";
"A":   PN = "1"  !CDS_PN = "1";
"B":   PN = "2"  !CDS_PN = "2";
BODY = "RES","I226": #LOCATION = "R1U19" !CDS_LOCATION = "R1U19" &SEC = "1" #&CDS_SEC = "1";
"A":   PN = "1"  !CDS_PN = "1";
"B":   PN = "2"  !CDS_PN = "2";
BODY = "RES","I227": #LOCATION = "R9G13" !CDS_LOCATION = "R9G13" &SEC = "1" #&CDS_SEC = "1";
"A":   PN = "1"  !CDS_PN = "1";
"B":   PN = "2"  !CDS_PN = "2";
BODY = "RES","I228": #LOCATION = "R8G5" !CDS_LOCATION = "R8G5" &SEC = "1" #&CDS_SEC = "1";
"A":   PN = "1"  !CDS_PN = "1";
"B":   PN = "2"  !CDS_PN = "2";
BODY = "RES","I229": #LOCATION = "R8G4" !CDS_LOCATION = "R8G4" &SEC = "1" #&CDS_SEC = "1";
"A":   PN = "1"  !CDS_PN = "1";
"B":   PN = "2"  !CDS_PN = "2";
BODY = "RES","I230": #LOCATION = "R2U34" !CDS_LOCATION = "R2U34" &SEC = "1" #&CDS_SEC = "1";
"A":   PN = "1"  !CDS_PN = "1";
"B":   PN = "2"  !CDS_PN = "2";
BODY = "RES","I231": #LOCATION = "R2U33" !CDS_LOCATION = "R2U33" &SEC = "1" #&CDS_SEC = "1";
"A":   PN = "1"  !CDS_PN = "1";
"B":   PN = "2"  !CDS_PN = "2";
BODY = "RES","I232": #LOCATION = "R1U9" !CDS_LOCATION = "R1U9" &SEC = "1" #&CDS_SEC = "1";
"A":   PN = "1"  !CDS_PN = "1";
"B":   PN = "2"  !CDS_PN = "2";
BODY = "RES","I233": #LOCATION = "R1U10" !CDS_LOCATION = "R1U10" &SEC = "1" #&CDS_SEC = "1";
"A":   PN = "1"  !CDS_PN = "1";
"B":   PN = "2"  !CDS_PN = "2";
BODY = "RES","I235": #LOCATION = "R8C15" !CDS_LOCATION = "R8C15" #SEC = "1" !CDS_SEC = "1";
"A":   PN = "1"  !CDS_PN = "1";
"B":   PN = "2"  !CDS_PN = "2";
BODY = "RES","I237": #LOCATION = "R8C16" !CDS_LOCATION = "R8C16" #SEC = "1" !CDS_SEC = "1";
"A":   PN = "1"  !CDS_PN = "1";
"B":   PN = "2"  !CDS_PN = "2";
DRAWING = "@baseboard_fab2_lib.baseboard_fab2(sch_1):page160";
BODY = "RES","I4": #LOCATION = "R1T8" !CDS_LOCATION = "R1T8" &SEC = "1" #&CDS_SEC = "1";
"A":   PN = "1"  !CDS_PN = "1";
"B":   PN = "2"  !CDS_PN = "2";
BODY = "RES","I46": #LOCATION = "R1T3" !CDS_LOCATION = "R1T3" #SEC = "1" !CDS_SEC = "1";
"A":   PN = "1"  !CDS_PN = "1";
"B":   PN = "2"  !CDS_PN = "2";
BODY = "RES","I49": #LOCATION = "R1T2" !CDS_LOCATION = "R1T2" #SEC = "1" !CDS_SEC = "1";
"A":   PN = "1"  !CDS_PN = "1";
"B":   PN = "2"  !CDS_PN = "2";
BODY = "RES","I50": #LOCATION = "R1T7" !CDS_LOCATION = "R1T7" &SEC = "1" #&CDS_SEC = "1";
"A":   PN = "1"  !CDS_PN = "1";
"B":   PN = "2"  !CDS_PN = "2";
BODY = "RES","I51": #LOCATION = "R9F23" !CDS_LOCATION = "R9F23" &SEC = "1" #&CDS_SEC = "1";
"A":   PN = "1"  !CDS_PN = "1";
"B":   PN = "2"  !CDS_PN = "2";
BODY = "RES","I52": #LOCATION = "R9F22" !CDS_LOCATION = "R9F22" &SEC = "1" #&CDS_SEC = "1";
"A":   PN = "1"  !CDS_PN = "1";
"B":   PN = "2"  !CDS_PN = "2";
DRAWING = "@baseboard_fab2_lib.baseboard_fab2(sch_1):page161";
BODY = "CAP","I3": #LOCATION = "C1E21" !CDS_LOCATION = "C1E21" #SEC = "1" !CDS_SEC = "1";
"A":   PN = "1"  !CDS_PN = "1";
"B":   PN = "2"  !CDS_PN = "2";
BODY = "CAP_A","I4": #LOCATION = "C1E20" !CDS_LOCATION = "C1E20" #SEC = "1" !CDS_SEC = "1";
"A":   PN = "1"  !CDS_PN = "1";
"B":   PN = "2"  !CDS_PN = "2";
BODY = "CAP_A","I26": #LOCATION = "C9M5" !CDS_LOCATION = "C9M5" #SEC = "1" !CDS_SEC = "1";
"A":   PN = "1"  !CDS_PN = "1";
"B":   PN = "2"  !CDS_PN = "2";
BODY = "CAP","I27": #LOCATION = "C9M4" !CDS_LOCATION = "C9M4" #SEC = "1" !CDS_SEC = "1";
"A":   PN = "1"  !CDS_PN = "1";
"B":   PN = "2"  !CDS_PN = "2";
BODY = "DIODE","I42": #LOCATION = "CR1F1" !CDS_LOCATION = "CR1F1" #SEC = "1" !CDS_SEC = "1";
"A":   PN = "2"  !CDS_PN = "2";
"C":   PN = "1"  !CDS_PN = "1";
BODY = "RES","I43": #LOCATION = "R1F2" !CDS_LOCATION = "R1F2" #SEC = "1" !CDS_SEC = "1";
"A":   PN = "1"  !CDS_PN = "1";
"B":   PN = "2"  !CDS_PN = "2";
BODY = "RES","I45": #LOCATION = "R1F1" !CDS_LOCATION = "R1F1" #SEC = "1" !CDS_SEC = "1";
"A":   PN = "1"  !CDS_PN = "1";
"B":   PN = "2"  !CDS_PN = "2";
BODY = "CAP_A","I46": #LOCATION = "C1F9" !CDS_LOCATION = "C1F9" #SEC = "1" !CDS_SEC = "1";
"A":   PN = "1"  !CDS_PN = "1";
"B":   PN = "2"  !CDS_PN = "2";
BODY = "DIODE","I50": #LOCATION = "CR1E1" !CDS_LOCATION = "CR1E1" #SEC = "1" !CDS_SEC = "1";
"A":   PN = "2"  !CDS_PN = "2";
"C":   PN = "1"  !CDS_PN = "1";
BODY = "RES","I51": #LOCATION = "R1E12" !CDS_LOCATION = "R1E12" #SEC = "1" !CDS_SEC = "1";
"A":   PN = "1"  !CDS_PN = "1";
"B":   PN = "2"  !CDS_PN = "2";
BODY = "DIODE","I62": #LOCATION = "CR1B2" !CDS_LOCATION = "CR1B2" #SEC = "1" !CDS_SEC = "1";
"A":   PN = "2"  !CDS_PN = "2";
"C":   PN = "1"  !CDS_PN = "1";
BODY = "DIODE","I64": #LOCATION = "CR1B1" !CDS_LOCATION = "CR1B1" #SEC = "1" !CDS_SEC = "1";
"A":   PN = "2"  !CDS_PN = "2";
"C":   PN = "1"  !CDS_PN = "1";
BODY = "RES","I65": #LOCATION = "R7F33" !CDS_LOCATION = "R7F33" #SEC = "1" !CDS_SEC = "1";
"A":   PN = "1"  !CDS_PN = "1";
"B":   PN = "2"  !CDS_PN = "2";
BODY = "RES","I67": #LOCATION = "R1B22" !CDS_LOCATION = "R1B22" #SEC = "1" !CDS_SEC = "1";
"A":   PN = "1"  !CDS_PN = "1";
"B":   PN = "2"  !CDS_PN = "2";
BODY = "CAP_A","I68": #LOCATION = "C1B15" !CDS_LOCATION = "C1B15" #SEC = "1" !CDS_SEC = "1";
"A":   PN = "1"  !CDS_PN = "1";
"B":   PN = "2"  !CDS_PN = "2";
BODY = "RES","I70": #LOCATION = "R1B21" !CDS_LOCATION = "R1B21" #SEC = "1" !CDS_SEC = "1";
"A":   PN = "1"  !CDS_PN = "1";
"B":   PN = "2"  !CDS_PN = "2";
BODY = "TTL1G07_A","I88": #LOCATION = "U8G2" !CDS_LOCATION = "U8G2" #SEC = "1" !CDS_SEC = "1";
"A":   PN = "2"  !CDS_PN = "2";
"Y":   PN = "4"  !CDS_PN = "4";
BODY = "CAP_A","I90": #LOCATION = "C2U27" !CDS_LOCATION = "C2U27" #SEC = "1" !CDS_SEC = "1";
"A":   PN = "1"  !CDS_PN = "1";
"B":   PN = "2"  !CDS_PN = "2";
BODY = "TTL1G07_A","I92": #LOCATION = "U8G3" !CDS_LOCATION = "U8G3" #SEC = "1" !CDS_SEC = "1";
"A":   PN = "2"  !CDS_PN = "2";
"Y":   PN = "4"  !CDS_PN = "4";
BODY = "CAP_A","I93": #LOCATION = "C2U28" !CDS_LOCATION = "C2U28" #SEC = "1" !CDS_SEC = "1";
"A":   PN = "1"  !CDS_PN = "1";
"B":   PN = "2"  !CDS_PN = "2";
BODY = "RES","I99": #LOCATION = "R2U42" !CDS_LOCATION = "R2U42" #SEC = "1" !CDS_SEC = "1";
"A":   PN = "1"  !CDS_PN = "1";
"B":   PN = "2"  !CDS_PN = "2";
BODY = "RES","I102": #LOCATION = "R2U44" !CDS_LOCATION = "R2U44" #SEC = "1" !CDS_SEC = "1";
"A":   PN = "1"  !CDS_PN = "1";
"B":   PN = "2"  !CDS_PN = "2";
BODY = "CAP_A","I113": #LOCATION = "C1E22" !CDS_LOCATION = "C1E22" #SEC = "1" !CDS_SEC = "1";
"A":   PN = "1"  !CDS_PN = "1";
"B":   PN = "2"  !CDS_PN = "2";
BODY = "RES","I120": #LOCATION = "R1E11" !CDS_LOCATION = "R1E11" #SEC = "1" !CDS_SEC = "1";
"A":   PN = "1"  !CDS_PN = "1";
"B":   PN = "2"  !CDS_PN = "2";
BODY = "TTL1G08","I121": #LOCATION = "U1E2" !CDS_LOCATION = "U1E2" #SEC = "1" !CDS_SEC = "1";
"A<0>":   PN = "1"  !CDS_PN = "1";
"B<0>":   PN = "2"  !CDS_PN = "2";
"Y<0>":   PN = "4"  !CDS_PN = "4";
BODY = "LOTES-CON4-S1-GP","I139": #LOCATION = "J1F2" !CDS_LOCATION = "J1F2" #SEC = "1" !CDS_SEC = "1";
"1":   PN = "1"  !CDS_PN = "1";
"2":   PN = "2"  !CDS_PN = "2";
"3":   PN = "3"  !CDS_PN = "3";
"4":   PN = "4"  !CDS_PN = "4";
"NP1":   PN = "NP1"  !CDS_PN = "NP1";
BODY = "LOTES-CON4-S1-GP","I140": #LOCATION = "J10W1" !CDS_LOCATION = "J10W1" #SEC = "1" !CDS_SEC = "1";
"1":   PN = "1"  !CDS_PN = "1";
"2":   PN = "2"  !CDS_PN = "2";
"3":   PN = "3"  !CDS_PN = "3";
"4":   PN = "4"  !CDS_PN = "4";
"NP1":   PN = "NP1"  !CDS_PN = "NP1";
DRAWING = "@baseboard_fab2_lib.baseboard_fab2(sch_1):page162";
BODY = "RES","I8": #LOCATION = "R8F16" !CDS_LOCATION = "R8F16" #SEC = "1" !CDS_SEC = "1";
"A":   PN = "1"  !CDS_PN = "1";
"B":   PN = "2"  !CDS_PN = "2";
BODY = "RES","I9": #LOCATION = "R8F14" !CDS_LOCATION = "R8F14" #SEC = "1" !CDS_SEC = "1";
"A":   PN = "1"  !CDS_PN = "1";
"B":   PN = "2"  !CDS_PN = "2";
BODY = "RES","I13": #LOCATION = "R8F12" !CDS_LOCATION = "R8F12" #SEC = "1" !CDS_SEC = "1";
"A":   PN = "1"  !CDS_PN = "1";
"B":   PN = "2"  !CDS_PN = "2";
BODY = "RES","I22": #LOCATION = "R8F34" !CDS_LOCATION = "R8F34" #SEC = "1" !CDS_SEC = "1";
"A":   PN = "1"  !CDS_PN = "1";
"B":   PN = "2"  !CDS_PN = "2";
BODY = "RES","I24": #LOCATION = "R8F35" !CDS_LOCATION = "R8F35" #SEC = "1" !CDS_SEC = "1";
"A":   PN = "1"  !CDS_PN = "1";
"B":   PN = "2"  !CDS_PN = "2";
BODY = "CAP_A","I28": #LOCATION = "C8F5" !CDS_LOCATION = "C8F5" #SEC = "1" !CDS_SEC = "1";
"A":   PN = "1"  !CDS_PN = "1";
"B":   PN = "2"  !CDS_PN = "2";
BODY = "CAP_A","I30": #LOCATION = "C8F4" !CDS_LOCATION = "C8F4" #SEC = "1" !CDS_SEC = "1";
"A":   PN = "1"  !CDS_PN = "1";
"B":   PN = "2"  !CDS_PN = "2";
BODY = "W25Q128","I32": #LOCATION = "U8F2" !CDS_LOCATION = "U8F2" #SEC = "1" !CDS_SEC = "1";
"CLK":   PN = "16"  !CDS_PN = "16";
"CS_N":   PN = "7"  !CDS_PN = "7";
"DI_IO<0>":   PN = "15"  !CDS_PN = "15";
"DO_IO<1>":   PN = "8"  !CDS_PN = "8";
"GND":   PN = "10"  !CDS_PN = "10";
"HOLD_N_IO<3>":   PN = "1"  !CDS_PN = "1";
"NC<0>":   PN = "4"  !CDS_PN = "4";
"NC<1>":   PN = "5"  !CDS_PN = "5";
"NC<2>":   PN = "6"  !CDS_PN = "6";
"NC<3>":   PN = "11"  !CDS_PN = "11";
"NC<4>":   PN = "12"  !CDS_PN = "12";
"NC<5>":   PN = "13"  !CDS_PN = "13";
"NC<6>":   PN = "14"  !CDS_PN = "14";
"RESET_N":   PN = "3"  !CDS_PN = "3";
"VCC":   PN = "2"  !CDS_PN = "2";
"WP_N_IO<2>":   PN = "9"  !CDS_PN = "9";
BODY = "RES","I35": #LOCATION = "R8F13" !CDS_LOCATION = "R8F13" #SEC = "1" !CDS_SEC = "1";
"A":   PN = "1"  !CDS_PN = "1";
"B":   PN = "2"  !CDS_PN = "2";
DRAWING = "@baseboard_fab2_lib.baseboard_fab2(sch_1):page163";
BODY = "RES","I2": #LOCATION = "R6N8" !CDS_LOCATION = "R6N8" #SEC = "1" !CDS_SEC = "1";
"A":   PN = "1"  !CDS_PN = "1";
"B":   PN = "2"  !CDS_PN = "2";
BODY = "RES","I3": #LOCATION = "R6N9" !CDS_LOCATION = "R6N9" #SEC = "1" !CDS_SEC = "1";
"A":   PN = "1"  !CDS_PN = "1";
"B":   PN = "2"  !CDS_PN = "2";
BODY = "RES","I6": #LOCATION = "R9M18" !CDS_LOCATION = "R9M18" #SEC = "1" !CDS_SEC = "1";
"A":   PN = "1"  !CDS_PN = "1";
"B":   PN = "2"  !CDS_PN = "2";
BODY = "RES","I7": #LOCATION = "R9M19" !CDS_LOCATION = "R9M19" #SEC = "1" !CDS_SEC = "1";
"A":   PN = "1"  !CDS_PN = "1";
"B":   PN = "2"  !CDS_PN = "2";
BODY = "CAP_A","I10": #LOCATION = "C9M8" !CDS_LOCATION = "C9M8" #SEC = "1" !CDS_SEC = "1";
"A":   PN = "1"  !CDS_PN = "1";
"B":   PN = "2"  !CDS_PN = "2";
BODY = "CAP_A","I12": #LOCATION = "C9M7" !CDS_LOCATION = "C9M7" #SEC = "1" !CDS_SEC = "1";
"A":   PN = "1"  !CDS_PN = "1";
"B":   PN = "2"  !CDS_PN = "2";
BODY = "RES","I15": #LOCATION = "R9M17" !CDS_LOCATION = "R9M17" #SEC = "1" !CDS_SEC = "1";
"A":   PN = "1"  !CDS_PN = "1";
"B":   PN = "2"  !CDS_PN = "2";
BODY = "RES","I16": #LOCATION = "R9M16" !CDS_LOCATION = "R9M16" #SEC = "1" !CDS_SEC = "1";
"A":   PN = "1"  !CDS_PN = "1";
"B":   PN = "2"  !CDS_PN = "2";
BODY = "RES","I20": #LOCATION = "R9M14" !CDS_LOCATION = "R9M14" #SEC = "1" !CDS_SEC = "1";
"A":   PN = "1"  !CDS_PN = "1";
"B":   PN = "2"  !CDS_PN = "2";
BODY = "RES","I21": #LOCATION = "R9M13" !CDS_LOCATION = "R9M13" #SEC = "1" !CDS_SEC = "1";
"A":   PN = "1"  !CDS_PN = "1";
"B":   PN = "2"  !CDS_PN = "2";
BODY = "TCA9517DGKR-GP","I28": #LOCATION = "U1B2" !CDS_LOCATION = "U1B2" #SEC = "1" !CDS_SEC = "1";
"EN":   PN = "5"  !CDS_PN = "5";
"GND":   PN = "4"  !CDS_PN = "4";
"SCLA":   PN = "2"  !CDS_PN = "2";
"SCLB":   PN = "7"  !CDS_PN = "7";
"SDAA":   PN = "3"  !CDS_PN = "3";
"SDAB":   PN = "6"  !CDS_PN = "6";
"VCCA":   PN = "1"  !CDS_PN = "1";
"VCCB":   PN = "8"  !CDS_PN = "8";
DRAWING = "@baseboard_fab2_lib.baseboard_fab2(sch_1):page164";
BODY = "RES","I7": #LOCATION = "R1T11" !CDS_LOCATION = "R1T11" #SEC = "1" !CDS_SEC = "1";
"A":   PN = "1"  !CDS_PN = "1";
"B":   PN = "2"  !CDS_PN = "2";
BODY = "RES","I11": #LOCATION = "R1T5" !CDS_LOCATION = "R1T5" #SEC = "1" !CDS_SEC = "1";
"A":   PN = "1"  !CDS_PN = "1";
"B":   PN = "2"  !CDS_PN = "2";
BODY = "RES","I21": #LOCATION = "R1U17" !CDS_LOCATION = "R1U17" #SEC = "1" !CDS_SEC = "1";
"A":   PN = "1"  !CDS_PN = "1";
"B":   PN = "2"  !CDS_PN = "2";
BODY = "RES","I32": #LOCATION = "R2N18" !CDS_LOCATION = "R2N18" #SEC = "1" !CDS_SEC = "1";
"A":   PN = "1"  !CDS_PN = "1";
"B":   PN = "2"  !CDS_PN = "2";
BODY = "RES","I34": #LOCATION = "R1U23" !CDS_LOCATION = "R1U23" #SEC = "1" !CDS_SEC = "1";
"A":   PN = "1"  !CDS_PN = "1";
"B":   PN = "2"  !CDS_PN = "2";
BODY = "RES","I37": #LOCATION = "R1U16" !CDS_LOCATION = "R1U16" #SEC = "1" !CDS_SEC = "1";
"A":   PN = "1"  !CDS_PN = "1";
"B":   PN = "2"  !CDS_PN = "2";
BODY = "RES","I40": #LOCATION = "R1U18" !CDS_LOCATION = "R1U18" #SEC = "1" !CDS_SEC = "1";
"A":   PN = "1"  !CDS_PN = "1";
"B":   PN = "2"  !CDS_PN = "2";
BODY = "RES","I41": #LOCATION = "R1U21" !CDS_LOCATION = "R1U21" #SEC = "1" !CDS_SEC = "1";
"A":   PN = "1"  !CDS_PN = "1";
"B":   PN = "2"  !CDS_PN = "2";
BODY = "RES","I43": #LOCATION = "R1U22" !CDS_LOCATION = "R1U22" #SEC = "1" !CDS_SEC = "1";
"A":   PN = "1"  !CDS_PN = "1";
"B":   PN = "2"  !CDS_PN = "2";
BODY = "RES","I46": #LOCATION = "R2N17" !CDS_LOCATION = "R2N17" #SEC = "1" !CDS_SEC = "1";
"A":   PN = "1"  !CDS_PN = "1";
"B":   PN = "2"  !CDS_PN = "2";
BODY = "RES","I47": #LOCATION = "R1U24" !CDS_LOCATION = "R1U24" #SEC = "1" !CDS_SEC = "1";
"A":   PN = "1"  !CDS_PN = "1";
"B":   PN = "2"  !CDS_PN = "2";
BODY = "RES","I48": #LOCATION = "R1U15" !CDS_LOCATION = "R1U15" #SEC = "1" !CDS_SEC = "1";
"A":   PN = "1"  !CDS_PN = "1";
"B":   PN = "2"  !CDS_PN = "2";
BODY = "RES","I51": #LOCATION = "R1T6" !CDS_LOCATION = "R1T6" #SEC = "1" !CDS_SEC = "1";
"A":   PN = "1"  !CDS_PN = "1";
"B":   PN = "2"  !CDS_PN = "2";
BODY = "RES","I53": #LOCATION = "R1T12" !CDS_LOCATION = "R1T12" #SEC = "1" !CDS_SEC = "1";
"A":   PN = "1"  !CDS_PN = "1";
"B":   PN = "2"  !CDS_PN = "2";
BODY = "CAP_A","I66": #LOCATION = "C6W14" !CDS_LOCATION = "C6W14" #SEC = "1" !CDS_SEC = "1";
"A":   PN = "1"  !CDS_PN = "1";
"B":   PN = "2"  !CDS_PN = "2";
BODY = "RES","I76": #LOCATION = "R6W47" !CDS_LOCATION = "R6W47" #SEC = "1" !CDS_SEC = "1";
"A":   PN = "1"  !CDS_PN = "1";
"B":   PN = "2"  !CDS_PN = "2";
BODY = "RES","I78": #LOCATION = "R6W44" !CDS_LOCATION = "R6W44" #SEC = "1" !CDS_SEC = "1";
"A":   PN = "1"  !CDS_PN = "1";
"B":   PN = "2"  !CDS_PN = "2";
BODY = "RES","I87": #LOCATION = "R6W41" !CDS_LOCATION = "R6W41" #SEC = "1" !CDS_SEC = "1";
"A":   PN = "1"  !CDS_PN = "1";
"B":   PN = "2"  !CDS_PN = "2";
BODY = "RES","I93": #LOCATION = "R6W46" !CDS_LOCATION = "R6W46" #SEC = "1" !CDS_SEC = "1";
"A":   PN = "1"  !CDS_PN = "1";
"B":   PN = "2"  !CDS_PN = "2";
BODY = "RES","I94": #LOCATION = "R6W45" !CDS_LOCATION = "R6W45" #SEC = "1" !CDS_SEC = "1";
"A":   PN = "1"  !CDS_PN = "1";
"B":   PN = "2"  !CDS_PN = "2";
BODY = "RES","I95": #LOCATION = "R6W42" !CDS_LOCATION = "R6W42" #SEC = "1" !CDS_SEC = "1";
"A":   PN = "1"  !CDS_PN = "1";
"B":   PN = "2"  !CDS_PN = "2";
BODY = "RES","I96": #LOCATION = "R6W43" !CDS_LOCATION = "R6W43" #SEC = "1" !CDS_SEC = "1";
"A":   PN = "1"  !CDS_PN = "1";
"B":   PN = "2"  !CDS_PN = "2";
BODY = "PCA9554PWR-GP","I97": #LOCATION = "U6W11" !CDS_LOCATION = "U6W11" #SEC = "1" !CDS_SEC = "1";
"A0":   PN = "1"  !CDS_PN = "1";
"A1":   PN = "2"  !CDS_PN = "2";
"A2":   PN = "3"  !CDS_PN = "3";
"GND":   PN = "8"  !CDS_PN = "8";
"INT#":   PN = "13"  !CDS_PN = "13";
"P0":   PN = "4"  !CDS_PN = "4";
"P1":   PN = "5"  !CDS_PN = "5";
"P2":   PN = "6"  !CDS_PN = "6";
"P3":   PN = "7"  !CDS_PN = "7";
"P4":   PN = "9"  !CDS_PN = "9";
"P5":   PN = "10"  !CDS_PN = "10";
"P6":   PN = "11"  !CDS_PN = "11";
"P7":   PN = "12"  !CDS_PN = "12";
"SCL":   PN = "14"  !CDS_PN = "14";
"SDA":   PN = "15"  !CDS_PN = "15";
"VCC":   PN = "16"  !CDS_PN = "16";
BODY = "RES","I100": #LOCATION = "R1T4" !CDS_LOCATION = "R1T4" #SEC = "1" !CDS_SEC = "1";
"A":   PN = "1"  !CDS_PN = "1";
"B":   PN = "2"  !CDS_PN = "2";
BODY = "RES","I101": #LOCATION = "R1T10" !CDS_LOCATION = "R1T10" #SEC = "1" !CDS_SEC = "1";
"A":   PN = "1"  !CDS_PN = "1";
"B":   PN = "2"  !CDS_PN = "2";
DRAWING = "@baseboard_fab2_lib.baseboard_fab2(sch_1):page166";
BODY = "RES","I28": #LOCATION = "R7C17" !CDS_LOCATION = "R7C17" #SEC = "1" !CDS_SEC = "1";
"A":   PN = "1"  !CDS_PN = "1";
"B":   PN = "2"  !CDS_PN = "2";
BODY = "RES","I32": #LOCATION = "R7D15" !CDS_LOCATION = "R7D15" #SEC = "1" !CDS_SEC = "1";
"A":   PN = "1"  !CDS_PN = "1";
"B":   PN = "2"  !CDS_PN = "2";
BODY = "PI5A3157BC6E-GP","I34": #LOCATION = "U7W1" !CDS_LOCATION = "U7W1" #SEC = "1" !CDS_SEC = "1";
"A":   PN = "4"  !CDS_PN = "4";
"B0":   PN = "3"  !CDS_PN = "3";
"B1":   PN = "1"  !CDS_PN = "1";
"GND":   PN = "2"  !CDS_PN = "2";
"S":   PN = "6"  !CDS_PN = "6";
"VCC":   PN = "5"  !CDS_PN = "5";
BODY = "CAP_A","I36": #LOCATION = "C7W1" !CDS_LOCATION = "C7W1" #SEC = "1" !CDS_SEC = "1";
"A":   PN = "1"  !CDS_PN = "1";
"B":   PN = "2"  !CDS_PN = "2";
BODY = "RES","I42": #LOCATION = "R7W2" !CDS_LOCATION = "R7W2" #SEC = "1" !CDS_SEC = "1";
"A":   PN = "1"  !CDS_PN = "1";
"B":   PN = "2"  !CDS_PN = "2";
BODY = "RES","I46": #LOCATION = "R7W3" !CDS_LOCATION = "R7W3" #SEC = "1" !CDS_SEC = "1";
"A":   PN = "1"  !CDS_PN = "1";
"B":   PN = "2"  !CDS_PN = "2";
DRAWING = "@baseboard_fab2_lib.baseboard_fab2(sch_1):page167";
BODY = "TMP421","I1": #LOCATION = "U9B4" !CDS_LOCATION = "U9B4" #SEC = "1" !CDS_SEC = "1";
"A<0>":   PN = "4"  !CDS_PN = "4";
"A<1>":   PN = "3"  !CDS_PN = "3";
"DXN":   PN = "2"  !CDS_PN = "2";
"DXP":   PN = "1"  !CDS_PN = "1";
"GND":   PN = "5"  !CDS_PN = "5";
"SCL":   PN = "7"  !CDS_PN = "7";
"SDA":   PN = "6"  !CDS_PN = "6";
"VP":   PN = "8"  !CDS_PN = "8";
BODY = "RES","I5": #LOCATION = "R9B5" !CDS_LOCATION = "R9B5" #SEC = "1" !CDS_SEC = "1";
"A":   PN = "1"  !CDS_PN = "1";
"B":   PN = "2"  !CDS_PN = "2";
BODY = "RES","I6": #LOCATION = "R9B4" !CDS_LOCATION = "R9B4" #SEC = "1" !CDS_SEC = "1";
"A":   PN = "1"  !CDS_PN = "1";
"B":   PN = "2"  !CDS_PN = "2";
BODY = "CAP","I7": #LOCATION = "C1M4" !CDS_LOCATION = "C1M4" #SEC = "1" !CDS_SEC = "1";
"A":   PN = "1"  !CDS_PN = "1";
"B":   PN = "2"  !CDS_PN = "2";
BODY = "RES","I8": #LOCATION = "R1M9" !CDS_LOCATION = "R1M9" #SEC = "1" !CDS_SEC = "1";
"A":   PN = "1"  !CDS_PN = "1";
"B":   PN = "2"  !CDS_PN = "2";
BODY = "RES","I10": #LOCATION = "R9B8" !CDS_LOCATION = "R9B8" #SEC = "1" !CDS_SEC = "1";
"A":   PN = "1"  !CDS_PN = "1";
"B":   PN = "2"  !CDS_PN = "2";
BODY = "CAP","I24": #LOCATION = "C1E19" !CDS_LOCATION = "C1E19" #SEC = "1" !CDS_SEC = "1";
"A":   PN = "1"  !CDS_PN = "1";
"B":   PN = "2"  !CDS_PN = "2";
BODY = "RES","I25": #LOCATION = "R9R5" !CDS_LOCATION = "R9R5" #SEC = "1" !CDS_SEC = "1";
"A":   PN = "1"  !CDS_PN = "1";
"B":   PN = "2"  !CDS_PN = "2";
BODY = "RES","I26": #LOCATION = "R9R6" !CDS_LOCATION = "R9R6" #SEC = "1" !CDS_SEC = "1";
"A":   PN = "1"  !CDS_PN = "1";
"B":   PN = "2"  !CDS_PN = "2";
BODY = "TMP421","I30": #LOCATION = "U1E1" !CDS_LOCATION = "U1E1" #SEC = "1" !CDS_SEC = "1";
"A<0>":   PN = "4"  !CDS_PN = "4";
"A<1>":   PN = "3"  !CDS_PN = "3";
"DXN":   PN = "2"  !CDS_PN = "2";
"DXP":   PN = "1"  !CDS_PN = "1";
"GND":   PN = "5"  !CDS_PN = "5";
"SCL":   PN = "7"  !CDS_PN = "7";
"SDA":   PN = "6"  !CDS_PN = "6";
"VP":   PN = "8"  !CDS_PN = "8";
BODY = "RES","I34": #LOCATION = "R1E9" !CDS_LOCATION = "R1E9" #SEC = "1" !CDS_SEC = "1";
"A":   PN = "1"  !CDS_PN = "1";
"B":   PN = "2"  !CDS_PN = "2";
BODY = "RES","I35": #LOCATION = "R9B6" !CDS_LOCATION = "R9B6" #SEC = "1" !CDS_SEC = "1";
"A":   PN = "1"  !CDS_PN = "1";
"B":   PN = "2"  !CDS_PN = "2";
BODY = "RES","I38": #LOCATION = "R1E10" !CDS_LOCATION = "R1E10" #SEC = "1" !CDS_SEC = "1";
"A":   PN = "1"  !CDS_PN = "1";
"B":   PN = "2"  !CDS_PN = "2";
BODY = "CAP_A","I39": #LOCATION = "C9B7" !CDS_LOCATION = "C9B7" #SEC = "1" !CDS_SEC = "1";
"A":   PN = "1"  !CDS_PN = "1";
"B":   PN = "2"  !CDS_PN = "2";
BODY = "CAP_A","I41": #LOCATION = "C9R14" !CDS_LOCATION = "C9R14" #SEC = "1" !CDS_SEC = "1";
"A":   PN = "1"  !CDS_PN = "1";
"B":   PN = "2"  !CDS_PN = "2";
BODY = "CAP_A","I42": #LOCATION = "C9R13" !CDS_LOCATION = "C9R13" #SEC = "1" !CDS_SEC = "1";
"A":   PN = "1"  !CDS_PN = "1";
"B":   PN = "2"  !CDS_PN = "2";
BODY = "AT24C64","I49": #LOCATION = "U8D4" !CDS_LOCATION = "U8D4" #SEC = "1" !CDS_SEC = "1";
"A0":   PN = "1"  !CDS_PN = "1";
"A1":   PN = "2"  !CDS_PN = "2";
"A2":   PN = "3"  !CDS_PN = "3";
"SCL":   PN = "6"  !CDS_PN = "6";
"SDA":   PN = "5"  !CDS_PN = "5";
"WP":   PN = "7"  !CDS_PN = "7";
BODY = "RES","I50": #LOCATION = "R8D27" !CDS_LOCATION = "R8D27" #SEC = "1" !CDS_SEC = "1";
"A":   PN = "1"  !CDS_PN = "1";
"B":   PN = "2"  !CDS_PN = "2";
BODY = "RES","I58": #LOCATION = "R9G15" !CDS_LOCATION = "R9G15" &SEC = "1" #&CDS_SEC = "1";
"A":   PN = "1"  !CDS_PN = "1";
"B":   PN = "2"  !CDS_PN = "2";
BODY = "RES","I70": #LOCATION = "R8D28" !CDS_LOCATION = "R8D28" #SEC = "1" !CDS_SEC = "1";
"A":   PN = "1"  !CDS_PN = "1";
"B":   PN = "2"  !CDS_PN = "2";
BODY = "RES","I74": #LOCATION = "R1M8" !CDS_LOCATION = "R1M8" #SEC = "1" !CDS_SEC = "1";
"A":   PN = "1"  !CDS_PN = "1";
"B":   PN = "2"  !CDS_PN = "2";
BODY = "RES","I75": #LOCATION = "R9R7" !CDS_LOCATION = "R9R7" #SEC = "1" !CDS_SEC = "1";
"A":   PN = "1"  !CDS_PN = "1";
"B":   PN = "2"  !CDS_PN = "2";
BODY = "RES","I76": #LOCATION = "R9R8" !CDS_LOCATION = "R9R8" #SEC = "1" !CDS_SEC = "1";
"A":   PN = "1"  !CDS_PN = "1";
"B":   PN = "2"  !CDS_PN = "2";
BODY = "RES","I77": #LOCATION = "R9G14" !CDS_LOCATION = "R9G14" &SEC = "1" #&CDS_SEC = "1";
"A":   PN = "1"  !CDS_PN = "1";
"B":   PN = "2"  !CDS_PN = "2";
BODY = "RES","I80": #LOCATION = "R2U38" !CDS_LOCATION = "R2U38" #SEC = "1" !CDS_SEC = "1";
"A":   PN = "1"  !CDS_PN = "1";
"B":   PN = "2"  !CDS_PN = "2";
BODY = "RES","I83": #LOCATION = "R2U39" !CDS_LOCATION = "R2U39" #SEC = "1" !CDS_SEC = "1";
"A":   PN = "1"  !CDS_PN = "1";
"B":   PN = "2"  !CDS_PN = "2";
BODY = "RES","I84": #LOCATION = "R8D24" !CDS_LOCATION = "R8D24" #SEC = "1" !CDS_SEC = "1";
"A":   PN = "1"  !CDS_PN = "1";
"B":   PN = "2"  !CDS_PN = "2";
BODY = "RES","I85": #LOCATION = "R8D23" !CDS_LOCATION = "R8D23" #SEC = "1" !CDS_SEC = "1";
"A":   PN = "1"  !CDS_PN = "1";
"B":   PN = "2"  !CDS_PN = "2";
BODY = "2SB2907A-B0-00001-GP","I93": #LOCATION = "Q9B1" !CDS_LOCATION = "Q9B1" #SEC = "1" !CDS_SEC = "1";
"B":   PN = "B"  !CDS_PN = "B";
"C":   PN = "C"  !CDS_PN = "C";
"E":   PN = "E"  !CDS_PN = "E";
BODY = "2SB2907A-B0-00001-GP","I94": #LOCATION = "Q1E1" !CDS_LOCATION = "Q1E1" #SEC = "1" !CDS_SEC = "1";
"B":   PN = "B"  !CDS_PN = "B";
"C":   PN = "C"  !CDS_PN = "C";
"E":   PN = "E"  !CDS_PN = "E";
DRAWING = "@baseboard_fab2_lib.baseboard_fab2(sch_1):page168";
BODY = "DIODE","I2": #LOCATION = "CR1L1" !CDS_LOCATION = "CR1L1" #SEC = "1" !CDS_SEC = "1";
"A":   PN = "2"  !CDS_PN = "2";
"C":   PN = "1"  !CDS_PN = "1";
BODY = "DIODE","I3": #LOCATION = "CR1L2" !CDS_LOCATION = "CR1L2" #SEC = "1" !CDS_SEC = "1";
"A":   PN = "2"  !CDS_PN = "2";
"C":   PN = "1"  !CDS_PN = "1";
BODY = "DIODE","I4": #LOCATION = "CR1L3" !CDS_LOCATION = "CR1L3" #SEC = "1" !CDS_SEC = "1";
"A":   PN = "2"  !CDS_PN = "2";
"C":   PN = "1"  !CDS_PN = "1";
BODY = "DIODE","I5": #LOCATION = "CR1L4" !CDS_LOCATION = "CR1L4" #SEC = "1" !CDS_SEC = "1";
"A":   PN = "2"  !CDS_PN = "2";
"C":   PN = "1"  !CDS_PN = "1";
BODY = "RES","I6": #LOCATION = "R1L6" !CDS_LOCATION = "R1L6" #SEC = "1" !CDS_SEC = "1";
"A":   PN = "1"  !CDS_PN = "1";
"B":   PN = "2"  !CDS_PN = "2";
BODY = "NPN","I8": #LOCATION = "Q1L3" !CDS_LOCATION = "Q1L3" #SEC = "1" !CDS_SEC = "1";
"B":   PN = "1"  !CDS_PN = "1";
"C":   PN = "3"  !CDS_PN = "3";
"E":   PN = "2"  !CDS_PN = "2";
BODY = "RES","I11": #LOCATION = "R1L36" !CDS_LOCATION = "R1L36" #SEC = "1" !CDS_SEC = "1";
"A":   PN = "1"  !CDS_PN = "1";
"B":   PN = "2"  !CDS_PN = "2";
BODY = "FET_N_DUAL","I18": #LOCATION = "Q1L4" !CDS_LOCATION = "Q1L4" #SEC = "2" !CDS_SEC = "2";
"DRAIN<0>":   PN = "3"  !CDS_PN = "3";
"GATE<0>":   PN = "5"  !CDS_PN = "5";
"SOURCE<0>":   PN = "4"  !CDS_PN = "4";
BODY = "FET_N_DUAL","I19": #LOCATION = "Q1L4" !CDS_LOCATION = "Q1L4" #SEC = "1" !CDS_SEC = "1";
"DRAIN<0>":   PN = "6"  !CDS_PN = "6";
"GATE<0>":   PN = "2"  !CDS_PN = "2";
"SOURCE<0>":   PN = "1"  !CDS_PN = "1";
BODY = "RES","I22": #LOCATION = "R1L38" !CDS_LOCATION = "R1L38" #SEC = "1" !CDS_SEC = "1";
"A":   PN = "1"  !CDS_PN = "1";
"B":   PN = "2"  !CDS_PN = "2";
BODY = "FET_N","I43": #LOCATION = "Q6W4" !CDS_LOCATION = "Q6W4" #SEC = "1" !CDS_SEC = "1";
"DRN":   PN = "3"  !CDS_PN = "3";
"GATE":   PN = "1"  !CDS_PN = "1";
"SRC":   PN = "2"  !CDS_PN = "2";
BODY = "RES","I46": #LOCATION = "R6W16" !CDS_LOCATION = "R6W16" #SEC = "1" !CDS_SEC = "1";
"A":   PN = "1"  !CDS_PN = "1";
"B":   PN = "2"  !CDS_PN = "2";
BODY = "NPN","I47": #LOCATION = "Q6W2" !CDS_LOCATION = "Q6W2" #SEC = "1" !CDS_SEC = "1";
"B":   PN = "1"  !CDS_PN = "1";
"C":   PN = "3"  !CDS_PN = "3";
"E":   PN = "2"  !CDS_PN = "2";
BODY = "RES","I48": #LOCATION = "R6W49" !CDS_LOCATION = "R6W49" #SEC = "1" !CDS_SEC = "1";
"A":   PN = "1"  !CDS_PN = "1";
"B":   PN = "2"  !CDS_PN = "2";
DRAWING = "@baseboard_fab2_lib.baseboard_fab2(sch_1):page169";
BODY = "CAP","I56": #LOCATION = "C1U21" !CDS_LOCATION = "C1U21" #SEC = "1" !CDS_SEC = "1";
"A":   PN = "1"  !CDS_PN = "1";
"B":   PN = "2"  !CDS_PN = "2";
BODY = "FERRITE","I57": #LOCATION = "FB1U3" !CDS_LOCATION = "FB1U3" #SEC = "1" !CDS_SEC = "1";
"A":   PN = "1"  !CDS_PN = "1";
"B":   PN = "2"  !CDS_PN = "2";
BODY = "CAP","I68": #LOCATION = "C9G21" !CDS_LOCATION = "C9G21" #SEC = "1" !CDS_SEC = "1";
"A":   PN = "1"  !CDS_PN = "1";
"B":   PN = "2"  !CDS_PN = "2";
BODY = "CAP","I80": #LOCATION = "C9G17" !CDS_LOCATION = "C9G17" #SEC = "1" !CDS_SEC = "1";
"A":   PN = "1"  !CDS_PN = "1";
"B":   PN = "2"  !CDS_PN = "2";
BODY = "RES","I82": #LOCATION = "R1U32" !CDS_LOCATION = "R1U32" #SEC = "1" !CDS_SEC = "1";
"A":   PN = "1"  !CDS_PN = "1";
"B":   PN = "2"  !CDS_PN = "2";
BODY = "CAP","I86": #LOCATION = "C9G20" !CDS_LOCATION = "C9G20" #SEC = "1" !CDS_SEC = "1";
"A":   PN = "1"  !CDS_PN = "1";
"B":   PN = "2"  !CDS_PN = "2";
BODY = "RES","I88": #LOCATION = "R1U39" !CDS_LOCATION = "R1U39" #SEC = "1" !CDS_SEC = "1";
"A":   PN = "1"  !CDS_PN = "1";
"B":   PN = "2"  !CDS_PN = "2";
BODY = "RES","I106": #LOCATION = "R9G26" !CDS_LOCATION = "R9G26" #SEC = "1" !CDS_SEC = "1";
"A":   PN = "1"  !CDS_PN = "1";
"B":   PN = "2"  !CDS_PN = "2";
BODY = "CAP","I108": #LOCATION = "C9G22" !CDS_LOCATION = "C9G22" #SEC = "1" !CDS_SEC = "1";
"A":   PN = "1"  !CDS_PN = "1";
"B":   PN = "2"  !CDS_PN = "2";
BODY = "RES","I115": #LOCATION = "R1U47" !CDS_LOCATION = "R1U47" #SEC = "1" !CDS_SEC = "1";
"A":   PN = "1"  !CDS_PN = "1";
"B":   PN = "2"  !CDS_PN = "2";
BODY = "RES","I126": #LOCATION = "R1U50" !CDS_LOCATION = "R1U50" #SEC = "1" !CDS_SEC = "1";
"A":   PN = "1"  !CDS_PN = "1";
"B":   PN = "2"  !CDS_PN = "2";
BODY = "CAP","I139": #LOCATION = "C9G15" !CDS_LOCATION = "C9G15" #SEC = "1" !CDS_SEC = "1";
"A":   PN = "1"  !CDS_PN = "1";
"B":   PN = "2"  !CDS_PN = "2";
BODY = "RES","I141": #LOCATION = "R1U29" !CDS_LOCATION = "R1U29" #SEC = "1" !CDS_SEC = "1";
"A":   PN = "1"  !CDS_PN = "1";
"B":   PN = "2"  !CDS_PN = "2";
BODY = "CAP","I146": #LOCATION = "C9G14" !CDS_LOCATION = "C9G14" #SEC = "1" !CDS_SEC = "1";
"A":   PN = "1"  !CDS_PN = "1";
"B":   PN = "2"  !CDS_PN = "2";
BODY = "RES","I148": #LOCATION = "R1U26" !CDS_LOCATION = "R1U26" #SEC = "1" !CDS_SEC = "1";
"A":   PN = "1"  !CDS_PN = "1";
"B":   PN = "2"  !CDS_PN = "2";
BODY = "CAP","I153": #LOCATION = "C9G18" !CDS_LOCATION = "C9G18" #SEC = "1" !CDS_SEC = "1";
"A":   PN = "1"  !CDS_PN = "1";
"B":   PN = "2"  !CDS_PN = "2";
BODY = "FERRITE","I155": #LOCATION = "FB1U4" !CDS_LOCATION = "FB1U4" #SEC = "1" !CDS_SEC = "1";
"A":   PN = "1"  !CDS_PN = "1";
"B":   PN = "2"  !CDS_PN = "2";
BODY = "FET_N_DUAL","I157": #LOCATION = "Q9G1" !CDS_LOCATION = "Q9G1" #SEC = "2" !CDS_SEC = "2";
"DRAIN<0>":   PN = "3"  !CDS_PN = "3";
"GATE<0>":   PN = "5"  !CDS_PN = "5";
"SOURCE<0>":   PN = "4"  !CDS_PN = "4";
BODY = "FET_N_DUAL","I162": #LOCATION = "Q9G1" !CDS_LOCATION = "Q9G1" #SEC = "1" !CDS_SEC = "1";
"DRAIN<0>":   PN = "6"  !CDS_PN = "6";
"GATE<0>":   PN = "2"  !CDS_PN = "2";
"SOURCE<0>":   PN = "1"  !CDS_PN = "1";
BODY = "RES","I163": #LOCATION = "R1U49" !CDS_LOCATION = "R1U49" #SEC = "1" !CDS_SEC = "1";
"A":   PN = "1"  !CDS_PN = "1";
"B":   PN = "2"  !CDS_PN = "2";
BODY = "RES","I164": #LOCATION = "R9G35" !CDS_LOCATION = "R9G35" #SEC = "1" !CDS_SEC = "1";
"A":   PN = "1"  !CDS_PN = "1";
"B":   PN = "2"  !CDS_PN = "2";
BODY = "1K82R2F-1-GP","I169": #LOCATION = "R1U28" !CDS_LOCATION = "R1U28" #SEC = "1" !CDS_SEC = "1";
"1":   PN = "1"  !CDS_PN = "1";
"2":   PN = "2"  !CDS_PN = "2";
BODY = "1K82R2F-1-GP","I170": #LOCATION = "R1U44" !CDS_LOCATION = "R1U44" #SEC = "1" !CDS_SEC = "1";
"1":   PN = "1"  !CDS_PN = "1";
"2":   PN = "2"  !CDS_PN = "2";
BODY = "649R2F-GP","I171": #LOCATION = "R1U33" !CDS_LOCATION = "R1U33" #SEC = "1" !CDS_SEC = "1";
"1":   PN = "1"  !CDS_PN = "1";
"2":   PN = "2"  !CDS_PN = "2";
BODY = "RES","I172": #LOCATION = "R1U38" !CDS_LOCATION = "R1U38" #SEC = "1" !CDS_SEC = "1";
"A":   PN = "1"  !CDS_PN = "1";
"B":   PN = "2"  !CDS_PN = "2";
BODY = "RES","I173": #LOCATION = "R1U27" !CDS_LOCATION = "R1U27" #SEC = "1" !CDS_SEC = "1";
"A":   PN = "1"  !CDS_PN = "1";
"B":   PN = "2"  !CDS_PN = "2";
DRAWING = "@baseboard_fab2_lib.baseboard_fab2(sch_1):page170";
BODY = "RES","I2": #LOCATION = "R2P3" !CDS_LOCATION = "R2P3" #SEC = "1" !CDS_SEC = "1";
"A":   PN = "1"  !CDS_PN = "1";
"B":   PN = "2"  !CDS_PN = "2";
BODY = "TTL1G07_A","I4": #LOCATION = "U8D3" !CDS_LOCATION = "U8D3" &SEC = "1" #&CDS_SEC = "1";
"A":   PN = "2"  !CDS_PN = "2";
"Y":   PN = "4"  !CDS_PN = "4";
BODY = "CAP_A","I8": #LOCATION = "C2P1" !CDS_LOCATION = "C2P1" #SEC = "1" !CDS_SEC = "1";
"A":   PN = "1"  !CDS_PN = "1";
"B":   PN = "2"  !CDS_PN = "2";
BODY = "TTL08","I10": #LOCATION = "U8E1" !CDS_LOCATION = "U8E1" #SEC = "4" !CDS_SEC = "4";
"A<0>":   PN = "1"  !CDS_PN = "1";
"B<0>":   PN = "2"  !CDS_PN = "2";
"Y<0>":   PN = "3"  !CDS_PN = "3";
BODY = "TTL08","I11": #LOCATION = "U8E1" !CDS_LOCATION = "U8E1" #SEC = "3" !CDS_SEC = "3";
"A<0>":   PN = "4"  !CDS_PN = "4";
"B<0>":   PN = "5"  !CDS_PN = "5";
"Y<0>":   PN = "6"  !CDS_PN = "6";
BODY = "TTL08","I12": #LOCATION = "U8E1" !CDS_LOCATION = "U8E1" #SEC = "1" !CDS_SEC = "1";
"A<0>":   PN = "12"  !CDS_PN = "12";
"B<0>":   PN = "13"  !CDS_PN = "13";
"Y<0>":   PN = "11"  !CDS_PN = "11";
BODY = "TTL1G126_A","I20": #LOCATION = "U1R2" !CDS_LOCATION = "U1R2" #SEC = "1" !CDS_SEC = "1";
"A":   PN = "2"  !CDS_PN = "2";
"OE":   PN = "1"  !CDS_PN = "1";
"Y":   PN = "4"  !CDS_PN = "4";
BODY = "CAP_A","I30": #LOCATION = "C1R27" !CDS_LOCATION = "C1R27" #SEC = "1" !CDS_SEC = "1";
"A":   PN = "1"  !CDS_PN = "1";
"B":   PN = "2"  !CDS_PN = "2";
BODY = "CAP_A","I33": #LOCATION = "C8D2" !CDS_LOCATION = "C8D2" #SEC = "1" !CDS_SEC = "1";
"A":   PN = "1"  !CDS_PN = "1";
"B":   PN = "2"  !CDS_PN = "2";
BODY = "TTL1G126_A","I38": #LOCATION = "U8D5" !CDS_LOCATION = "U8D5" #SEC = "1" !CDS_SEC = "1";
"A":   PN = "2"  !CDS_PN = "2";
"OE":   PN = "1"  !CDS_PN = "1";
"Y":   PN = "4"  !CDS_PN = "4";
BODY = "CAP_A","I40": #LOCATION = "C8E2" !CDS_LOCATION = "C8E2" #SEC = "1" !CDS_SEC = "1";
"A":   PN = "1"  !CDS_PN = "1";
"B":   PN = "2"  !CDS_PN = "2";
BODY = "CAP","I42": #LOCATION = "C8D3" !CDS_LOCATION = "C8D3" #SEC = "1" !CDS_SEC = "1";
"A":   PN = "1"  !CDS_PN = "1";
"B":   PN = "2"  !CDS_PN = "2";
BODY = "TTL1G07_A","I46": #LOCATION = "U1R1" !CDS_LOCATION = "U1R1" #SEC = "1" !CDS_SEC = "1";
"A":   PN = "2"  !CDS_PN = "2";
"Y":   PN = "4"  !CDS_PN = "4";
BODY = "CAP_A","I49": #LOCATION = "C1R28" !CDS_LOCATION = "C1R28" #SEC = "1" !CDS_SEC = "1";
"A":   PN = "1"  !CDS_PN = "1";
"B":   PN = "2"  !CDS_PN = "2";
BODY = "RES","I51": #LOCATION = "R1R8" !CDS_LOCATION = "R1R8" #SEC = "1" !CDS_SEC = "1";
"A":   PN = "1"  !CDS_PN = "1";
"B":   PN = "2"  !CDS_PN = "2";
BODY = "RES","I54": #LOCATION = "R2T3" !CDS_LOCATION = "R2T3" #SEC = "1" !CDS_SEC = "1";
"A":   PN = "1"  !CDS_PN = "1";
"B":   PN = "2"  !CDS_PN = "2";
BODY = "RES","I56": #LOCATION = "R2P5" !CDS_LOCATION = "R2P5" #SEC = "1" !CDS_SEC = "1";
"A":   PN = "1"  !CDS_PN = "1";
"B":   PN = "2"  !CDS_PN = "2";
BODY = "FET_N","I58": #LOCATION = "Q2P1" !CDS_LOCATION = "Q2P1" #SEC = "1" !CDS_SEC = "1";
"DRN":   PN = "3"  !CDS_PN = "3";
"GATE":   PN = "1"  !CDS_PN = "1";
"SRC":   PN = "2"  !CDS_PN = "2";
BODY = "RES","I61": #LOCATION = "R2P13" !CDS_LOCATION = "R2P13" #SEC = "1" !CDS_SEC = "1";
"A":   PN = "1"  !CDS_PN = "1";
"B":   PN = "2"  !CDS_PN = "2";
BODY = "RES","I63": #LOCATION = "R2P11" !CDS_LOCATION = "R2P11" #SEC = "1" !CDS_SEC = "1";
"A":   PN = "1"  !CDS_PN = "1";
"B":   PN = "2"  !CDS_PN = "2";
BODY = "RES","I65": #LOCATION = "R9F3" !CDS_LOCATION = "R9F3" #SEC = "1" !CDS_SEC = "1";
"A":   PN = "1"  !CDS_PN = "1";
"B":   PN = "2"  !CDS_PN = "2";
BODY = "FET_N","I67": #LOCATION = "Q8F2" !CDS_LOCATION = "Q8F2" #SEC = "1" !CDS_SEC = "1";
"DRN":   PN = "3"  !CDS_PN = "3";
"GATE":   PN = "1"  !CDS_PN = "1";
"SRC":   PN = "2"  !CDS_PN = "2";
BODY = "RES","I71": #LOCATION = "R8D26" !CDS_LOCATION = "R8D26" #SEC = "1" !CDS_SEC = "1";
"A":   PN = "1"  !CDS_PN = "1";
"B":   PN = "2"  !CDS_PN = "2";
BODY = "RES","I73": #LOCATION = "R1R5" !CDS_LOCATION = "R1R5" #SEC = "1" !CDS_SEC = "1";
"A":   PN = "1"  !CDS_PN = "1";
"B":   PN = "2"  !CDS_PN = "2";
BODY = "RES","I74": #LOCATION = "R2P4" !CDS_LOCATION = "R2P4" #SEC = "1" !CDS_SEC = "1";
"A":   PN = "1"  !CDS_PN = "1";
"B":   PN = "2"  !CDS_PN = "2";
BODY = "RES","I75": #LOCATION = "R2P8" !CDS_LOCATION = "R2P8" #SEC = "1" !CDS_SEC = "1";
"A":   PN = "1"  !CDS_PN = "1";
"B":   PN = "2"  !CDS_PN = "2";
DRAWING = "@baseboard_fab2_lib.baseboard_fab2(sch_1):page172";
BODY = "CAP_A","I5": #LOCATION = "C2L49" !CDS_LOCATION = "C2L49" #SEC = "1" !CDS_SEC = "1";
"A":   PN = "1"  !CDS_PN = "1";
"B":   PN = "2"  !CDS_PN = "2";
BODY = "CAP_A","I6": #LOCATION = "C2L52" !CDS_LOCATION = "C2L52" #SEC = "1" !CDS_SEC = "1";
"A":   PN = "1"  !CDS_PN = "1";
"B":   PN = "2"  !CDS_PN = "2";
BODY = "CAP_A","I7": #LOCATION = "C2L50" !CDS_LOCATION = "C2L50" #SEC = "1" !CDS_SEC = "1";
"A":   PN = "1"  !CDS_PN = "1";
"B":   PN = "2"  !CDS_PN = "2";
BODY = "CAP_A","I8": #LOCATION = "C2L51" !CDS_LOCATION = "C2L51" #SEC = "1" !CDS_SEC = "1";
"A":   PN = "1"  !CDS_PN = "1";
"B":   PN = "2"  !CDS_PN = "2";
BODY = "CAP","I36": #LOCATION = "C9B2" !CDS_LOCATION = "C9B2" #SEC = "1" !CDS_SEC = "1";
"A":   PN = "1"  !CDS_PN = "1";
"B":   PN = "2"  !CDS_PN = "2";
BODY = "CAP","I39": #LOCATION = "C9B1" !CDS_LOCATION = "C9B1" #SEC = "1" !CDS_SEC = "1";
"A":   PN = "1"  !CDS_PN = "1";
"B":   PN = "2"  !CDS_PN = "2";
BODY = "FUSE","I66": #LOCATION = "F9B1" !CDS_LOCATION = "F9B1" #SEC = "1" !CDS_SEC = "1";
"A<0>":   PN = "1"  !CDS_PN = "1";
"B<0>":   PN = "2"  !CDS_PN = "2";
BODY = "SKT-SATA7P-6P-165-GP-U1","I67": #LOCATION = "J2W1" !CDS_LOCATION = "J2W1" #SEC = "1" !CDS_SEC = "1";
"H1":   PN = "H1"  !CDS_PN = "H1";
"H2":   PN = "H2"  !CDS_PN = "H2";
"NP1":   PN = "NP1"  !CDS_PN = "NP1";
"NP2":   PN = "NP2"  !CDS_PN = "NP2";
"P1":   PN = "P1"  !CDS_PN = "P1";
"P2":   PN = "P2"  !CDS_PN = "P2";
"P3":   PN = "P3"  !CDS_PN = "P3";
"P4":   PN = "P4"  !CDS_PN = "P4";
"P5":   PN = "P5"  !CDS_PN = "P5";
"P6":   PN = "P6"  !CDS_PN = "P6";
"S1":   PN = "S1"  !CDS_PN = "S1";
"S2":   PN = "S2"  !CDS_PN = "S2";
"S3":   PN = "S3"  !CDS_PN = "S3";
"S4":   PN = "S4"  !CDS_PN = "S4";
"S5":   PN = "S5"  !CDS_PN = "S5";
"S6":   PN = "S6"  !CDS_PN = "S6";
"S7":   PN = "S7"  !CDS_PN = "S7";
BODY = "SKT-SATA7P-6P-165-GP-U1","I68": #LOCATION = "J2W2" !CDS_LOCATION = "J2W2" #SEC = "1" !CDS_SEC = "1";
"H1":   PN = "H1"  !CDS_PN = "H1";
"H2":   PN = "H2"  !CDS_PN = "H2";
"NP1":   PN = "NP1"  !CDS_PN = "NP1";
"NP2":   PN = "NP2"  !CDS_PN = "NP2";
"P1":   PN = "P1"  !CDS_PN = "P1";
"P2":   PN = "P2"  !CDS_PN = "P2";
"P3":   PN = "P3"  !CDS_PN = "P3";
"P4":   PN = "P4"  !CDS_PN = "P4";
"P5":   PN = "P5"  !CDS_PN = "P5";
"P6":   PN = "P6"  !CDS_PN = "P6";
"S1":   PN = "S1"  !CDS_PN = "S1";
"S2":   PN = "S2"  !CDS_PN = "S2";
"S3":   PN = "S3"  !CDS_PN = "S3";
"S4":   PN = "S4"  !CDS_PN = "S4";
"S5":   PN = "S5"  !CDS_PN = "S5";
"S6":   PN = "S6"  !CDS_PN = "S6";
"S7":   PN = "S7"  !CDS_PN = "S7";
BODY = "FUSE-3A75V-GP","I71": #LOCATION = "F8B1" !CDS_LOCATION = "F8B1" #SEC = "1" !CDS_SEC = "1";
"1":   PN = "1"  !CDS_PN = "1";
"2":   PN = "2"  !CDS_PN = "2";
DRAWING = "@baseboard_fab2_lib.baseboard_fab2(sch_1):page173";
BODY = "CONN72_G97614002_A","I163": #LOCATION = "J8A1" !CDS_LOCATION = "J8A1" #SEC = "1" !CDS_SEC = "1";
"GND<0>":   PN = "2D9"  !CDS_PN = "2D9";
"GND<1>":   PN = "2D6"  !CDS_PN = "2D6";
"GND<2>":   PN = "2D3"  !CDS_PN = "2D3";
"GND<3>":   PN = "2C9"  !CDS_PN = "2C9";
"GND<4>":   PN = "2C6"  !CDS_PN = "2C6";
"GND<5>":   PN = "2C3"  !CDS_PN = "2C3";
"GND<6>":   PN = "2B9"  !CDS_PN = "2B9";
"GND<7>":   PN = "2B6"  !CDS_PN = "2B6";
"GND<8>":   PN = "2B3"  !CDS_PN = "2B3";
"GND<9>":   PN = "2A9"  !CDS_PN = "2A9";
"GND<10>":   PN = "2A6"  !CDS_PN = "2A6";
"GND<11>":   PN = "2A3"  !CDS_PN = "2A3";
"GND<12>":   PN = "1D9"  !CDS_PN = "1D9";
"GND<13>":   PN = "1D6"  !CDS_PN = "1D6";
"GND<14>":   PN = "1D3"  !CDS_PN = "1D3";
"GND<15>":   PN = "1C9"  !CDS_PN = "1C9";
"GND<16>":   PN = "1C6"  !CDS_PN = "1C6";
"GND<17>":   PN = "1C3"  !CDS_PN = "1C3";
"GND<18>":   PN = "1B9"  !CDS_PN = "1B9";
"GND<19>":   PN = "1B6"  !CDS_PN = "1B6";
"GND<20>":   PN = "1B3"  !CDS_PN = "1B3";
"GND<21>":   PN = "1A9"  !CDS_PN = "1A9";
"GND<22>":   PN = "1A6"  !CDS_PN = "1A6";
"GND<23>":   PN = "1A3"  !CDS_PN = "1A3";
"RXA0_DN":   PN = "1B5"  !CDS_PN = "1B5";
"RXA0_DP":   PN = "1B4"  !CDS_PN = "1B4";
"RXA1_DN":   PN = "1A5"  !CDS_PN = "1A5";
"RXA1_DP":   PN = "1A4"  !CDS_PN = "1A4";
"RXA2_DN":   PN = "1B8"  !CDS_PN = "1B8";
"RXA2_DP":   PN = "1B7"  !CDS_PN = "1B7";
"RXA3_DN":   PN = "1A8"  !CDS_PN = "1A8";
"RXA3_DP":   PN = "1A7"  !CDS_PN = "1A7";
"RXB0_DN":   PN = "2B5"  !CDS_PN = "2B5";
"RXB0_DP":   PN = "2B4"  !CDS_PN = "2B4";
"RXB1_DN":   PN = "2A5"  !CDS_PN = "2A5";
"RXB1_DP":   PN = "2A4"  !CDS_PN = "2A4";
"RXB2_DN":   PN = "2B8"  !CDS_PN = "2B8";
"RXB2_DP":   PN = "2B7"  !CDS_PN = "2B7";
"RXB3_DN":   PN = "2A8"  !CDS_PN = "2A8";
"RXB3_DP":   PN = "2A7"  !CDS_PN = "2A7";
"SIDEBANDA_0":   PN = "1A2"  !CDS_PN = "1A2";
"SIDEBANDA_1":   PN = "1B2"  !CDS_PN = "1B2";
"SIDEBANDA_2":   PN = "1C2"  !CDS_PN = "1C2";
"SIDEBANDA_3":   PN = "1B1"  !CDS_PN = "1B1";
"SIDEBANDA_4":   PN = "1C1"  !CDS_PN = "1C1";
"SIDEBANDA_5":   PN = "1D1"  !CDS_PN = "1D1";
"SIDEBANDA_6":   PN = "1D2"  !CDS_PN = "1D2";
"SIDEBANDA_7":   PN = "1A1"  !CDS_PN = "1A1";
"SIDEBANDB_0":   PN = "2A2"  !CDS_PN = "2A2";
"SIDEBANDB_1":   PN = "2B2"  !CDS_PN = "2B2";
"SIDEBANDB_2":   PN = "2C2"  !CDS_PN = "2C2";
"SIDEBANDB_3":   PN = "2B1"  !CDS_PN = "2B1";
"SIDEBANDB_4":   PN = "2C1"  !CDS_PN = "2C1";
"SIDEBANDB_5":   PN = "2D1"  !CDS_PN = "2D1";
"SIDEBANDB_6":   PN = "2D2"  !CDS_PN = "2D2";
"SIDEBANDB_7":   PN = "2A1"  !CDS_PN = "2A1";
"TXA0_DN":   PN = "1D5"  !CDS_PN = "1D5";
"TXA0_DP":   PN = "1D4"  !CDS_PN = "1D4";
"TXA1_DN":   PN = "1C5"  !CDS_PN = "1C5";
"TXA1_DP":   PN = "1C4"  !CDS_PN = "1C4";
"TXA2_DN":   PN = "1D8"  !CDS_PN = "1D8";
"TXA2_DP":   PN = "1D7"  !CDS_PN = "1D7";
"TXA3_DN":   PN = "1C8"  !CDS_PN = "1C8";
"TXA3_DP":   PN = "1C7"  !CDS_PN = "1C7";
"TXB0_DN":   PN = "2D5"  !CDS_PN = "2D5";
"TXB0_DP":   PN = "2D4"  !CDS_PN = "2D4";
"TXB1_DN":   PN = "2C5"  !CDS_PN = "2C5";
"TXB1_DP":   PN = "2C4"  !CDS_PN = "2C4";
"TXB2_DN":   PN = "2D8"  !CDS_PN = "2D8";
"TXB2_DP":   PN = "2D7"  !CDS_PN = "2D7";
"TXB3_DN":   PN = "2C8"  !CDS_PN = "2C8";
"TXB3_DP":   PN = "2C7"  !CDS_PN = "2C7";
BODY = "CAP_A","I165": #LOCATION = "C2L13" !CDS_LOCATION = "C2L13" #SEC = "1" !CDS_SEC = "1";
"A":   PN = "1"  !CDS_PN = "1";
"B":   PN = "2"  !CDS_PN = "2";
BODY = "CAP_A","I166": #LOCATION = "C2L6" !CDS_LOCATION = "C2L6" #SEC = "1" !CDS_SEC = "1";
"A":   PN = "1"  !CDS_PN = "1";
"B":   PN = "2"  !CDS_PN = "2";
BODY = "CAP_A","I172": #LOCATION = "C2L19" !CDS_LOCATION = "C2L19" #SEC = "1" !CDS_SEC = "1";
"A":   PN = "1"  !CDS_PN = "1";
"B":   PN = "2"  !CDS_PN = "2";
BODY = "CAP_A","I173": #LOCATION = "C2L10" !CDS_LOCATION = "C2L10" #SEC = "1" !CDS_SEC = "1";
"A":   PN = "1"  !CDS_PN = "1";
"B":   PN = "2"  !CDS_PN = "2";
BODY = "CAP_A","I174": #LOCATION = "C2L17" !CDS_LOCATION = "C2L17" #SEC = "1" !CDS_SEC = "1";
"A":   PN = "1"  !CDS_PN = "1";
"B":   PN = "2"  !CDS_PN = "2";
BODY = "CAP_A","I191": #LOCATION = "C2L15" !CDS_LOCATION = "C2L15" #SEC = "1" !CDS_SEC = "1";
"A":   PN = "1"  !CDS_PN = "1";
"B":   PN = "2"  !CDS_PN = "2";
BODY = "CAP_A","I192": #LOCATION = "C2L4" !CDS_LOCATION = "C2L4" #SEC = "1" !CDS_SEC = "1";
"A":   PN = "1"  !CDS_PN = "1";
"B":   PN = "2"  !CDS_PN = "2";
BODY = "CAP_A","I194": #LOCATION = "C2L3" !CDS_LOCATION = "C2L3" #SEC = "1" !CDS_SEC = "1";
"A":   PN = "1"  !CDS_PN = "1";
"B":   PN = "2"  !CDS_PN = "2";
BODY = "CAP_A","I195": #LOCATION = "C2L20" !CDS_LOCATION = "C2L20" #SEC = "1" !CDS_SEC = "1";
"A":   PN = "1"  !CDS_PN = "1";
"B":   PN = "2"  !CDS_PN = "2";
BODY = "CAP_A","I196": #LOCATION = "C2L12" !CDS_LOCATION = "C2L12" #SEC = "1" !CDS_SEC = "1";
"A":   PN = "1"  !CDS_PN = "1";
"B":   PN = "2"  !CDS_PN = "2";
BODY = "CAP_A","I197": #LOCATION = "C2L18" !CDS_LOCATION = "C2L18" #SEC = "1" !CDS_SEC = "1";
"A":   PN = "1"  !CDS_PN = "1";
"B":   PN = "2"  !CDS_PN = "2";
BODY = "CAP_A","I205": #LOCATION = "C2L16" !CDS_LOCATION = "C2L16" #SEC = "1" !CDS_SEC = "1";
"A":   PN = "1"  !CDS_PN = "1";
"B":   PN = "2"  !CDS_PN = "2";
BODY = "CAP_A","I206": #LOCATION = "C2L7" !CDS_LOCATION = "C2L7" #SEC = "1" !CDS_SEC = "1";
"A":   PN = "1"  !CDS_PN = "1";
"B":   PN = "2"  !CDS_PN = "2";
BODY = "CAP_A","I207": #LOCATION = "C2L9" !CDS_LOCATION = "C2L9" #SEC = "1" !CDS_SEC = "1";
"A":   PN = "1"  !CDS_PN = "1";
"B":   PN = "2"  !CDS_PN = "2";
BODY = "CAP_A","I208": #LOCATION = "C2L14" !CDS_LOCATION = "C2L14" #SEC = "1" !CDS_SEC = "1";
"A":   PN = "1"  !CDS_PN = "1";
"B":   PN = "2"  !CDS_PN = "2";
BODY = "CAP_A","I209": #LOCATION = "C2L5" !CDS_LOCATION = "C2L5" #SEC = "1" !CDS_SEC = "1";
"A":   PN = "1"  !CDS_PN = "1";
"B":   PN = "2"  !CDS_PN = "2";
BODY = "CAP_A","I220": #LOCATION = "C2L40" !CDS_LOCATION = "C2L40" #SEC = "1" !CDS_SEC = "1";
"A":   PN = "1"  !CDS_PN = "1";
"B":   PN = "2"  !CDS_PN = "2";
BODY = "CAP_A","I221": #LOCATION = "C2L39" !CDS_LOCATION = "C2L39" #SEC = "1" !CDS_SEC = "1";
"A":   PN = "1"  !CDS_PN = "1";
"B":   PN = "2"  !CDS_PN = "2";
BODY = "CAP_A","I222": #LOCATION = "C2L43" !CDS_LOCATION = "C2L43" #SEC = "1" !CDS_SEC = "1";
"A":   PN = "1"  !CDS_PN = "1";
"B":   PN = "2"  !CDS_PN = "2";
BODY = "CAP_A","I228": #LOCATION = "C2L44" !CDS_LOCATION = "C2L44" #SEC = "1" !CDS_SEC = "1";
"A":   PN = "1"  !CDS_PN = "1";
"B":   PN = "2"  !CDS_PN = "2";
BODY = "CAP_A","I233": #LOCATION = "C2L42" !CDS_LOCATION = "C2L42" #SEC = "1" !CDS_SEC = "1";
"A":   PN = "1"  !CDS_PN = "1";
"B":   PN = "2"  !CDS_PN = "2";
BODY = "CAP_A","I234": #LOCATION = "C2L22" !CDS_LOCATION = "C2L22" #SEC = "1" !CDS_SEC = "1";
"A":   PN = "1"  !CDS_PN = "1";
"B":   PN = "2"  !CDS_PN = "2";
BODY = "CAP_A","I238": #LOCATION = "C2L37" !CDS_LOCATION = "C2L37" #SEC = "1" !CDS_SEC = "1";
"A":   PN = "1"  !CDS_PN = "1";
"B":   PN = "2"  !CDS_PN = "2";
BODY = "CAP_A","I239": #LOCATION = "C2L47" !CDS_LOCATION = "C2L47" #SEC = "1" !CDS_SEC = "1";
"A":   PN = "1"  !CDS_PN = "1";
"B":   PN = "2"  !CDS_PN = "2";
BODY = "CAP_A","I240": #LOCATION = "C2L27" !CDS_LOCATION = "C2L27" #SEC = "1" !CDS_SEC = "1";
"A":   PN = "1"  !CDS_PN = "1";
"B":   PN = "2"  !CDS_PN = "2";
BODY = "CAP_A","I241": #LOCATION = "C2L23" !CDS_LOCATION = "C2L23" #SEC = "1" !CDS_SEC = "1";
"A":   PN = "1"  !CDS_PN = "1";
"B":   PN = "2"  !CDS_PN = "2";
BODY = "CAP_A","I242": #LOCATION = "C2L41" !CDS_LOCATION = "C2L41" #SEC = "1" !CDS_SEC = "1";
"A":   PN = "1"  !CDS_PN = "1";
"B":   PN = "2"  !CDS_PN = "2";
BODY = "CAP_A","I255": #LOCATION = "C2L26" !CDS_LOCATION = "C2L26" #SEC = "1" !CDS_SEC = "1";
"A":   PN = "1"  !CDS_PN = "1";
"B":   PN = "2"  !CDS_PN = "2";
BODY = "CAP_A","I256": #LOCATION = "C2L38" !CDS_LOCATION = "C2L38" #SEC = "1" !CDS_SEC = "1";
"A":   PN = "1"  !CDS_PN = "1";
"B":   PN = "2"  !CDS_PN = "2";
BODY = "CAP_A","I257": #LOCATION = "C2L48" !CDS_LOCATION = "C2L48" #SEC = "1" !CDS_SEC = "1";
"A":   PN = "1"  !CDS_PN = "1";
"B":   PN = "2"  !CDS_PN = "2";
BODY = "CAP_A","I258": #LOCATION = "C2L24" !CDS_LOCATION = "C2L24" #SEC = "1" !CDS_SEC = "1";
"A":   PN = "1"  !CDS_PN = "1";
"B":   PN = "2"  !CDS_PN = "2";
BODY = "CAP_A","I259": #LOCATION = "C2L21" !CDS_LOCATION = "C2L21" #SEC = "1" !CDS_SEC = "1";
"A":   PN = "1"  !CDS_PN = "1";
"B":   PN = "2"  !CDS_PN = "2";
BODY = "RES","I261": #LOCATION = "R2L23" !CDS_LOCATION = "R2L23" #SEC = "1" !CDS_SEC = "1";
"A":   PN = "1"  !CDS_PN = "1";
"B":   PN = "2"  !CDS_PN = "2";
BODY = "RES","I263": #LOCATION = "R2L21" !CDS_LOCATION = "R2L21" #SEC = "1" !CDS_SEC = "1";
"A":   PN = "1"  !CDS_PN = "1";
"B":   PN = "2"  !CDS_PN = "2";
BODY = "RES","I264": #LOCATION = "R2L22" !CDS_LOCATION = "R2L22" #SEC = "1" !CDS_SEC = "1";
"A":   PN = "1"  !CDS_PN = "1";
"B":   PN = "2"  !CDS_PN = "2";
BODY = "RES","I266": #LOCATION = "R2L18" !CDS_LOCATION = "R2L18" #SEC = "1" !CDS_SEC = "1";
"A":   PN = "1"  !CDS_PN = "1";
"B":   PN = "2"  !CDS_PN = "2";
DRAWING = "@baseboard_fab2_lib.baseboard_fab2(sch_1):page175";
BODY = "RES","I4": #LOCATION = "R1L31" !CDS_LOCATION = "R1L31" #SEC = "1" !CDS_SEC = "1";
"A":   PN = "1"  !CDS_PN = "1";
"B":   PN = "2"  !CDS_PN = "2";
BODY = "RES","I5": #LOCATION = "R1L27" !CDS_LOCATION = "R1L27" #SEC = "1" !CDS_SEC = "1";
"A":   PN = "1"  !CDS_PN = "1";
"B":   PN = "2"  !CDS_PN = "2";
BODY = "CAP_A","I11": #LOCATION = "C1L18" !CDS_LOCATION = "C1L18" #SEC = "1" !CDS_SEC = "1";
"A":   PN = "1"  !CDS_PN = "1";
"B":   PN = "2"  !CDS_PN = "2";
BODY = "RES","I13": #LOCATION = "R1L26" !CDS_LOCATION = "R1L26" #SEC = "1" !CDS_SEC = "1";
"A":   PN = "1"  !CDS_PN = "1";
"B":   PN = "2"  !CDS_PN = "2";
BODY = "CAP_A","I19": #LOCATION = "C1L10" !CDS_LOCATION = "C1L10" #SEC = "1" !CDS_SEC = "1";
"A":   PN = "1"  !CDS_PN = "1";
"B":   PN = "2"  !CDS_PN = "2";
BODY = "RES","I22": #LOCATION = "R1L22" !CDS_LOCATION = "R1L22" #SEC = "1" !CDS_SEC = "1";
"A":   PN = "1"  !CDS_PN = "1";
"B":   PN = "2"  !CDS_PN = "2";
BODY = "CAP_A","I37": #LOCATION = "C1L17" !CDS_LOCATION = "C1L17" #SEC = "1" !CDS_SEC = "1";
"A":   PN = "1"  !CDS_PN = "1";
"B":   PN = "2"  !CDS_PN = "2";
BODY = "CAP_A","I38": #LOCATION = "C1L9" !CDS_LOCATION = "C1L9" #SEC = "1" !CDS_SEC = "1";
"A":   PN = "1"  !CDS_PN = "1";
"B":   PN = "2"  !CDS_PN = "2";
BODY = "CAP_A","I40": #LOCATION = "C9A3" !CDS_LOCATION = "C9A3" #SEC = "1" !CDS_SEC = "1";
"A":   PN = "1"  !CDS_PN = "1";
"B":   PN = "2"  !CDS_PN = "2";
BODY = "RES","I45": #LOCATION = "R1L33" !CDS_LOCATION = "R1L33" #SEC = "1" !CDS_SEC = "1";
"A":   PN = "1"  !CDS_PN = "1";
"B":   PN = "2"  !CDS_PN = "2";
BODY = "FET_N","I49": #LOCATION = "Q9A3" !CDS_LOCATION = "Q9A3" #SEC = "1" !CDS_SEC = "1";
"DRN":   PN = "3"  !CDS_PN = "3";
"GATE":   PN = "1"  !CDS_PN = "1";
"SRC":   PN = "2"  !CDS_PN = "2";
BODY = "LED","I50": #LOCATION = "DS9A1" !CDS_LOCATION = "DS9A1" &SEC = "1" #&CDS_SEC = "1";
"A":   PN = "2"  !CDS_PN = "2";
"C":   PN = "1"  !CDS_PN = "1";
BODY = "TTL1G86","I57": #LOCATION = "U1L2" !CDS_LOCATION = "U1L2" &SEC = "1" #&CDS_SEC = "1";
"A":   PN = "1"  !CDS_PN = "1";
"B":   PN = "2"  !CDS_PN = "2";
"Y":   PN = "4"  !CDS_PN = "4";
BODY = "RES","I58": #LOCATION = "R1L8" !CDS_LOCATION = "R1L8" #SEC = "1" !CDS_SEC = "1";
"A":   PN = "1"  !CDS_PN = "1";
"B":   PN = "2"  !CDS_PN = "2";
BODY = "RES","I63": #LOCATION = "R1L12" !CDS_LOCATION = "R1L12" #SEC = "1" !CDS_SEC = "1";
"A":   PN = "1"  !CDS_PN = "1";
"B":   PN = "2"  !CDS_PN = "2";
BODY = "CAP_A","I64": #LOCATION = "C1L4" !CDS_LOCATION = "C1L4" #SEC = "1" !CDS_SEC = "1";
"A":   PN = "1"  !CDS_PN = "1";
"B":   PN = "2"  !CDS_PN = "2";
BODY = "LED","I67": #LOCATION = "DS9A3" !CDS_LOCATION = "DS9A3" #SEC = "1" !CDS_SEC = "1";
"A":   PN = "2"  !CDS_PN = "2";
"C":   PN = "1"  !CDS_PN = "1";
BODY = "SWITCH_D37771002","I78": #LOCATION = "S9A1" !CDS_LOCATION = "S9A1" #SEC = "1" !CDS_SEC = "1";
"PIN1":   PN = "1"  !CDS_PN = "1";
"PIN2":   PN = "2"  !CDS_PN = "2";
"PIN3":   PN = "3"  !CDS_PN = "3";
"PIN4":   PN = "4"  !CDS_PN = "4";
BODY = "SWITCH_D37771002","I92": #LOCATION = "S9A2" !CDS_LOCATION = "S9A2" #SEC = "1" !CDS_SEC = "1";
"PIN1":   PN = "1"  !CDS_PN = "1";
"PIN2":   PN = "2"  !CDS_PN = "2";
"PIN3":   PN = "3"  !CDS_PN = "3";
"PIN4":   PN = "4"  !CDS_PN = "4";
BODY = "TC7PZ14FU-GP","I93": #LOCATION = "U9A3" !CDS_LOCATION = "U9A3" #SEC = "1" !CDS_SEC = "1";
"1A":   PN = "1"  !CDS_PN = "1";
"1Y":   PN = "6"  !CDS_PN = "6";
"2A":   PN = "3"  !CDS_PN = "3";
"2Y":   PN = "4"  !CDS_PN = "4";
"GND":   PN = "2"  !CDS_PN = "2";
"VCC":   PN = "5"  !CDS_PN = "5";
BODY = "RES","I95": #LOCATION = "R9A9" !CDS_LOCATION = "R9A9" #SEC = "1" !CDS_SEC = "1";
"A":   PN = "1"  !CDS_PN = "1";
"B":   PN = "2"  !CDS_PN = "2";
BODY = "TC7PZ14FU-GP","I97": #LOCATION = "U9A4" !CDS_LOCATION = "U9A4" #SEC = "1" !CDS_SEC = "1";
"1A":   PN = "1"  !CDS_PN = "1";
"1Y":   PN = "6"  !CDS_PN = "6";
"2A":   PN = "3"  !CDS_PN = "3";
"2Y":   PN = "4"  !CDS_PN = "4";
"GND":   PN = "2"  !CDS_PN = "2";
"VCC":   PN = "5"  !CDS_PN = "5";
BODY = "RES","I99": #LOCATION = "R1L19" !CDS_LOCATION = "R1L19" #SEC = "1" !CDS_SEC = "1";
"A":   PN = "1"  !CDS_PN = "1";
"B":   PN = "2"  !CDS_PN = "2";
DRAWING = "@baseboard_fab2_lib.baseboard_fab2(sch_1):page176";
BODY = "RES","I16": #LOCATION = "R1M5" !CDS_LOCATION = "R1M5" #SEC = "1" !CDS_SEC = "1";
"A":   PN = "1"  !CDS_PN = "1";
"B":   PN = "2"  !CDS_PN = "2";
BODY = "RES","I31": #LOCATION = "R1M6" !CDS_LOCATION = "R1M6" #SEC = "1" !CDS_SEC = "1";
"A":   PN = "1"  !CDS_PN = "1";
"B":   PN = "2"  !CDS_PN = "2";
BODY = "CONN9_H51826001","I69": #LOCATION = "J9B1" !CDS_LOCATION = "J9B1" &SEC = "1" #&CDS_SEC = "1";
"DN":   PN = "2"  !CDS_PN = "2";
"DP":   PN = "3"  !CDS_PN = "3";
"GND":   PN = "4"  !CDS_PN = "4";
"GND_DRAIN":   PN = "7"  !CDS_PN = "7";
"MH1":   PN = "MH1"  !CDS_PN = "MH1";
"MH2":   PN = "MH2"  !CDS_PN = "MH2";
"MH3":   PN = "MH3"  !CDS_PN = "MH3";
"MH4":   PN = "MH4"  !CDS_PN = "MH4";
"STDA_SSRXN":   PN = "5"  !CDS_PN = "5";
"STDA_SSRXP":   PN = "6"  !CDS_PN = "6";
"STDA_SSTXN":   PN = "8"  !CDS_PN = "8";
"STDA_SSTXP":   PN = "9"  !CDS_PN = "9";
"VBUS":   PN = "1"  !CDS_PN = "1";
BODY = "DIODEAC_DUAL_ARRAY","I98": #LOCATION = "CR1M2" !CDS_LOCATION = "CR1M2" #SEC = "1" !CDS_SEC = "1";
"AC0":   PN = "1"  !CDS_PN = "1";
"AC1":   PN = "2"  !CDS_PN = "2";
"AC2":   PN = "4"  !CDS_PN = "4";
"AC3":   PN = "5"  !CDS_PN = "5";
"GND<0>":   PN = "3"  !CDS_PN = "3";
"OUT0":   PN = "9"  !CDS_PN = "9";
"OUT1":   PN = "8"  !CDS_PN = "8";
"OUT2":   PN = "7"  !CDS_PN = "7";
"OUT3":   PN = "6"  !CDS_PN = "6";
BODY = "TPS2061","I100": #LOCATION = "U1M3" !CDS_LOCATION = "U1M3" #SEC = "1" !CDS_SEC = "1";
"EN_N":   PN = "4"  !CDS_PN = "4";
"GND":   PN = "2"  !CDS_PN = "2";
"IN":   PN = "5"  !CDS_PN = "5";
"OC_N":   PN = "3"  !CDS_PN = "3";
"OUT":   PN = "1"  !CDS_PN = "1";
BODY = "RES","I105": #LOCATION = "R1M24" !CDS_LOCATION = "R1M24" #SEC = "1" !CDS_SEC = "1";
"A":   PN = "1"  !CDS_PN = "1";
"B":   PN = "2"  !CDS_PN = "2";
BODY = "CAP_A","I108": #LOCATION = "C1M38" !CDS_LOCATION = "C1M38" #SEC = "1" !CDS_SEC = "1";
"A":   PN = "1"  !CDS_PN = "1";
"B":   PN = "2"  !CDS_PN = "2";
BODY = "RES","I111": #LOCATION = "R1M25" !CDS_LOCATION = "R1M25" #SEC = "1" !CDS_SEC = "1";
"A":   PN = "1"  !CDS_PN = "1";
"B":   PN = "2"  !CDS_PN = "2";
BODY = "CAPP","I113": #LOCATION = "C9B8" !CDS_LOCATION = "C9B8" #SEC = "1" !CDS_SEC = "1";
"A":   PN = "1"  !CDS_PN = "1";
"B":   PN = "2"  !CDS_PN = "2";
BODY = "RES","I132": #LOCATION = "R1W10" !CDS_LOCATION = "R1W10" #SEC = "1" !CDS_SEC = "1";
"A":   PN = "1"  !CDS_PN = "1";
"B":   PN = "2"  !CDS_PN = "2";
BODY = "RES","I133": #LOCATION = "R1W11" !CDS_LOCATION = "R1W11" #SEC = "1" !CDS_SEC = "1";
"A":   PN = "1"  !CDS_PN = "1";
"B":   PN = "2"  !CDS_PN = "2";
BODY = "RES","I137": #LOCATION = "R1W12" !CDS_LOCATION = "R1W12" #SEC = "1" !CDS_SEC = "1";
"A":   PN = "1"  !CDS_PN = "1";
"B":   PN = "2"  !CDS_PN = "2";
BODY = "RES","I138": #LOCATION = "R1W13" !CDS_LOCATION = "R1W13" #SEC = "1" !CDS_SEC = "1";
"A":   PN = "1"  !CDS_PN = "1";
"B":   PN = "2"  !CDS_PN = "2";
BODY = "CAP_A","I139": #LOCATION = "C6W10" !CDS_LOCATION = "C6W10" #SEC = "1" !CDS_SEC = "1";
"A":   PN = "1"  !CDS_PN = "1";
"B":   PN = "2"  !CDS_PN = "2";
BODY = "RES","I142": #LOCATION = "R1W33" !CDS_LOCATION = "R1W33" #SEC = "1" !CDS_SEC = "1";
"A":   PN = "1"  !CDS_PN = "1";
"B":   PN = "2"  !CDS_PN = "2";
BODY = "RES","I143": #LOCATION = "R1W34" !CDS_LOCATION = "R1W34" #SEC = "1" !CDS_SEC = "1";
"A":   PN = "1"  !CDS_PN = "1";
"B":   PN = "2"  !CDS_PN = "2";
BODY = "TTL1G126_A","I146": #LOCATION = "U6W4" !CDS_LOCATION = "U6W4" #SEC = "1" !CDS_SEC = "1";
"A":   PN = "2"  !CDS_PN = "2";
"OE":   PN = "1"  !CDS_PN = "1";
"Y":   PN = "4"  !CDS_PN = "4";
BODY = "RES","I147": #LOCATION = "R6W30" !CDS_LOCATION = "R6W30" #SEC = "1" !CDS_SEC = "1";
"A":   PN = "1"  !CDS_PN = "1";
"B":   PN = "2"  !CDS_PN = "2";
BODY = "TTL1G126_A","I148": #LOCATION = "U6W5" !CDS_LOCATION = "U6W5" #SEC = "1" !CDS_SEC = "1";
"A":   PN = "2"  !CDS_PN = "2";
"OE":   PN = "1"  !CDS_PN = "1";
"Y":   PN = "4"  !CDS_PN = "4";
BODY = "RES","I156": #LOCATION = "R6W38" !CDS_LOCATION = "R6W38" #SEC = "1" !CDS_SEC = "1";
"A":   PN = "1"  !CDS_PN = "1";
"B":   PN = "2"  !CDS_PN = "2";
BODY = "TTL1G126_A","I157": #LOCATION = "U6W6" !CDS_LOCATION = "U6W6" #SEC = "1" !CDS_SEC = "1";
"A":   PN = "2"  !CDS_PN = "2";
"OE":   PN = "1"  !CDS_PN = "1";
"Y":   PN = "4"  !CDS_PN = "4";
BODY = "RES","I158": #LOCATION = "R6W39" !CDS_LOCATION = "R6W39" #SEC = "1" !CDS_SEC = "1";
"A":   PN = "1"  !CDS_PN = "1";
"B":   PN = "2"  !CDS_PN = "2";
BODY = "RES","I160": #LOCATION = "R6W37" !CDS_LOCATION = "R6W37" &SEC = "1" #&CDS_SEC = "1";
"A":   PN = "1"  !CDS_PN = "1";
"B":   PN = "2"  !CDS_PN = "2";
BODY = "RES","I161": #LOCATION = "R6W36" !CDS_LOCATION = "R6W36" &SEC = "1" #&CDS_SEC = "1";
"A":   PN = "1"  !CDS_PN = "1";
"B":   PN = "2"  !CDS_PN = "2";
BODY = "PCA9617","I162": #LOCATION = "U1W3" !CDS_LOCATION = "U1W3" &SEC = "1" #&CDS_SEC = "1";
"EN":   PN = "5"  !CDS_PN = "5";
"SCLA":   PN = "2"  !CDS_PN = "2";
"SCLB":   PN = "7"  !CDS_PN = "7";
"SDAA":   PN = "3"  !CDS_PN = "3";
"SDAB":   PN = "6"  !CDS_PN = "6";
"VCCA":   PN = "1"  !CDS_PN = "1";
"VCCB":   PN = "8"  !CDS_PN = "8";
BODY = "CAP_A","I163": #LOCATION = "C1W18" !CDS_LOCATION = "C1W18" &SEC = "1" #&CDS_SEC = "1";
"A":   PN = "1"  !CDS_PN = "1";
"B":   PN = "2"  !CDS_PN = "2";
BODY = "CAP_A","I166": #LOCATION = "C1W19" !CDS_LOCATION = "C1W19" &SEC = "1" #&CDS_SEC = "1";
"A":   PN = "1"  !CDS_PN = "1";
"B":   PN = "2"  !CDS_PN = "2";
BODY = "RES","I172": #LOCATION = "R1W36" !CDS_LOCATION = "R1W36" #SEC = "1" !CDS_SEC = "1";
"A":   PN = "1"  !CDS_PN = "1";
"B":   PN = "2"  !CDS_PN = "2";
BODY = "RES","I173": #LOCATION = "R1W37" !CDS_LOCATION = "R1W37" #SEC = "1" !CDS_SEC = "1";
"A":   PN = "1"  !CDS_PN = "1";
"B":   PN = "2"  !CDS_PN = "2";
BODY = "RES","I175": #LOCATION = "R1W39" !CDS_LOCATION = "R1W39" #SEC = "1" !CDS_SEC = "1";
"A":   PN = "1"  !CDS_PN = "1";
"B":   PN = "2"  !CDS_PN = "2";
BODY = "RES","I176": #LOCATION = "R1W38" !CDS_LOCATION = "R1W38" #SEC = "1" !CDS_SEC = "1";
"A":   PN = "1"  !CDS_PN = "1";
"B":   PN = "2"  !CDS_PN = "2";
BODY = "RES","I178": #LOCATION = "R6W50" !CDS_LOCATION = "R6W50" #SEC = "1" !CDS_SEC = "1";
"A":   PN = "1"  !CDS_PN = "1";
"B":   PN = "2"  !CDS_PN = "2";
BODY = "CHOKE_4PIN","I181": #LOCATION = "L1M2" !CDS_LOCATION = "L1M2" #SEC = "1" !CDS_SEC = "1";
"A1":   PN = "1"  !CDS_PN = "1";
"A2":   PN = "2"  !CDS_PN = "2";
"B1":   PN = "3"  !CDS_PN = "3";
"B2":   PN = "4"  !CDS_PN = "4";
BODY = "NC7SB3157","I182": #LOCATION = "U6W12" !CDS_LOCATION = "U6W12" &SEC = "1" #&CDS_SEC = "1";
"A":   PN = "4"  !CDS_PN = "4";
"B0":   PN = "3"  !CDS_PN = "3";
"B1":   PN = "1"  !CDS_PN = "1";
"GND":   PN = "2"  !CDS_PN = "2";
"S":   PN = "6"  !CDS_PN = "6";
"VCC":   PN = "5"  !CDS_PN = "5";
DRAWING = "@baseboard_fab2_lib.baseboard_fab2(sch_1):page177";
BODY = "RES","I3": #LOCATION = "R1M13" !CDS_LOCATION = "R1M13" &SEC = "1" #&CDS_SEC = "1";
"A":   PN = "1"  !CDS_PN = "1";
"B":   PN = "2"  !CDS_PN = "2";
BODY = "RES","I6": #LOCATION = "R1M10" !CDS_LOCATION = "R1M10" &SEC = "1" #&CDS_SEC = "1";
"A":   PN = "1"  !CDS_PN = "1";
"B":   PN = "2"  !CDS_PN = "2";
BODY = "RES","I8": #LOCATION = "R1M12" !CDS_LOCATION = "R1M12" #SEC = "1" !CDS_SEC = "1";
"A":   PN = "1"  !CDS_PN = "1";
"B":   PN = "2"  !CDS_PN = "2";
BODY = "RES","I9": #LOCATION = "R1M11" !CDS_LOCATION = "R1M11" #SEC = "1" !CDS_SEC = "1";
"A":   PN = "1"  !CDS_PN = "1";
"B":   PN = "2"  !CDS_PN = "2";
BODY = "CAP_A","I20": #LOCATION = "C1M3" !CDS_LOCATION = "C1M3" &SEC = "1" #&CDS_SEC = "1";
"A":   PN = "1"  !CDS_PN = "1";
"B":   PN = "2"  !CDS_PN = "2";
BODY = "LED","I31": #LOCATION = "DS9A6" !CDS_LOCATION = "DS9A6" #SEC = "1" !CDS_SEC = "1";
"A":   PN = "1"  !CDS_PN = "1";
"C":   PN = "2"  !CDS_PN = "2";
BODY = "RES","I33": #LOCATION = "R1L37" !CDS_LOCATION = "R1L37" &SEC = "1" #&CDS_SEC = "1";
"A":   PN = "1"  !CDS_PN = "1";
"B":   PN = "2"  !CDS_PN = "2";
BODY = "LED","I42": #LOCATION = "DS9A2" !CDS_LOCATION = "DS9A2" #SEC = "1" !CDS_SEC = "1";
"A":   PN = "2"  !CDS_PN = "2";
"C":   PN = "1"  !CDS_PN = "1";
BODY = "RES","I43": #LOCATION = "R1L21" !CDS_LOCATION = "R1L21" #SEC = "1" !CDS_SEC = "1";
"A":   PN = "1"  !CDS_PN = "1";
"B":   PN = "2"  !CDS_PN = "2";
BODY = "TTL1G08","I70": #LOCATION = "U1M1" !CDS_LOCATION = "U1M1" #SEC = "1" !CDS_SEC = "1";
"A<0>":   PN = "1"  !CDS_PN = "1";
"B<0>":   PN = "2"  !CDS_PN = "2";
"Y<0>":   PN = "4"  !CDS_PN = "4";
BODY = "LED","I71": #LOCATION = "DS9F1" !CDS_LOCATION = "DS9F1" #SEC = "1" !CDS_SEC = "1";
"A":   PN = "1"  !CDS_PN = "1";
"C":   PN = "2"  !CDS_PN = "2";
BODY = "RES","I72": #LOCATION = "R9F28" !CDS_LOCATION = "R9F28" #SEC = "1" !CDS_SEC = "1";
"A":   PN = "1"  !CDS_PN = "1";
"B":   PN = "2"  !CDS_PN = "2";
BODY = "RES","I76": #LOCATION = "R9F30" !CDS_LOCATION = "R9F30" #SEC = "1" !CDS_SEC = "1";
"A":   PN = "1"  !CDS_PN = "1";
"B":   PN = "2"  !CDS_PN = "2";
BODY = "FET_N_DUAL","I79": #LOCATION = "Q9F1" !CDS_LOCATION = "Q9F1" #SEC = "2" !CDS_SEC = "2";
"DRAIN<0>":   PN = "3"  !CDS_PN = "3";
"GATE<0>":   PN = "5"  !CDS_PN = "5";
"SOURCE<0>":   PN = "4"  !CDS_PN = "4";
BODY = "FET_N_DUAL","I80": #LOCATION = "Q9F1" !CDS_LOCATION = "Q9F1" #SEC = "1" !CDS_SEC = "1";
"DRAIN<0>":   PN = "6"  !CDS_PN = "6";
"GATE<0>":   PN = "2"  !CDS_PN = "2";
"SOURCE<0>":   PN = "1"  !CDS_PN = "1";
BODY = "RES","I82": #LOCATION = "R9F52" !CDS_LOCATION = "R9F52" #SEC = "1" !CDS_SEC = "1";
"A":   PN = "1"  !CDS_PN = "1";
"B":   PN = "2"  !CDS_PN = "2";
DRAWING = "@baseboard_fab2_lib.baseboard_fab2(sch_1):page178";
BODY = "RES","I1": #LOCATION = "R8D20" !CDS_LOCATION = "R8D20" #SEC = "1" !CDS_SEC = "1";
"A":   PN = "1"  !CDS_PN = "1";
"B":   PN = "2"  !CDS_PN = "2";
BODY = "RES","I2": #LOCATION = "R2L12" !CDS_LOCATION = "R2L12" #SEC = "1" !CDS_SEC = "1";
"A":   PN = "1"  !CDS_PN = "1";
"B":   PN = "2"  !CDS_PN = "2";
BODY = "RES","I8": #LOCATION = "R8D19" !CDS_LOCATION = "R8D19" #SEC = "1" !CDS_SEC = "1";
"A":   PN = "1"  !CDS_PN = "1";
"B":   PN = "2"  !CDS_PN = "2";
BODY = "RES","I11": #LOCATION = "R2N31" !CDS_LOCATION = "R2N31" #SEC = "1" !CDS_SEC = "1";
"A":   PN = "1"  !CDS_PN = "1";
"B":   PN = "2"  !CDS_PN = "2";
BODY = "RES","I12": #LOCATION = "R2L15" !CDS_LOCATION = "R2L15" #SEC = "1" !CDS_SEC = "1";
"A":   PN = "1"  !CDS_PN = "1";
"B":   PN = "2"  !CDS_PN = "2";
BODY = "RES","I13": #LOCATION = "R2L11" !CDS_LOCATION = "R2L11" #SEC = "1" !CDS_SEC = "1";
"A":   PN = "1"  !CDS_PN = "1";
"B":   PN = "2"  !CDS_PN = "2";
BODY = "RES","I17": #LOCATION = "R2L6" !CDS_LOCATION = "R2L6" #SEC = "1" !CDS_SEC = "1";
"A":   PN = "1"  !CDS_PN = "1";
"B":   PN = "2"  !CDS_PN = "2";
BODY = "RES","I18": #LOCATION = "R2L4" !CDS_LOCATION = "R2L4" #SEC = "1" !CDS_SEC = "1";
"A":   PN = "1"  !CDS_PN = "1";
"B":   PN = "2"  !CDS_PN = "2";
BODY = "RES","I20": #LOCATION = "R2L5" !CDS_LOCATION = "R2L5" #SEC = "1" !CDS_SEC = "1";
"A":   PN = "1"  !CDS_PN = "1";
"B":   PN = "2"  !CDS_PN = "2";
BODY = "RES","I21": #LOCATION = "R8B29" !CDS_LOCATION = "R8B29" #SEC = "1" !CDS_SEC = "1";
"A":   PN = "1"  !CDS_PN = "1";
"B":   PN = "2"  !CDS_PN = "2";
BODY = "RES","I22": #LOCATION = "R2N19" !CDS_LOCATION = "R2N19" #SEC = "1" !CDS_SEC = "1";
"A":   PN = "1"  !CDS_PN = "1";
"B":   PN = "2"  !CDS_PN = "2";
BODY = "RES","I23": #LOCATION = "R2N22" !CDS_LOCATION = "R2N22" #SEC = "1" !CDS_SEC = "1";
"A":   PN = "1"  !CDS_PN = "1";
"B":   PN = "2"  !CDS_PN = "2";
DRAWING = "@baseboard_fab2_lib.baseboard_fab2(sch_1):page184";
BODY = "SCONN11_H67026001","I87": #LOCATION = "J8E1" !CDS_LOCATION = "J8E1" #SEC = "1" !CDS_SEC = "1";
"IO1":   PN = "1"  !CDS_PN = "1";
"IO2":   PN = "2"  !CDS_PN = "2";
"IO3":   PN = "3"  !CDS_PN = "3";
"IO4":   PN = "4"  !CDS_PN = "4";
"IO5":   PN = "5"  !CDS_PN = "5";
"IO6":   PN = "6"  !CDS_PN = "6";
"IO7":   PN = "7"  !CDS_PN = "7";
"IO8":   PN = "8"  !CDS_PN = "8";
"IO9":   PN = "9"  !CDS_PN = "9";
"IO10":   PN = "10"  !CDS_PN = "10";
"IO11":   PN = "11"  !CDS_PN = "11";
"MP1":   PN = "MP1"  !CDS_PN = "MP1";
"MP2":   PN = "MP2"  !CDS_PN = "MP2";
BODY = "RES","I88": #LOCATION = "R8E9" !CDS_LOCATION = "R8E9" #SEC = "1" !CDS_SEC = "1";
"A":   PN = "1"  !CDS_PN = "1";
"B":   PN = "2"  !CDS_PN = "2";
BODY = "RES","I92": #LOCATION = "R8D35" !CDS_LOCATION = "R8D35" #SEC = "1" !CDS_SEC = "1";
"A":   PN = "1"  !CDS_PN = "1";
"B":   PN = "2"  !CDS_PN = "2";
BODY = "RES","I93": #LOCATION = "R8E13" !CDS_LOCATION = "R8E13" #SEC = "1" !CDS_SEC = "1";
"A":   PN = "1"  !CDS_PN = "1";
"B":   PN = "2"  !CDS_PN = "2";
BODY = "RES","I95": #LOCATION = "R8E10" !CDS_LOCATION = "R8E10" #SEC = "1" !CDS_SEC = "1";
"A":   PN = "1"  !CDS_PN = "1";
"B":   PN = "2"  !CDS_PN = "2";
BODY = "RES","I99": #LOCATION = "R8E1" !CDS_LOCATION = "R8E1" &SEC = "1" #&CDS_SEC = "1";
"A":   PN = "1"  !CDS_PN = "1";
"B":   PN = "2"  !CDS_PN = "2";
BODY = "STANDOFF","I104": #LOCATION = "RM8D1" !CDS_LOCATION = "RM8D1" #SEC = "1" !CDS_SEC = "1";
"IO1":   PN = "1"  !CDS_PN = "1";
DRAWING = "@baseboard_fab2_lib.baseboard_fab2(sch_1):page185";
BODY = "CAP","I96": #LOCATION = "C8F7" !CDS_LOCATION = "C8F7" #SEC = "1" !CDS_SEC = "1";
"A":   PN = "1"  !CDS_PN = "1";
"B":   PN = "2"  !CDS_PN = "2";
BODY = "RES","I105": #LOCATION = "R8F18" !CDS_LOCATION = "R8F18" #SEC = "1" !CDS_SEC = "1";
"A":   PN = "1"  !CDS_PN = "1";
"B":   PN = "2"  !CDS_PN = "2";
BODY = "RES","I106": #LOCATION = "R8F21" !CDS_LOCATION = "R8F21" #SEC = "1" !CDS_SEC = "1";
"A":   PN = "1"  !CDS_PN = "1";
"B":   PN = "2"  !CDS_PN = "2";
BODY = "TTL1G07_A","I110": #LOCATION = "U2P1" !CDS_LOCATION = "U2P1" #SEC = "1" !CDS_SEC = "1";
"A":   PN = "2"  !CDS_PN = "2";
"Y":   PN = "4"  !CDS_PN = "4";
BODY = "RES","I111": #LOCATION = "R2P15" !CDS_LOCATION = "R2P15" #SEC = "1" !CDS_SEC = "1";
"A":   PN = "1"  !CDS_PN = "1";
"B":   PN = "2"  !CDS_PN = "2";
BODY = "RES","I113": #LOCATION = "R2P16" !CDS_LOCATION = "R2P16" #SEC = "1" !CDS_SEC = "1";
"A":   PN = "1"  !CDS_PN = "1";
"B":   PN = "2"  !CDS_PN = "2";
BODY = "RES","I115": #LOCATION = "R2P14" !CDS_LOCATION = "R2P14" #SEC = "1" !CDS_SEC = "1";
"A":   PN = "1"  !CDS_PN = "1";
"B":   PN = "2"  !CDS_PN = "2";
BODY = "CAP_A","I117": #LOCATION = "C2P9" !CDS_LOCATION = "C2P9" #SEC = "1" !CDS_SEC = "1";
"A":   PN = "1"  !CDS_PN = "1";
"B":   PN = "2"  !CDS_PN = "2";
BODY = "CAP_A","I120": #LOCATION = "C2T29" !CDS_LOCATION = "C2T29" #SEC = "1" !CDS_SEC = "1";
"A":   PN = "1"  !CDS_PN = "1";
"B":   PN = "2"  !CDS_PN = "2";
BODY = "CAP_A","I123": #LOCATION = "C2T26" !CDS_LOCATION = "C2T26" #SEC = "1" !CDS_SEC = "1";
"A":   PN = "1"  !CDS_PN = "1";
"B":   PN = "2"  !CDS_PN = "2";
BODY = "CAP_A","I124": #LOCATION = "C2T21" !CDS_LOCATION = "C2T21" #SEC = "1" !CDS_SEC = "1";
"A":   PN = "1"  !CDS_PN = "1";
"B":   PN = "2"  !CDS_PN = "2";
BODY = "CAP_A","I126": #LOCATION = "C2T16" !CDS_LOCATION = "C2T16" #SEC = "1" !CDS_SEC = "1";
"A":   PN = "1"  !CDS_PN = "1";
"B":   PN = "2"  !CDS_PN = "2";
BODY = "CAP_A","I127": #LOCATION = "C2T15" !CDS_LOCATION = "C2T15" #SEC = "1" !CDS_SEC = "1";
"A":   PN = "1"  !CDS_PN = "1";
"B":   PN = "2"  !CDS_PN = "2";
BODY = "CAP_A","I129": #LOCATION = "C2T24" !CDS_LOCATION = "C2T24" #SEC = "1" !CDS_SEC = "1";
"A":   PN = "1"  !CDS_PN = "1";
"B":   PN = "2"  !CDS_PN = "2";
BODY = "CAP_A","I131": #LOCATION = "C2T2" !CDS_LOCATION = "C2T2" #SEC = "1" !CDS_SEC = "1";
"A":   PN = "1"  !CDS_PN = "1";
"B":   PN = "2"  !CDS_PN = "2";
BODY = "CAP_A","I132": #LOCATION = "C2T4" !CDS_LOCATION = "C2T4" #SEC = "1" !CDS_SEC = "1";
"A":   PN = "1"  !CDS_PN = "1";
"B":   PN = "2"  !CDS_PN = "2";
BODY = "CAP_A","I135": #LOCATION = "C2T5" !CDS_LOCATION = "C2T5" #SEC = "1" !CDS_SEC = "1";
"A":   PN = "1"  !CDS_PN = "1";
"B":   PN = "2"  !CDS_PN = "2";
BODY = "RES","I136": #LOCATION = "R8F36" !CDS_LOCATION = "R8F36" #SEC = "1" !CDS_SEC = "1";
"A":   PN = "1"  !CDS_PN = "1";
"B":   PN = "2"  !CDS_PN = "2";
BODY = "CAP_A","I138": #LOCATION = "C8F6" !CDS_LOCATION = "C8F6" #SEC = "1" !CDS_SEC = "1";
"A":   PN = "1"  !CDS_PN = "1";
"B":   PN = "2"  !CDS_PN = "2";
BODY = "CAP_A","I139": #LOCATION = "C8F11" !CDS_LOCATION = "C8F11" #SEC = "1" !CDS_SEC = "1";
"A":   PN = "1"  !CDS_PN = "1";
"B":   PN = "2"  !CDS_PN = "2";
BODY = "CAP","I140": #LOCATION = "C8F12" !CDS_LOCATION = "C8F12" #SEC = "1" !CDS_SEC = "1";
"A":   PN = "1"  !CDS_PN = "1";
"B":   PN = "2"  !CDS_PN = "2";
BODY = "CAP_A","I141": #LOCATION = "C8F13" !CDS_LOCATION = "C8F13" #SEC = "1" !CDS_SEC = "1";
"A":   PN = "1"  !CDS_PN = "1";
"B":   PN = "2"  !CDS_PN = "2";
BODY = "CAP_A","I142": #LOCATION = "C8F15" !CDS_LOCATION = "C8F15" #SEC = "1" !CDS_SEC = "1";
"A":   PN = "1"  !CDS_PN = "1";
"B":   PN = "2"  !CDS_PN = "2";
BODY = "SKT-MINI67P-41-GP","I143": #LOCATION = "J8F1" !CDS_LOCATION = "J8F1" #SEC = "1" !CDS_SEC = "1";
"1":   PN = "1"  !CDS_PN = "1";
"2":   PN = "2"  !CDS_PN = "2";
"3":   PN = "3"  !CDS_PN = "3";
"4":   PN = "4"  !CDS_PN = "4";
"5":   PN = "5"  !CDS_PN = "5";
"6":   PN = "6"  !CDS_PN = "6";
"7":   PN = "7"  !CDS_PN = "7";
"8":   PN = "8"  !CDS_PN = "8";
"9":   PN = "9"  !CDS_PN = "9";
"10":   PN = "10"  !CDS_PN = "10";
"11":   PN = "11"  !CDS_PN = "11";
"12":   PN = "12"  !CDS_PN = "12";
"13":   PN = "13"  !CDS_PN = "13";
"14":   PN = "14"  !CDS_PN = "14";
"15":   PN = "15"  !CDS_PN = "15";
"16":   PN = "16"  !CDS_PN = "16";
"17":   PN = "17"  !CDS_PN = "17";
"18":   PN = "18"  !CDS_PN = "18";
"19":   PN = "19"  !CDS_PN = "19";
"20":   PN = "20"  !CDS_PN = "20";
"21":   PN = "21"  !CDS_PN = "21";
"22":   PN = "22"  !CDS_PN = "22";
"23":   PN = "23"  !CDS_PN = "23";
"24":   PN = "24"  !CDS_PN = "24";
"25":   PN = "25"  !CDS_PN = "25";
"26":   PN = "26"  !CDS_PN = "26";
"27":   PN = "27"  !CDS_PN = "27";
"28":   PN = "28"  !CDS_PN = "28";
"29":   PN = "29"  !CDS_PN = "29";
"30":   PN = "30"  !CDS_PN = "30";
"31":   PN = "31"  !CDS_PN = "31";
"32":   PN = "32"  !CDS_PN = "32";
"33":   PN = "33"  !CDS_PN = "33";
"34":   PN = "34"  !CDS_PN = "34";
"35":   PN = "35"  !CDS_PN = "35";
"36":   PN = "36"  !CDS_PN = "36";
"37":   PN = "37"  !CDS_PN = "37";
"38":   PN = "38"  !CDS_PN = "38";
"39":   PN = "39"  !CDS_PN = "39";
"40":   PN = "40"  !CDS_PN = "40";
"41":   PN = "41"  !CDS_PN = "41";
"42":   PN = "42"  !CDS_PN = "42";
"43":   PN = "43"  !CDS_PN = "43";
"44":   PN = "44"  !CDS_PN = "44";
"45":   PN = "45"  !CDS_PN = "45";
"46":   PN = "46"  !CDS_PN = "46";
"47":   PN = "47"  !CDS_PN = "47";
"48":   PN = "48"  !CDS_PN = "48";
"49":   PN = "49"  !CDS_PN = "49";
"50":   PN = "50"  !CDS_PN = "50";
"51":   PN = "51"  !CDS_PN = "51";
"52":   PN = "52"  !CDS_PN = "52";
"53":   PN = "53"  !CDS_PN = "53";
"54":   PN = "54"  !CDS_PN = "54";
"55":   PN = "55"  !CDS_PN = "55";
"56":   PN = "56"  !CDS_PN = "56";
"57":   PN = "57"  !CDS_PN = "57";
"58":   PN = "58"  !CDS_PN = "58";
"67":   PN = "67"  !CDS_PN = "67";
"68":   PN = "68"  !CDS_PN = "68";
"69":   PN = "69"  !CDS_PN = "69";
"70":   PN = "70"  !CDS_PN = "70";
"71":   PN = "71"  !CDS_PN = "71";
"72":   PN = "72"  !CDS_PN = "72";
"73":   PN = "73"  !CDS_PN = "73";
"74":   PN = "74"  !CDS_PN = "74";
"75":   PN = "75"  !CDS_PN = "75";
"76":   PN = "76"  !CDS_PN = "76";
"77":   PN = "77"  !CDS_PN = "77";
"NP1":   PN = "NP1"  !CDS_PN = "NP1";
"NP2":   PN = "NP2"  !CDS_PN = "NP2";
BODY = "CAP","I167": #LOCATION = "C2T11" !CDS_LOCATION = "C2T11" #SEC = "1" !CDS_SEC = "1";
"A":   PN = "1"  !CDS_PN = "1";
"B":   PN = "2"  !CDS_PN = "2";
BODY = "CAP","I168": #LOCATION = "C2T10" !CDS_LOCATION = "C2T10" #SEC = "1" !CDS_SEC = "1";
"A":   PN = "1"  !CDS_PN = "1";
"B":   PN = "2"  !CDS_PN = "2";
BODY = "CAP","I171": #LOCATION = "C2T14" !CDS_LOCATION = "C2T14" #SEC = "1" !CDS_SEC = "1";
"A":   PN = "1"  !CDS_PN = "1";
"B":   PN = "2"  !CDS_PN = "2";
BODY = "CAP","I172": #LOCATION = "C2T13" !CDS_LOCATION = "C2T13" #SEC = "1" !CDS_SEC = "1";
"A":   PN = "1"  !CDS_PN = "1";
"B":   PN = "2"  !CDS_PN = "2";
BODY = "CAP","I179": #LOCATION = "C2T20" !CDS_LOCATION = "C2T20" #SEC = "1" !CDS_SEC = "1";
"A":   PN = "1"  !CDS_PN = "1";
"B":   PN = "2"  !CDS_PN = "2";
BODY = "CAP","I180": #LOCATION = "C2T23" !CDS_LOCATION = "C2T23" #SEC = "1" !CDS_SEC = "1";
"A":   PN = "1"  !CDS_PN = "1";
"B":   PN = "2"  !CDS_PN = "2";
BODY = "RES","I183": #LOCATION = "R32W10" !CDS_LOCATION = "R32W10" #SEC = "1" !CDS_SEC = "1";
"A":   PN = "1"  !CDS_PN = "1";
"B":   PN = "2"  !CDS_PN = "2";
BODY = "RES","I184": #LOCATION = "R32W11" !CDS_LOCATION = "R32W11" #SEC = "1" !CDS_SEC = "1";
"A":   PN = "1"  !CDS_PN = "1";
"B":   PN = "2"  !CDS_PN = "2";
BODY = "RES","I187": #LOCATION = "R32W12" !CDS_LOCATION = "R32W12" #SEC = "1" !CDS_SEC = "1";
"A":   PN = "1"  !CDS_PN = "1";
"B":   PN = "2"  !CDS_PN = "2";
BODY = "CAP_A","I188": #LOCATION = "C32W1" !CDS_LOCATION = "C32W1" #SEC = "1" !CDS_SEC = "1";
"A":   PN = "1"  !CDS_PN = "1";
"B":   PN = "2"  !CDS_PN = "2";
BODY = "CAP_A","I190": #LOCATION = "C32W3" !CDS_LOCATION = "C32W3" #SEC = "1" !CDS_SEC = "1";
"A":   PN = "1"  !CDS_PN = "1";
"B":   PN = "2"  !CDS_PN = "2";
BODY = "TCA9517DGKR-GP","I191": #LOCATION = "U32W1" !CDS_LOCATION = "U32W1" #SEC = "1" !CDS_SEC = "1";
"EN":   PN = "5"  !CDS_PN = "5";
"GND":   PN = "4"  !CDS_PN = "4";
"SCLA":   PN = "2"  !CDS_PN = "2";
"SCLB":   PN = "7"  !CDS_PN = "7";
"SDAA":   PN = "3"  !CDS_PN = "3";
"SDAB":   PN = "6"  !CDS_PN = "6";
"VCCA":   PN = "1"  !CDS_PN = "1";
"VCCB":   PN = "8"  !CDS_PN = "8";
BODY = "CAP_A","I193": #LOCATION = "C32W2" !CDS_LOCATION = "C32W2" #SEC = "1" !CDS_SEC = "1";
"A":   PN = "1"  !CDS_PN = "1";
"B":   PN = "2"  !CDS_PN = "2";
BODY = "CAP_A","I196": #LOCATION = "C32W4" !CDS_LOCATION = "C32W4" #SEC = "1" !CDS_SEC = "1";
"A":   PN = "1"  !CDS_PN = "1";
"B":   PN = "2"  !CDS_PN = "2";
BODY = "RES","I200": #LOCATION = "R32W9" !CDS_LOCATION = "R32W9" #SEC = "1" !CDS_SEC = "1";
"A":   PN = "1"  !CDS_PN = "1";
"B":   PN = "2"  !CDS_PN = "2";
BODY = "TCA9517DGKR-GP","I204": #LOCATION = "U32W2" !CDS_LOCATION = "U32W2" #SEC = "1" !CDS_SEC = "1";
"EN":   PN = "5"  !CDS_PN = "5";
"GND":   PN = "4"  !CDS_PN = "4";
"SCLA":   PN = "2"  !CDS_PN = "2";
"SCLB":   PN = "7"  !CDS_PN = "7";
"SDAA":   PN = "3"  !CDS_PN = "3";
"SDAB":   PN = "6"  !CDS_PN = "6";
"VCCA":   PN = "1"  !CDS_PN = "1";
"VCCB":   PN = "8"  !CDS_PN = "8";
BODY = "RES","I206": #LOCATION = "R32W3" !CDS_LOCATION = "R32W3" #SEC = "1" !CDS_SEC = "1";
"A":   PN = "1"  !CDS_PN = "1";
"B":   PN = "2"  !CDS_PN = "2";
BODY = "RES","I207": #LOCATION = "R32W2" !CDS_LOCATION = "R32W2" #SEC = "1" !CDS_SEC = "1";
"A":   PN = "1"  !CDS_PN = "1";
"B":   PN = "2"  !CDS_PN = "2";
BODY = "RES","I208": #LOCATION = "R32W1" !CDS_LOCATION = "R32W1" #SEC = "1" !CDS_SEC = "1";
"A":   PN = "1"  !CDS_PN = "1";
"B":   PN = "2"  !CDS_PN = "2";
BODY = "RES","I211": #LOCATION = "R32W4" !CDS_LOCATION = "R32W4" #SEC = "1" !CDS_SEC = "1";
"A":   PN = "1"  !CDS_PN = "1";
"B":   PN = "2"  !CDS_PN = "2";
BODY = "LMV431AIMFX-GP","I213": #LOCATION = "VR32W1" !CDS_LOCATION = "VR32W1" #SEC = "1" !CDS_SEC = "1";
"ANODE":   PN = "3"  !CDS_PN = "3";
"CATHODE":   PN = "2"  !CDS_PN = "2";
"REF":   PN = "1"  !CDS_PN = "1";
BODY = "RES","I214": #LOCATION = "R32W6" !CDS_LOCATION = "R32W6" #SEC = "1" !CDS_SEC = "1";
"A":   PN = "1"  !CDS_PN = "1";
"B":   PN = "2"  !CDS_PN = "2";
BODY = "RES","I215": #LOCATION = "R32W7" !CDS_LOCATION = "R32W7" #SEC = "1" !CDS_SEC = "1";
"A":   PN = "1"  !CDS_PN = "1";
"B":   PN = "2"  !CDS_PN = "2";
BODY = "RES","I216": #LOCATION = "R32W5" !CDS_LOCATION = "R32W5" #SEC = "1" !CDS_SEC = "1";
"A":   PN = "1"  !CDS_PN = "1";
"B":   PN = "2"  !CDS_PN = "2";
BODY = "CAP","I217": #LOCATION = "C32W5" !CDS_LOCATION = "C32W5" #SEC = "1" !CDS_SEC = "1";
"A":   PN = "1"  !CDS_PN = "1";
"B":   PN = "2"  !CDS_PN = "2";
DRAWING = "@baseboard_fab2_lib.baseboard_fab2(sch_1):page186";
BODY = "CAP","I3": #LOCATION = "C1M27" !CDS_LOCATION = "C1M27" #SEC = "1" !CDS_SEC = "1";
"A":   PN = "1"  !CDS_PN = "1";
"B":   PN = "2"  !CDS_PN = "2";
BODY = "CAP","I6": #LOCATION = "C1M26" !CDS_LOCATION = "C1M26" #SEC = "1" !CDS_SEC = "1";
"A":   PN = "1"  !CDS_PN = "1";
"B":   PN = "2"  !CDS_PN = "2";
BODY = "CAP_A","I7": #LOCATION = "C1M23" !CDS_LOCATION = "C1M23" #SEC = "1" !CDS_SEC = "1";
"A":   PN = "1"  !CDS_PN = "1";
"B":   PN = "2"  !CDS_PN = "2";
BODY = "CAP_A","I8": #LOCATION = "C1M22" !CDS_LOCATION = "C1M22" #SEC = "1" !CDS_SEC = "1";
"A":   PN = "1"  !CDS_PN = "1";
"B":   PN = "2"  !CDS_PN = "2";
BODY = "CAP_A","I10": #LOCATION = "C1M24" !CDS_LOCATION = "C1M24" #SEC = "1" !CDS_SEC = "1";
"A":   PN = "1"  !CDS_PN = "1";
"B":   PN = "2"  !CDS_PN = "2";
BODY = "RES","I220": #LOCATION = "R1M14" !CDS_LOCATION = "R1M14" #SEC = "1" !CDS_SEC = "1";
"A":   PN = "1"  !CDS_PN = "1";
"B":   PN = "2"  !CDS_PN = "2";
BODY = "CAP_A","I270": #LOCATION = "C1M20" !CDS_LOCATION = "C1M20" #SEC = "1" !CDS_SEC = "1";
"A":   PN = "1"  !CDS_PN = "1";
"B":   PN = "2"  !CDS_PN = "2";
BODY = "CAP_A","I334": #LOCATION = "C1M21" !CDS_LOCATION = "C1M21" #SEC = "1" !CDS_SEC = "1";
"A":   PN = "1"  !CDS_PN = "1";
"B":   PN = "2"  !CDS_PN = "2";
BODY = "CAP_A","I335": #LOCATION = "C1M25" !CDS_LOCATION = "C1M25" #SEC = "1" !CDS_SEC = "1";
"A":   PN = "1"  !CDS_PN = "1";
"B":   PN = "2"  !CDS_PN = "2";
BODY = "SCONN120_A28699018","I336": #LOCATION = "J9B3" !CDS_LOCATION = "J9B3" #SEC = "1" !CDS_SEC = "1";
"IO1":   PN = "1"  !CDS_PN = "1";
"IO2":   PN = "2"  !CDS_PN = "2";
"IO3":   PN = "3"  !CDS_PN = "3";
"IO4":   PN = "4"  !CDS_PN = "4";
"IO5":   PN = "5"  !CDS_PN = "5";
"IO6":   PN = "6"  !CDS_PN = "6";
"IO7":   PN = "7"  !CDS_PN = "7";
"IO8":   PN = "8"  !CDS_PN = "8";
"IO9":   PN = "9"  !CDS_PN = "9";
"IO10":   PN = "10"  !CDS_PN = "10";
"IO11":   PN = "11"  !CDS_PN = "11";
"IO12":   PN = "12"  !CDS_PN = "12";
"IO13":   PN = "13"  !CDS_PN = "13";
"IO14":   PN = "14"  !CDS_PN = "14";
"IO15":   PN = "15"  !CDS_PN = "15";
"IO16":   PN = "16"  !CDS_PN = "16";
"IO17":   PN = "17"  !CDS_PN = "17";
"IO18":   PN = "18"  !CDS_PN = "18";
"IO19":   PN = "19"  !CDS_PN = "19";
"IO20":   PN = "20"  !CDS_PN = "20";
"IO21":   PN = "21"  !CDS_PN = "21";
"IO22":   PN = "22"  !CDS_PN = "22";
"IO23":   PN = "23"  !CDS_PN = "23";
"IO24":   PN = "24"  !CDS_PN = "24";
"IO25":   PN = "25"  !CDS_PN = "25";
"IO26":   PN = "26"  !CDS_PN = "26";
"IO27":   PN = "27"  !CDS_PN = "27";
"IO28":   PN = "28"  !CDS_PN = "28";
"IO29":   PN = "29"  !CDS_PN = "29";
"IO30":   PN = "30"  !CDS_PN = "30";
"IO31":   PN = "31"  !CDS_PN = "31";
"IO32":   PN = "32"  !CDS_PN = "32";
"IO33":   PN = "33"  !CDS_PN = "33";
"IO34":   PN = "34"  !CDS_PN = "34";
"IO35":   PN = "35"  !CDS_PN = "35";
"IO36":   PN = "36"  !CDS_PN = "36";
"IO37":   PN = "37"  !CDS_PN = "37";
"IO38":   PN = "38"  !CDS_PN = "38";
"IO39":   PN = "39"  !CDS_PN = "39";
"IO40":   PN = "40"  !CDS_PN = "40";
"IO41":   PN = "41"  !CDS_PN = "41";
"IO42":   PN = "42"  !CDS_PN = "42";
"IO43":   PN = "43"  !CDS_PN = "43";
"IO44":   PN = "44"  !CDS_PN = "44";
"IO45":   PN = "45"  !CDS_PN = "45";
"IO46":   PN = "46"  !CDS_PN = "46";
"IO47":   PN = "47"  !CDS_PN = "47";
"IO48":   PN = "48"  !CDS_PN = "48";
"IO49":   PN = "49"  !CDS_PN = "49";
"IO50":   PN = "50"  !CDS_PN = "50";
"IO51":   PN = "51"  !CDS_PN = "51";
"IO52":   PN = "52"  !CDS_PN = "52";
"IO53":   PN = "53"  !CDS_PN = "53";
"IO54":   PN = "54"  !CDS_PN = "54";
"IO55":   PN = "55"  !CDS_PN = "55";
"IO56":   PN = "56"  !CDS_PN = "56";
"IO57":   PN = "57"  !CDS_PN = "57";
"IO58":   PN = "58"  !CDS_PN = "58";
"IO59":   PN = "59"  !CDS_PN = "59";
"IO60":   PN = "60"  !CDS_PN = "60";
"IO61":   PN = "61"  !CDS_PN = "61";
"IO62":   PN = "62"  !CDS_PN = "62";
"IO63":   PN = "63"  !CDS_PN = "63";
"IO64":   PN = "64"  !CDS_PN = "64";
"IO65":   PN = "65"  !CDS_PN = "65";
"IO66":   PN = "66"  !CDS_PN = "66";
"IO67":   PN = "67"  !CDS_PN = "67";
"IO68":   PN = "68"  !CDS_PN = "68";
"IO69":   PN = "69"  !CDS_PN = "69";
"IO70":   PN = "70"  !CDS_PN = "70";
"IO71":   PN = "71"  !CDS_PN = "71";
"IO72":   PN = "72"  !CDS_PN = "72";
"IO73":   PN = "73"  !CDS_PN = "73";
"IO74":   PN = "74"  !CDS_PN = "74";
"IO75":   PN = "75"  !CDS_PN = "75";
"IO76":   PN = "76"  !CDS_PN = "76";
"IO77":   PN = "77"  !CDS_PN = "77";
"IO78":   PN = "78"  !CDS_PN = "78";
"IO79":   PN = "79"  !CDS_PN = "79";
"IO80":   PN = "80"  !CDS_PN = "80";
"IO81":   PN = "81"  !CDS_PN = "81";
"IO82":   PN = "82"  !CDS_PN = "82";
"IO83":   PN = "83"  !CDS_PN = "83";
"IO84":   PN = "84"  !CDS_PN = "84";
"IO85":   PN = "85"  !CDS_PN = "85";
"IO86":   PN = "86"  !CDS_PN = "86";
"IO87":   PN = "87"  !CDS_PN = "87";
"IO88":   PN = "88"  !CDS_PN = "88";
"IO89":   PN = "89"  !CDS_PN = "89";
"IO90":   PN = "90"  !CDS_PN = "90";
"IO91":   PN = "91"  !CDS_PN = "91";
"IO92":   PN = "92"  !CDS_PN = "92";
"IO93":   PN = "93"  !CDS_PN = "93";
"IO94":   PN = "94"  !CDS_PN = "94";
"IO95":   PN = "95"  !CDS_PN = "95";
"IO96":   PN = "96"  !CDS_PN = "96";
"IO97":   PN = "97"  !CDS_PN = "97";
"IO98":   PN = "98"  !CDS_PN = "98";
"IO99":   PN = "99"  !CDS_PN = "99";
"IO100":   PN = "100"  !CDS_PN = "100";
"IO101":   PN = "101"  !CDS_PN = "101";
"IO102":   PN = "102"  !CDS_PN = "102";
"IO103":   PN = "103"  !CDS_PN = "103";
"IO104":   PN = "104"  !CDS_PN = "104";
"IO105":   PN = "105"  !CDS_PN = "105";
"IO106":   PN = "106"  !CDS_PN = "106";
"IO107":   PN = "107"  !CDS_PN = "107";
"IO108":   PN = "108"  !CDS_PN = "108";
"IO109":   PN = "109"  !CDS_PN = "109";
"IO110":   PN = "110"  !CDS_PN = "110";
"IO111":   PN = "111"  !CDS_PN = "111";
"IO112":   PN = "112"  !CDS_PN = "112";
"IO113":   PN = "113"  !CDS_PN = "113";
"IO114":   PN = "114"  !CDS_PN = "114";
"IO115":   PN = "115"  !CDS_PN = "115";
"IO116":   PN = "116"  !CDS_PN = "116";
"IO117":   PN = "117"  !CDS_PN = "117";
"IO118":   PN = "118"  !CDS_PN = "118";
"IO119":   PN = "119"  !CDS_PN = "119";
"IO120":   PN = "120"  !CDS_PN = "120";
BODY = "RES","I337": #LOCATION = "R1M16" !CDS_LOCATION = "R1M16" #SEC = "1" !CDS_SEC = "1";
"A":   PN = "1"  !CDS_PN = "1";
"B":   PN = "2"  !CDS_PN = "2";
BODY = "RES","I338": #LOCATION = "R1M17" !CDS_LOCATION = "R1M17" #SEC = "1" !CDS_SEC = "1";
"A":   PN = "1"  !CDS_PN = "1";
"B":   PN = "2"  !CDS_PN = "2";
BODY = "RES","I339": #LOCATION = "R1M15" !CDS_LOCATION = "R1M15" #SEC = "1" !CDS_SEC = "1";
"A":   PN = "1"  !CDS_PN = "1";
"B":   PN = "2"  !CDS_PN = "2";
BODY = "RES","I340": #LOCATION = "R1M18" !CDS_LOCATION = "R1M18" #SEC = "1" !CDS_SEC = "1";
"A":   PN = "1"  !CDS_PN = "1";
"B":   PN = "2"  !CDS_PN = "2";
BODY = "CAP_A","I345": #LOCATION = "C9B10" !CDS_LOCATION = "C9B10" #SEC = "1" !CDS_SEC = "1";
"A":   PN = "1"  !CDS_PN = "1";
"B":   PN = "2"  !CDS_PN = "2";
BODY = "RES","I356": #LOCATION = "R9W1" !CDS_LOCATION = "R9W1" #SEC = "1" !CDS_SEC = "1";
"A":   PN = "1"  !CDS_PN = "1";
"B":   PN = "2"  !CDS_PN = "2";
BODY = "SC1U10V2KX-4-GP","I357": #LOCATION = "C9B9" !CDS_LOCATION = "C9B9" #SEC = "1" !CDS_SEC = "1";
"1":   PN = "1"  !CDS_PN = "1";
"2":   PN = "2"  !CDS_PN = "2";
BODY = "887R2F-L-GP","I358": #LOCATION = "R9B7" !CDS_LOCATION = "R9B7" #SEC = "1" !CDS_SEC = "1";
"1":   PN = "1"  !CDS_PN = "1";
"2":   PN = "2"  !CDS_PN = "2";
DRAWING = "@baseboard_fab2_lib.baseboard_fab2(sch_1):page187";
BODY = "SCONN80_E67482007","I119": #LOCATION = "J8E3" !CDS_LOCATION = "J8E3" #SEC = "1" !CDS_SEC = "1";
"IO1":   PN = "1"  !CDS_PN = "1";
"IO2":   PN = "2"  !CDS_PN = "2";
"IO3":   PN = "3"  !CDS_PN = "3";
"IO4":   PN = "4"  !CDS_PN = "4";
"IO5":   PN = "5"  !CDS_PN = "5";
"IO6":   PN = "6"  !CDS_PN = "6";
"IO7":   PN = "7"  !CDS_PN = "7";
"IO8":   PN = "8"  !CDS_PN = "8";
"IO9":   PN = "9"  !CDS_PN = "9";
"IO10":   PN = "10"  !CDS_PN = "10";
"IO11":   PN = "11"  !CDS_PN = "11";
"IO12":   PN = "12"  !CDS_PN = "12";
"IO13":   PN = "13"  !CDS_PN = "13";
"IO14":   PN = "14"  !CDS_PN = "14";
"IO15":   PN = "15"  !CDS_PN = "15";
"IO16":   PN = "16"  !CDS_PN = "16";
"IO17":   PN = "17"  !CDS_PN = "17";
"IO18":   PN = "18"  !CDS_PN = "18";
"IO19":   PN = "19"  !CDS_PN = "19";
"IO20":   PN = "20"  !CDS_PN = "20";
"IO21":   PN = "21"  !CDS_PN = "21";
"IO22":   PN = "22"  !CDS_PN = "22";
"IO23":   PN = "23"  !CDS_PN = "23";
"IO24":   PN = "24"  !CDS_PN = "24";
"IO25":   PN = "25"  !CDS_PN = "25";
"IO26":   PN = "26"  !CDS_PN = "26";
"IO27":   PN = "27"  !CDS_PN = "27";
"IO28":   PN = "28"  !CDS_PN = "28";
"IO29":   PN = "29"  !CDS_PN = "29";
"IO30":   PN = "30"  !CDS_PN = "30";
"IO31":   PN = "31"  !CDS_PN = "31";
"IO32":   PN = "32"  !CDS_PN = "32";
"IO33":   PN = "33"  !CDS_PN = "33";
"IO34":   PN = "34"  !CDS_PN = "34";
"IO35":   PN = "35"  !CDS_PN = "35";
"IO36":   PN = "36"  !CDS_PN = "36";
"IO37":   PN = "37"  !CDS_PN = "37";
"IO38":   PN = "38"  !CDS_PN = "38";
"IO39":   PN = "39"  !CDS_PN = "39";
"IO40":   PN = "40"  !CDS_PN = "40";
"IO41":   PN = "41"  !CDS_PN = "41";
"IO42":   PN = "42"  !CDS_PN = "42";
"IO43":   PN = "43"  !CDS_PN = "43";
"IO44":   PN = "44"  !CDS_PN = "44";
"IO45":   PN = "45"  !CDS_PN = "45";
"IO46":   PN = "46"  !CDS_PN = "46";
"IO47":   PN = "47"  !CDS_PN = "47";
"IO48":   PN = "48"  !CDS_PN = "48";
"IO49":   PN = "49"  !CDS_PN = "49";
"IO50":   PN = "50"  !CDS_PN = "50";
"IO51":   PN = "51"  !CDS_PN = "51";
"IO52":   PN = "52"  !CDS_PN = "52";
"IO53":   PN = "53"  !CDS_PN = "53";
"IO54":   PN = "54"  !CDS_PN = "54";
"IO55":   PN = "55"  !CDS_PN = "55";
"IO56":   PN = "56"  !CDS_PN = "56";
"IO57":   PN = "57"  !CDS_PN = "57";
"IO58":   PN = "58"  !CDS_PN = "58";
"IO59":   PN = "59"  !CDS_PN = "59";
"IO60":   PN = "60"  !CDS_PN = "60";
"IO61":   PN = "61"  !CDS_PN = "61";
"IO62":   PN = "62"  !CDS_PN = "62";
"IO63":   PN = "63"  !CDS_PN = "63";
"IO64":   PN = "64"  !CDS_PN = "64";
"IO65":   PN = "65"  !CDS_PN = "65";
"IO66":   PN = "66"  !CDS_PN = "66";
"IO67":   PN = "67"  !CDS_PN = "67";
"IO68":   PN = "68"  !CDS_PN = "68";
"IO69":   PN = "69"  !CDS_PN = "69";
"IO70":   PN = "70"  !CDS_PN = "70";
"IO71":   PN = "71"  !CDS_PN = "71";
"IO72":   PN = "72"  !CDS_PN = "72";
"IO73":   PN = "73"  !CDS_PN = "73";
"IO74":   PN = "74"  !CDS_PN = "74";
"IO75":   PN = "75"  !CDS_PN = "75";
"IO76":   PN = "76"  !CDS_PN = "76";
"IO77":   PN = "77"  !CDS_PN = "77";
"IO78":   PN = "78"  !CDS_PN = "78";
"IO79":   PN = "79"  !CDS_PN = "79";
"IO80":   PN = "80"  !CDS_PN = "80";
BODY = "RES","I145": #LOCATION = "R9E10" !CDS_LOCATION = "R9E10" #SEC = "1" !CDS_SEC = "1";
"A":   PN = "1"  !CDS_PN = "1";
"B":   PN = "2"  !CDS_PN = "2";
BODY = "RES","I150": #LOCATION = "R9E11" !CDS_LOCATION = "R9E11" #SEC = "1" !CDS_SEC = "1";
"A":   PN = "1"  !CDS_PN = "1";
"B":   PN = "2"  !CDS_PN = "2";
BODY = "RES","I153": #LOCATION = "R9E12" !CDS_LOCATION = "R9E12" #SEC = "1" !CDS_SEC = "1";
"A":   PN = "1"  !CDS_PN = "1";
"B":   PN = "2"  !CDS_PN = "2";
BODY = "RES","I174": #LOCATION = "R2W1" !CDS_LOCATION = "R2W1" #SEC = "1" !CDS_SEC = "1";
"A":   PN = "1"  !CDS_PN = "1";
"B":   PN = "2"  !CDS_PN = "2";
BODY = "887R2F-L-GP","I175": #LOCATION = "R2R8" !CDS_LOCATION = "R2R8" #SEC = "1" !CDS_SEC = "1";
"1":   PN = "1"  !CDS_PN = "1";
"2":   PN = "2"  !CDS_PN = "2";
DRAWING = "@baseboard_fab2_lib.baseboard_fab2(sch_1):page188";
BODY = "CAP_A","I2": #LOCATION = "C2R15" !CDS_LOCATION = "C2R15" #SEC = "1" !CDS_SEC = "1";
"A":   PN = "1"  !CDS_PN = "1";
"B":   PN = "2"  !CDS_PN = "2";
BODY = "CAP_A","I3": #LOCATION = "C2R18" !CDS_LOCATION = "C2R18" &SEC = "1" #&CDS_SEC = "1";
"A":   PN = "1"  !CDS_PN = "1";
"B":   PN = "2"  !CDS_PN = "2";
BODY = "CAP_A","I21": #LOCATION = "C2P11" !CDS_LOCATION = "C2P11" #SEC = "1" !CDS_SEC = "1";
"A":   PN = "1"  !CDS_PN = "1";
"B":   PN = "2"  !CDS_PN = "2";
BODY = "CAP_A","I23": #LOCATION = "C2P12" !CDS_LOCATION = "C2P12" #SEC = "1" !CDS_SEC = "1";
"A":   PN = "1"  !CDS_PN = "1";
"B":   PN = "2"  !CDS_PN = "2";
BODY = "CAP_A","I25": #LOCATION = "C2R17" !CDS_LOCATION = "C2R17" &SEC = "1" #&CDS_SEC = "1";
"A":   PN = "1"  !CDS_PN = "1";
"B":   PN = "2"  !CDS_PN = "2";
BODY = "SCONN64_H87568002_A","I27": #LOCATION = "J8E4" !CDS_LOCATION = "J8E4" #SEC = "1" !CDS_SEC = "1";
"IO1":   PN = "1"  !CDS_PN = "1";
"IO2":   PN = "2"  !CDS_PN = "2";
"IO3":   PN = "3"  !CDS_PN = "3";
"IO4":   PN = "4"  !CDS_PN = "4";
"IO5":   PN = "5"  !CDS_PN = "5";
"IO6":   PN = "6"  !CDS_PN = "6";
"IO7":   PN = "7"  !CDS_PN = "7";
"IO8":   PN = "8"  !CDS_PN = "8";
"IO9":   PN = "9"  !CDS_PN = "9";
"IO10":   PN = "10"  !CDS_PN = "10";
"IO11":   PN = "11"  !CDS_PN = "11";
"IO12":   PN = "12"  !CDS_PN = "12";
"IO13":   PN = "13"  !CDS_PN = "13";
"IO14":   PN = "14"  !CDS_PN = "14";
"IO15":   PN = "15"  !CDS_PN = "15";
"IO16":   PN = "16"  !CDS_PN = "16";
"IO17":   PN = "17"  !CDS_PN = "17";
"IO18":   PN = "18"  !CDS_PN = "18";
"IO19":   PN = "19"  !CDS_PN = "19";
"IO20":   PN = "20"  !CDS_PN = "20";
"IO21":   PN = "21"  !CDS_PN = "21";
"IO22":   PN = "22"  !CDS_PN = "22";
"IO23":   PN = "23"  !CDS_PN = "23";
"IO24":   PN = "24"  !CDS_PN = "24";
"IO25":   PN = "25"  !CDS_PN = "25";
"IO26":   PN = "26"  !CDS_PN = "26";
"IO27":   PN = "27"  !CDS_PN = "27";
"IO28":   PN = "28"  !CDS_PN = "28";
"IO29":   PN = "29"  !CDS_PN = "29";
"IO30":   PN = "30"  !CDS_PN = "30";
"IO31":   PN = "31"  !CDS_PN = "31";
"IO32":   PN = "32"  !CDS_PN = "32";
"IO33":   PN = "33"  !CDS_PN = "33";
"IO34":   PN = "34"  !CDS_PN = "34";
"IO35":   PN = "35"  !CDS_PN = "35";
"IO36":   PN = "36"  !CDS_PN = "36";
"IO37":   PN = "37"  !CDS_PN = "37";
"IO38":   PN = "38"  !CDS_PN = "38";
"IO39":   PN = "39"  !CDS_PN = "39";
"IO40":   PN = "40"  !CDS_PN = "40";
"IO41":   PN = "41"  !CDS_PN = "41";
"IO42":   PN = "42"  !CDS_PN = "42";
"IO43":   PN = "43"  !CDS_PN = "43";
"IO44":   PN = "44"  !CDS_PN = "44";
"IO45":   PN = "45"  !CDS_PN = "45";
"IO46":   PN = "46"  !CDS_PN = "46";
"IO47":   PN = "47"  !CDS_PN = "47";
"IO48":   PN = "48"  !CDS_PN = "48";
"IO49":   PN = "49"  !CDS_PN = "49";
"IO50":   PN = "50"  !CDS_PN = "50";
"IO51":   PN = "51"  !CDS_PN = "51";
"IO52":   PN = "52"  !CDS_PN = "52";
"IO53":   PN = "53"  !CDS_PN = "53";
"IO54":   PN = "54"  !CDS_PN = "54";
"IO55":   PN = "55"  !CDS_PN = "55";
"IO56":   PN = "56"  !CDS_PN = "56";
"IO57":   PN = "57"  !CDS_PN = "57";
"IO58":   PN = "58"  !CDS_PN = "58";
"IO59":   PN = "59"  !CDS_PN = "59";
"IO60":   PN = "60"  !CDS_PN = "60";
"IO61":   PN = "61"  !CDS_PN = "61";
"IO62":   PN = "62"  !CDS_PN = "62";
"IO63":   PN = "63"  !CDS_PN = "63";
"IO64":   PN = "64"  !CDS_PN = "64";
BODY = "CAP_A","I40": #LOCATION = "C2R16" !CDS_LOCATION = "C2R16" &SEC = "1" #&CDS_SEC = "1";
"A":   PN = "1"  !CDS_PN = "1";
"B":   PN = "2"  !CDS_PN = "2";
BODY = "CAP","I41": #LOCATION = "C2P10" !CDS_LOCATION = "C2P10" #SEC = "1" !CDS_SEC = "1";
"A":   PN = "1"  !CDS_PN = "1";
"B":   PN = "2"  !CDS_PN = "2";
BODY = "CAP_A","I53": #LOCATION = "C2P16" !CDS_LOCATION = "C2P16" &SEC = "1" #&CDS_SEC = "1";
"A":   PN = "1"  !CDS_PN = "1";
"B":   PN = "2"  !CDS_PN = "2";
BODY = "CAP_A","I55": #LOCATION = "C2P15" !CDS_LOCATION = "C2P15" &SEC = "1" #&CDS_SEC = "1";
"A":   PN = "1"  !CDS_PN = "1";
"B":   PN = "2"  !CDS_PN = "2";
BODY = "CAP_A","I56": #LOCATION = "C2P14" !CDS_LOCATION = "C2P14" &SEC = "1" #&CDS_SEC = "1";
"A":   PN = "1"  !CDS_PN = "1";
"B":   PN = "2"  !CDS_PN = "2";
BODY = "CAP_A","I57": #LOCATION = "C2P13" !CDS_LOCATION = "C2P13" &SEC = "1" #&CDS_SEC = "1";
"A":   PN = "1"  !CDS_PN = "1";
"B":   PN = "2"  !CDS_PN = "2";
BODY = "CAP_A","I82": #LOCATION = "C8C15" !CDS_LOCATION = "C8C15" #SEC = "1" !CDS_SEC = "1";
"A":   PN = "1"  !CDS_PN = "1";
"B":   PN = "2"  !CDS_PN = "2";
BODY = "CAP_A","I86": #LOCATION = "C8C14" !CDS_LOCATION = "C8C14" #SEC = "1" !CDS_SEC = "1";
"A":   PN = "1"  !CDS_PN = "1";
"B":   PN = "2"  !CDS_PN = "2";
BODY = "RES","I88": #LOCATION = "R1R18" !CDS_LOCATION = "R1R18" #SEC = "1" !CDS_SEC = "1";
"A":   PN = "1"  !CDS_PN = "1";
"B":   PN = "2"  !CDS_PN = "2";
BODY = "RES","I89": #LOCATION = "R1R19" !CDS_LOCATION = "R1R19" #SEC = "1" !CDS_SEC = "1";
"A":   PN = "1"  !CDS_PN = "1";
"B":   PN = "2"  !CDS_PN = "2";
BODY = "RES","I90": #LOCATION = "R1R21" !CDS_LOCATION = "R1R21" #SEC = "1" !CDS_SEC = "1";
"A":   PN = "1"  !CDS_PN = "1";
"B":   PN = "2"  !CDS_PN = "2";
BODY = "RES","I91": #LOCATION = "R1R20" !CDS_LOCATION = "R1R20" #SEC = "1" !CDS_SEC = "1";
"A":   PN = "1"  !CDS_PN = "1";
"B":   PN = "2"  !CDS_PN = "2";
BODY = "RES","I92": #LOCATION = "R1R22" !CDS_LOCATION = "R1R22" #SEC = "1" !CDS_SEC = "1";
"A":   PN = "1"  !CDS_PN = "1";
"B":   PN = "2"  !CDS_PN = "2";
BODY = "RES","I93": #LOCATION = "R1R16" !CDS_LOCATION = "R1R16" #SEC = "1" !CDS_SEC = "1";
"A":   PN = "1"  !CDS_PN = "1";
"B":   PN = "2"  !CDS_PN = "2";
BODY = "RES","I94": #LOCATION = "R1R17" !CDS_LOCATION = "R1R17" #SEC = "1" !CDS_SEC = "1";
"A":   PN = "1"  !CDS_PN = "1";
"B":   PN = "2"  !CDS_PN = "2";
BODY = "RES","I95": #LOCATION = "R1R23" !CDS_LOCATION = "R1R23" #SEC = "1" !CDS_SEC = "1";
"A":   PN = "1"  !CDS_PN = "1";
"B":   PN = "2"  !CDS_PN = "2";
BODY = "CAP_A","I120": #LOCATION = "C8C13" !CDS_LOCATION = "C8C13" #SEC = "1" !CDS_SEC = "1";
"A":   PN = "1"  !CDS_PN = "1";
"B":   PN = "2"  !CDS_PN = "2";
BODY = "CAP_A","I121": #LOCATION = "C8C12" !CDS_LOCATION = "C8C12" #SEC = "1" !CDS_SEC = "1";
"A":   PN = "1"  !CDS_PN = "1";
"B":   PN = "2"  !CDS_PN = "2";
BODY = "RES","I128": #LOCATION = "R1W40" !CDS_LOCATION = "R1W40" #SEC = "1" !CDS_SEC = "1";
"A":   PN = "1"  !CDS_PN = "1";
"B":   PN = "2"  !CDS_PN = "2";
BODY = "RES","I129": #LOCATION = "R1W41" !CDS_LOCATION = "R1W41" #SEC = "1" !CDS_SEC = "1";
"A":   PN = "1"  !CDS_PN = "1";
"B":   PN = "2"  !CDS_PN = "2";
BODY = "RES","I131": #LOCATION = "R1W42" !CDS_LOCATION = "R1W42" #SEC = "1" !CDS_SEC = "1";
"A":   PN = "1"  !CDS_PN = "1";
"B":   PN = "2"  !CDS_PN = "2";
BODY = "RES","I132": #LOCATION = "R1W43" !CDS_LOCATION = "R1W43" #SEC = "1" !CDS_SEC = "1";
"A":   PN = "1"  !CDS_PN = "1";
"B":   PN = "2"  !CDS_PN = "2";
BODY = "RES","I133": #LOCATION = "R1W44" !CDS_LOCATION = "R1W44" #SEC = "1" !CDS_SEC = "1";
"A":   PN = "1"  !CDS_PN = "1";
"B":   PN = "2"  !CDS_PN = "2";
BODY = "RES","I134": #LOCATION = "R1W45" !CDS_LOCATION = "R1W45" #SEC = "1" !CDS_SEC = "1";
"A":   PN = "1"  !CDS_PN = "1";
"B":   PN = "2"  !CDS_PN = "2";
DRAWING = "@baseboard_fab2_lib.baseboard_fab2(sch_1):page189";
BODY = "RES","I7": #LOCATION = "R8G10" !CDS_LOCATION = "R8G10" #SEC = "1" !CDS_SEC = "1";
"A":   PN = "1"  !CDS_PN = "1";
"B":   PN = "2"  !CDS_PN = "2";
BODY = "RES","I8": #LOCATION = "R7G19" !CDS_LOCATION = "R7G19" #SEC = "1" !CDS_SEC = "1";
"A":   PN = "1"  !CDS_PN = "1";
"B":   PN = "2"  !CDS_PN = "2";
BODY = "RES","I9": #LOCATION = "R8G9" !CDS_LOCATION = "R8G9" &SEC = "1" #&CDS_SEC = "1";
"A":   PN = "1"  !CDS_PN = "1";
"B":   PN = "2"  !CDS_PN = "2";
BODY = "RES","I13": #LOCATION = "R7G18" !CDS_LOCATION = "R7G18" #SEC = "1" !CDS_SEC = "1";
"A":   PN = "1"  !CDS_PN = "1";
"B":   PN = "2"  !CDS_PN = "2";
BODY = "RES","I17": #LOCATION = "R8G8" !CDS_LOCATION = "R8G8" #SEC = "1" !CDS_SEC = "1";
"A":   PN = "1"  !CDS_PN = "1";
"B":   PN = "2"  !CDS_PN = "2";
BODY = "RES","I18": #LOCATION = "R8G7" !CDS_LOCATION = "R8G7" #SEC = "1" !CDS_SEC = "1";
"A":   PN = "1"  !CDS_PN = "1";
"B":   PN = "2"  !CDS_PN = "2";
BODY = "RES","I19": #LOCATION = "R8G11" !CDS_LOCATION = "R8G11" #SEC = "1" !CDS_SEC = "1";
"A":   PN = "1"  !CDS_PN = "1";
"B":   PN = "2"  !CDS_PN = "2";
BODY = "RES","I20": #LOCATION = "R8G14" !CDS_LOCATION = "R8G14" #SEC = "1" !CDS_SEC = "1";
"A":   PN = "1"  !CDS_PN = "1";
"B":   PN = "2"  !CDS_PN = "2";
BODY = "RES","I21": #LOCATION = "R8G12" !CDS_LOCATION = "R8G12" #SEC = "1" !CDS_SEC = "1";
"A":   PN = "1"  !CDS_PN = "1";
"B":   PN = "2"  !CDS_PN = "2";
BODY = "RES","I22": #LOCATION = "R8G16" !CDS_LOCATION = "R8G16" #SEC = "1" !CDS_SEC = "1";
"A":   PN = "1"  !CDS_PN = "1";
"B":   PN = "2"  !CDS_PN = "2";
BODY = "RES","I23": #LOCATION = "R8G13" !CDS_LOCATION = "R8G13" #SEC = "1" !CDS_SEC = "1";
"A":   PN = "1"  !CDS_PN = "1";
"B":   PN = "2"  !CDS_PN = "2";
BODY = "RES","I24": #LOCATION = "R8G15" !CDS_LOCATION = "R8G15" #SEC = "1" !CDS_SEC = "1";
"A":   PN = "1"  !CDS_PN = "1";
"B":   PN = "2"  !CDS_PN = "2";
BODY = "RES","I25": #LOCATION = "R8G17" !CDS_LOCATION = "R8G17" #SEC = "1" !CDS_SEC = "1";
"A":   PN = "1"  !CDS_PN = "1";
"B":   PN = "2"  !CDS_PN = "2";
BODY = "RES","I26": #LOCATION = "R8G18" !CDS_LOCATION = "R8G18" #SEC = "1" !CDS_SEC = "1";
"A":   PN = "1"  !CDS_PN = "1";
"B":   PN = "2"  !CDS_PN = "2";
BODY = "RES","I27": #LOCATION = "R7G16" !CDS_LOCATION = "R7G16" #SEC = "1" !CDS_SEC = "1";
"A":   PN = "1"  !CDS_PN = "1";
"B":   PN = "2"  !CDS_PN = "2";
BODY = "RES","I36": #LOCATION = "R7G15" !CDS_LOCATION = "R7G15" #SEC = "1" !CDS_SEC = "1";
"A":   PN = "1"  !CDS_PN = "1";
"B":   PN = "2"  !CDS_PN = "2";
BODY = "RES","I37": #LOCATION = "R7G17" !CDS_LOCATION = "R7G17" #SEC = "1" !CDS_SEC = "1";
"A":   PN = "1"  !CDS_PN = "1";
"B":   PN = "2"  !CDS_PN = "2";
BODY = "RES","I38": #LOCATION = "R7G14" !CDS_LOCATION = "R7G14" #SEC = "1" !CDS_SEC = "1";
"A":   PN = "1"  !CDS_PN = "1";
"B":   PN = "2"  !CDS_PN = "2";
BODY = "RES","I44": #LOCATION = "R3R15" !CDS_LOCATION = "R3R15" #SEC = "1" !CDS_SEC = "1";
"A":   PN = "1"  !CDS_PN = "1";
"B":   PN = "2"  !CDS_PN = "2";
BODY = "RES","I45": #LOCATION = "R3R11" !CDS_LOCATION = "R3R11" #SEC = "1" !CDS_SEC = "1";
"A":   PN = "1"  !CDS_PN = "1";
"B":   PN = "2"  !CDS_PN = "2";
BODY = "CONN8_C77962004","I47": #LOCATION = "J7G2" !CDS_LOCATION = "J7G2" #SEC = "1" !CDS_SEC = "1";
"IO1":   PN = "1"  !CDS_PN = "1";
"IO2":   PN = "2"  !CDS_PN = "2";
"IO3":   PN = "3"  !CDS_PN = "3";
"IO4":   PN = "4"  !CDS_PN = "4";
"IO5":   PN = "5"  !CDS_PN = "5";
"IO6":   PN = "6"  !CDS_PN = "6";
"IO7":   PN = "7"  !CDS_PN = "7";
"IO8":   PN = "8"  !CDS_PN = "8";
BODY = "DIODE","I49": #LOCATION = "CR3U1" !CDS_LOCATION = "CR3U1" #SEC = "1" !CDS_SEC = "1";
"A":   PN = "2"  !CDS_PN = "2";
"C":   PN = "1"  !CDS_PN = "1";
BODY = "RES","I50": #LOCATION = "R8G20" !CDS_LOCATION = "R8G20" &SEC = "1" #&CDS_SEC = "1";
"A":   PN = "1"  !CDS_PN = "1";
"B":   PN = "2"  !CDS_PN = "2";
BODY = "RES","I51": #LOCATION = "R7G23" !CDS_LOCATION = "R7G23" &SEC = "1" #&CDS_SEC = "1";
"A":   PN = "1"  !CDS_PN = "1";
"B":   PN = "2"  !CDS_PN = "2";
BODY = "RES","I53": #LOCATION = "R7G22" !CDS_LOCATION = "R7G22" &SEC = "1" #&CDS_SEC = "1";
"A":   PN = "1"  !CDS_PN = "1";
"B":   PN = "2"  !CDS_PN = "2";
BODY = "RES","I56": #LOCATION = "R8G23" !CDS_LOCATION = "R8G23" #SEC = "1" !CDS_SEC = "1";
"A":   PN = "1"  !CDS_PN = "1";
"B":   PN = "2"  !CDS_PN = "2";
BODY = "RES","I63": #LOCATION = "R7G21" !CDS_LOCATION = "R7G21" #SEC = "1" !CDS_SEC = "1";
"A":   PN = "1"  !CDS_PN = "1";
"B":   PN = "2"  !CDS_PN = "2";
BODY = "RES","I64": #LOCATION = "R8G19" !CDS_LOCATION = "R8G19" #SEC = "1" !CDS_SEC = "1";
"A":   PN = "1"  !CDS_PN = "1";
"B":   PN = "2"  !CDS_PN = "2";
BODY = "RES","I65": #LOCATION = "R8G21" !CDS_LOCATION = "R8G21" #SEC = "1" !CDS_SEC = "1";
"A":   PN = "1"  !CDS_PN = "1";
"B":   PN = "2"  !CDS_PN = "2";
BODY = "RES","I66": #LOCATION = "R8G22" !CDS_LOCATION = "R8G22" #SEC = "1" !CDS_SEC = "1";
"A":   PN = "1"  !CDS_PN = "1";
"B":   PN = "2"  !CDS_PN = "2";
BODY = "TTL3126","I67": #LOCATION = "U1L10" !CDS_LOCATION = "U1L10";
"A<0>":   PN = "12"  !CDS_PN = "12";
"A<1>":   PN = "9"  !CDS_PN = "9";
"A<2>":   PN = "5"  !CDS_PN = "5";
"A<3>":   PN = "2"  !CDS_PN = "2";
"B<0>":   PN = "11"  !CDS_PN = "11";
"B<1>":   PN = "8"  !CDS_PN = "8";
"B<2>":   PN = "6"  !CDS_PN = "6";
"B<3>":   PN = "3"  !CDS_PN = "3";
"OE<0>":   PN = "13"  !CDS_PN = "13";
"OE<1>":   PN = "10"  !CDS_PN = "10";
"OE<2>":   PN = "4"  !CDS_PN = "4";
"OE<3>":   PN = "1"  !CDS_PN = "1";
BODY = "CAP","I69": #LOCATION = "C1L119" !CDS_LOCATION = "C1L119" &SEC = "1" #&CDS_SEC = "1";
"A":   PN = "1"  !CDS_PN = "1";
"B":   PN = "2"  !CDS_PN = "2";
BODY = "RES","I76": #LOCATION = "R7G114" !CDS_LOCATION = "R7G114" &SEC = "1" #&CDS_SEC = "1";
"A":   PN = "1"  !CDS_PN = "1";
"B":   PN = "2"  !CDS_PN = "2";
BODY = "RES","I77": #LOCATION = "R25W186" !CDS_LOCATION = "R25W186" #SEC = "1" !CDS_SEC = "1";
"A":   PN = "1"  !CDS_PN = "1";
"B":   PN = "2"  !CDS_PN = "2";
DRAWING = "@baseboard_fab2_lib.baseboard_fab2(sch_1):page190";
BODY = "RES","I116": #LOCATION = "R3P34" !CDS_LOCATION = "R3P34" #SEC = "1" !CDS_SEC = "1";
"A":   PN = "1"  !CDS_PN = "1";
"B":   PN = "2"  !CDS_PN = "2";
BODY = "RES","I117": #LOCATION = "R3P35" !CDS_LOCATION = "R3P35" #SEC = "1" !CDS_SEC = "1";
"A":   PN = "1"  !CDS_PN = "1";
"B":   PN = "2"  !CDS_PN = "2";
BODY = "LCMXO2_A","I179": #LOCATION = "U8D7" !CDS_LOCATION = "U8D7" #SEC = "1" !CDS_SEC = "1";
"PB3A":   PN = "P4"  !CDS_PN = "P4";
"PB3B":   PN = "T4"  !CDS_PN = "T4";
"PB3C":   PN = "T2"  !CDS_PN = "T2";
"PB3D":   PN = "R3"  !CDS_PN = "R3";
"PB5A_CSSPIN":   PN = "R5"  !CDS_PN = "R5";
"PB5B":   PN = "P5"  !CDS_PN = "P5";
"PB6A":   PN = "T5"  !CDS_PN = "T5";
"PB6B":   PN = "R6"  !CDS_PN = "R6";
"PB6C":   PN = "T3"  !CDS_PN = "T3";
"PB6D":   PN = "R4"  !CDS_PN = "R4";
"PB8A_MCLK_CCLK":   PN = "P6"  !CDS_PN = "P6";
"PB8B_SO_SPISO":   PN = "T6"  !CDS_PN = "T6";
"PB8C":   PN = "N6"  !CDS_PN = "N6";
"PB8D":   PN = "L7"  !CDS_PN = "L7";
"PB9A":   PN = "R7"  !CDS_PN = "R7";
"PB9B":   PN = "P7"  !CDS_PN = "P7";
"PB9C":   PN = "M7"  !CDS_PN = "M7";
"PB9D":   PN = "N7"  !CDS_PN = "N7";
"PB11A_PCLKT2_0":   PN = "T7"  !CDS_PN = "T7";
"PB11B_PCLKC2_0":   PN = "R8"  !CDS_PN = "R8";
"PB11C":   PN = "M6"  !CDS_PN = "M6";
"PB11D":   PN = "L8"  !CDS_PN = "L8";
"PB12A":   PN = "P8"  !CDS_PN = "P8";
"PB12B":   PN = "T8"  !CDS_PN = "T8";
"PB12C":   PN = "N8"  !CDS_PN = "N8";
"PB12D":   PN = "L9"  !CDS_PN = "L9";
"PB16A_PCLKT2_1":   PN = "T9"  !CDS_PN = "T9";
"PB16B_PCLKC2_1":   PN = "P9"  !CDS_PN = "P9";
"PB16C":   PN = "M8"  !CDS_PN = "M8";
"PB16D":   PN = "N9"  !CDS_PN = "N9";
"PB18A":   PN = "R9"  !CDS_PN = "R9";
"PB18B":   PN = "T10"  !CDS_PN = "T10";
"PB18C":   PN = "M9"  !CDS_PN = "M9";
"PB18D":   PN = "L10"  !CDS_PN = "L10";
"PB19A":   PN = "P10"  !CDS_PN = "P10";
"PB19B":   PN = "R10"  !CDS_PN = "R10";
"PB19C":   PN = "N10"  !CDS_PN = "N10";
"PB19D":   PN = "M11"  !CDS_PN = "M11";
"PB21A":   PN = "T11"  !CDS_PN = "T11";
"PB21B":   PN = "P11"  !CDS_PN = "P11";
"PB21C":   PN = "M10"  !CDS_PN = "M10";
"PB21D":   PN = "N11"  !CDS_PN = "N11";
"PB22A":   PN = "R11"  !CDS_PN = "R11";
"PB22B":   PN = "T12"  !CDS_PN = "T12";
"PB22C":   PN = "R13"  !CDS_PN = "R13";
"PB22D":   PN = "T14"  !CDS_PN = "T14";
"PB24A":   PN = "P12"  !CDS_PN = "P12";
"PB24B":   PN = "T13"  !CDS_PN = "T13";
"PB25A_SN":   PN = "R12"  !CDS_PN = "R12";
"PB25B_SI_SISPI":   PN = "P13"  !CDS_PN = "P13";
"PB25C":   PN = "T15"  !CDS_PN = "T15";
"PB25D":   PN = "R14"  !CDS_PN = "R14";
"PL1A_L_GPLLT_FB":   PN = "D3"  !CDS_PN = "D3";
"PL1B_L_GPLLC_FB":   PN = "D1"  !CDS_PN = "D1";
"PL1C":   PN = "B1"  !CDS_PN = "B1";
"PL1D":   PN = "C2"  !CDS_PN = "C2";
"PL2A_L_GPLLT_IN":   PN = "E2"  !CDS_PN = "E2";
"PL2B_L_GPLLC_IN":   PN = "E3"  !CDS_PN = "E3";
"PL2C":   PN = "C1"  !CDS_PN = "C1";
"PL2D":   PN = "D2"  !CDS_PN = "D2";
"PL3A_PCLKT5_0":   PN = "E1"  !CDS_PN = "E1";
"PL3B_PCLKC5_0":   PN = "F2"  !CDS_PN = "F2";
"PL3C":   PN = "F4"  !CDS_PN = "F4";
"PL3D":   PN = "G6"  !CDS_PN = "G6";
"PL4A":   PN = "F3"  !CDS_PN = "F3";
"PL4B":   PN = "F1"  !CDS_PN = "F1";
"PL4C":   PN = "G5"  !CDS_PN = "G5";
"PL4D":   PN = "G4"  !CDS_PN = "G4";
"PL5A":   PN = "G2"  !CDS_PN = "G2";
"PL5B":   PN = "G3"  !CDS_PN = "G3";
"PL5C":   PN = "F5"  !CDS_PN = "F5";
"PL5D":   PN = "H6"  !CDS_PN = "H6";
"PL6A":   PN = "G1"  !CDS_PN = "G1";
"PL6B":   PN = "H2"  !CDS_PN = "H2";
"PL6C":   PN = "H4"  !CDS_PN = "H4";
"PL6D":   PN = "J6"  !CDS_PN = "J6";
"PL7A":   PN = "H3"  !CDS_PN = "H3";
"PL7B":   PN = "H1"  !CDS_PN = "H1";
"PL7C_PCLKT4_0":   PN = "J1"  !CDS_PN = "J1";
"PL7D_PCLKC4_0":   PN = "J3"  !CDS_PN = "J3";
"PL9A":   PN = "J2"  !CDS_PN = "J2";
"PL9B":   PN = "K1"  !CDS_PN = "K1";
"PL9C":   PN = "H5"  !CDS_PN = "H5";
"PL9D":   PN = "J4"  !CDS_PN = "J4";
"PL10A":   PN = "K3"  !CDS_PN = "K3";
"PL10B":   PN = "K2"  !CDS_PN = "K2";
"PL10C":   PN = "J5"  !CDS_PN = "J5";
"PL10D":   PN = "K6"  !CDS_PN = "K6";
"PL11A":   PN = "L1"  !CDS_PN = "L1";
"PL11B":   PN = "L3"  !CDS_PN = "L3";
"PL11C":   PN = "K4"  !CDS_PN = "K4";
"PL11D":   PN = "L5"  !CDS_PN = "L5";
"PL12A_PCLKT3_0":   PN = "L2"  !CDS_PN = "L2";
"PL12B_PCLKC3_0":   PN = "M1"  !CDS_PN = "M1";
"PL12C":   PN = "K5"  !CDS_PN = "K5";
"PL12D":   PN = "L4"  !CDS_PN = "L4";
"PL13A":   PN = "M3"  !CDS_PN = "M3";
"PL13B":   PN = "N1"  !CDS_PN = "N1";
"PL13C":   PN = "N2"  !CDS_PN = "N2";
"PL13D":   PN = "P1"  !CDS_PN = "P1";
"PL14A":   PN = "M2"  !CDS_PN = "M2";
"PL14B":   PN = "N3"  !CDS_PN = "N3";
"PL14C":   PN = "R1"  !CDS_PN = "R1";
"PL14D":   PN = "P2"  !CDS_PN = "P2";
BODY = "RES","I338": #LOCATION = "R2R2" !CDS_LOCATION = "R2R2" &SEC = "1" #&CDS_SEC = "1";
"A":   PN = "1"  !CDS_PN = "1";
"B":   PN = "2"  !CDS_PN = "2";
BODY = "RES","I349": #LOCATION = "R1W26" !CDS_LOCATION = "R1W26" #SEC = "1" !CDS_SEC = "1";
"A":   PN = "1"  !CDS_PN = "1";
"B":   PN = "2"  !CDS_PN = "2";
BODY = "RES","I351": #LOCATION = "R1W27" !CDS_LOCATION = "R1W27" #SEC = "1" !CDS_SEC = "1";
"A":   PN = "1"  !CDS_PN = "1";
"B":   PN = "2"  !CDS_PN = "2";
DRAWING = "@baseboard_fab2_lib.baseboard_fab2(sch_1):page191";
BODY = "LCMXO2_A","I59": #LOCATION = "U8D7" !CDS_LOCATION = "U8D7" #SEC = "2" !CDS_SEC = "2";
"PR1A":   PN = "D14"  !CDS_PN = "D14";
"PR1B":   PN = "E15"  !CDS_PN = "E15";
"PR1C":   PN = "C15"  !CDS_PN = "C15";
"PR1D":   PN = "B16"  !CDS_PN = "B16";
"PR2A":   PN = "D16"  !CDS_PN = "D16";
"PR2B":   PN = "E14"  !CDS_PN = "E14";
"PR2C":   PN = "C16"  !CDS_PN = "C16";
"PR2D":   PN = "D15"  !CDS_PN = "D15";
"PR3A":   PN = "E16"  !CDS_PN = "E16";
"PR3B":   PN = "F15"  !CDS_PN = "F15";
"PR3C":   PN = "F13"  !CDS_PN = "F13";
"PR3D":   PN = "G12"  !CDS_PN = "G12";
"PR4A":   PN = "F14"  !CDS_PN = "F14";
"PR4B":   PN = "F16"  !CDS_PN = "F16";
"PR4C":   PN = "F12"  !CDS_PN = "F12";
"PR4D":   PN = "G13"  !CDS_PN = "G13";
"PR5A":   PN = "G15"  !CDS_PN = "G15";
"PR5B":   PN = "G14"  !CDS_PN = "G14";
"PR5C":   PN = "G11"  !CDS_PN = "G11";
"PR5D":   PN = "H12"  !CDS_PN = "H12";
"PR6A":   PN = "G16"  !CDS_PN = "G16";
"PR6B":   PN = "H15"  !CDS_PN = "H15";
"PR6C":   PN = "H13"  !CDS_PN = "H13";
"PR6D":   PN = "J12"  !CDS_PN = "J12";
"PR7A_PCLKT1_0":   PN = "H14"  !CDS_PN = "H14";
"PR7B_PCLKC1_0":   PN = "H16"  !CDS_PN = "H16";
"PR7C":   PN = "J16"  !CDS_PN = "J16";
"PR7D":   PN = "J14"  !CDS_PN = "J14";
"PR9A":   PN = "J15"  !CDS_PN = "J15";
"PR9B":   PN = "K16"  !CDS_PN = "K16";
"PR9C":   PN = "H11"  !CDS_PN = "H11";
"PR9D":   PN = "J13"  !CDS_PN = "J13";
"PR10A":   PN = "K14"  !CDS_PN = "K14";
"PR10B":   PN = "K15"  !CDS_PN = "K15";
"PR10C":   PN = "J11"  !CDS_PN = "J11";
"PR10D":   PN = "L12"  !CDS_PN = "L12";
"PR11A":   PN = "L16"  !CDS_PN = "L16";
"PR11B":   PN = "L14"  !CDS_PN = "L14";
"PR11C":   PN = "K13"  !CDS_PN = "K13";
"PR11D":   PN = "K12"  !CDS_PN = "K12";
"PR12A":   PN = "L15"  !CDS_PN = "L15";
"PR12B":   PN = "M16"  !CDS_PN = "M16";
"PR12C":   PN = "K11"  !CDS_PN = "K11";
"PR12D":   PN = "L13"  !CDS_PN = "L13";
"PR13A":   PN = "M14"  !CDS_PN = "M14";
"PR13B":   PN = "M15"  !CDS_PN = "M15";
"PR13C":   PN = "N15"  !CDS_PN = "N15";
"PR13D":   PN = "P16"  !CDS_PN = "P16";
"PR14A":   PN = "N16"  !CDS_PN = "N16";
"PR14B":   PN = "N14"  !CDS_PN = "N14";
"PR14C":   PN = "P15"  !CDS_PN = "P15";
"PR14D":   PN = "R16"  !CDS_PN = "R16";
"PT9A":   PN = "C4"  !CDS_PN = "C4";
"PT9B":   PN = "B5"  !CDS_PN = "B5";
"PT9C":   PN = "B3"  !CDS_PN = "B3";
"PT10A":   PN = "A4"  !CDS_PN = "A4";
"PT10B":   PN = "C5"  !CDS_PN = "C5";
"PT11A":   PN = "A5"  !CDS_PN = "A5";
"PT11B":   PN = "B6"  !CDS_PN = "B6";
"PT11C":   PN = "A3"  !CDS_PN = "A3";
"PT11D":   PN = "B4"  !CDS_PN = "B4";
"PT12A":   PN = "D6"  !CDS_PN = "D6";
"PT12B":   PN = "E7"  !CDS_PN = "E7";
"PT12C_TDO":   PN = "C6"  !CDS_PN = "C6";
"PT12D_TDI":   PN = "A6"  !CDS_PN = "A6";
"PT13A":   PN = "B7"  !CDS_PN = "B7";
"PT13B":   PN = "C7"  !CDS_PN = "C7";
"PT13C":   PN = "E6"  !CDS_PN = "E6";
"PT13D":   PN = "D7"  !CDS_PN = "D7";
"PT16A":   PN = "F7"  !CDS_PN = "F7";
"PT16B":   PN = "E8"  !CDS_PN = "E8";
"PT16C_TCK":   PN = "A7"  !CDS_PN = "A7";
"PT16D_TMS":   PN = "B8"  !CDS_PN = "B8";
"PT17A_PCLKT0_1":   PN = "C8"  !CDS_PN = "C8";
"PT17B_PCLKC0_1":   PN = "A8"  !CDS_PN = "A8";
"PT17C":   PN = "D8"  !CDS_PN = "D8";
"PT17D":   PN = "E9"  !CDS_PN = "E9";
"PT18A":   PN = "F8"  !CDS_PN = "F8";
"PT18B":   PN = "D9"  !CDS_PN = "D9";
"PT18C_SCL_PCLKT0_0":   PN = "A9"  !CDS_PN = "A9";
"PT18D_SDA_PCLKC0_0":   PN = "C9"  !CDS_PN = "C9";
"PT19A":   PN = "B9"  !CDS_PN = "B9";
"PT19B":   PN = "A10"  !CDS_PN = "A10";
"PT19C":   PN = "F9"  !CDS_PN = "F9";
"PT19D":   PN = "E11"  !CDS_PN = "E11";
"PT20A":   PN = "D10"  !CDS_PN = "D10";
"PT20B":   PN = "E10"  !CDS_PN = "E10";
"PT20C_JTAGENB":   PN = "C10"  !CDS_PN = "C10";
"PT20D_PROGRAMN":   PN = "B10"  !CDS_PN = "B10";
"PT21A":   PN = "A11"  !CDS_PN = "A11";
"PT21B":   PN = "C11"  !CDS_PN = "C11";
"PT21C":   PN = "F10"  !CDS_PN = "F10";
"PT21D":   PN = "D11"  !CDS_PN = "D11";
"PT22A":   PN = "B11"  !CDS_PN = "B11";
"PT22B":   PN = "A12"  !CDS_PN = "A12";
"PT22C":   PN = "B13"  !CDS_PN = "B13";
"PT22D":   PN = "A14"  !CDS_PN = "A14";
"PT23A":   PN = "C12"  !CDS_PN = "C12";
"PT23B":   PN = "B12"  !CDS_PN = "B12";
"PT24A":   PN = "B14"  !CDS_PN = "B14";
"PT24B":   PN = "A15"  !CDS_PN = "A15";
"PT24C_INITN":   PN = "A13"  !CDS_PN = "A13";
"PT24D_DONE":   PN = "C13"  !CDS_PN = "C13";
BODY = "RES","I166": #LOCATION = "R2R6" !CDS_LOCATION = "R2R6" #SEC = "1" !CDS_SEC = "1";
"A":   PN = "1"  !CDS_PN = "1";
"B":   PN = "2"  !CDS_PN = "2";
BODY = "RES","I172": #LOCATION = "R2R7" !CDS_LOCATION = "R2R7" #SEC = "1" !CDS_SEC = "1";
"A":   PN = "1"  !CDS_PN = "1";
"B":   PN = "2"  !CDS_PN = "2";
BODY = "RES","I184": #LOCATION = "R2R4" !CDS_LOCATION = "R2R4" &SEC = "1" #&CDS_SEC = "1";
"A":   PN = "1"  !CDS_PN = "1";
"B":   PN = "2"  !CDS_PN = "2";
BODY = "RES","I193": #LOCATION = "R7D42" !CDS_LOCATION = "R7D42" #SEC = "1" !CDS_SEC = "1";
"A":   PN = "1"  !CDS_PN = "1";
"B":   PN = "2"  !CDS_PN = "2";
BODY = "RES","I195": #LOCATION = "R4W1" !CDS_LOCATION = "R4W1" #SEC = "1" !CDS_SEC = "1";
"A":   PN = "1"  !CDS_PN = "1";
"B":   PN = "2"  !CDS_PN = "2";
BODY = "RES","I197": #LOCATION = "R1W28" !CDS_LOCATION = "R1W28" #SEC = "1" !CDS_SEC = "1";
"A":   PN = "1"  !CDS_PN = "1";
"B":   PN = "2"  !CDS_PN = "2";
BODY = "RES","I198": #LOCATION = "R1W29" !CDS_LOCATION = "R1W29" #SEC = "1" !CDS_SEC = "1";
"A":   PN = "1"  !CDS_PN = "1";
"B":   PN = "2"  !CDS_PN = "2";
DRAWING = "@baseboard_fab2_lib.baseboard_fab2(sch_1):page192";
BODY = "CAP_A","I1": #LOCATION = "C2P8" !CDS_LOCATION = "C2P8" &SEC = "1" #&CDS_SEC = "1";
"A":   PN = "1"  !CDS_PN = "1";
"B":   PN = "2"  !CDS_PN = "2";
BODY = "CAP_A","I3": #LOCATION = "C2P5" !CDS_LOCATION = "C2P5" &SEC = "1" #&CDS_SEC = "1";
"A":   PN = "1"  !CDS_PN = "1";
"B":   PN = "2"  !CDS_PN = "2";
BODY = "CAP_A","I4": #LOCATION = "C3R1" !CDS_LOCATION = "C3R1" &SEC = "1" #&CDS_SEC = "1";
"A":   PN = "1"  !CDS_PN = "1";
"B":   PN = "2"  !CDS_PN = "2";
BODY = "CAP_A","I6": #LOCATION = "C3P43" !CDS_LOCATION = "C3P43" &SEC = "1" #&CDS_SEC = "1";
"A":   PN = "1"  !CDS_PN = "1";
"B":   PN = "2"  !CDS_PN = "2";
BODY = "CAP_A","I7": #LOCATION = "C3R3" !CDS_LOCATION = "C3R3" &SEC = "1" #&CDS_SEC = "1";
"A":   PN = "1"  !CDS_PN = "1";
"B":   PN = "2"  !CDS_PN = "2";
BODY = "CAP_A","I8": #LOCATION = "C2R1" !CDS_LOCATION = "C2R1" &SEC = "1" #&CDS_SEC = "1";
"A":   PN = "1"  !CDS_PN = "1";
"B":   PN = "2"  !CDS_PN = "2";
BODY = "CAP_A","I9": #LOCATION = "C2P2" !CDS_LOCATION = "C2P2" &SEC = "1" #&CDS_SEC = "1";
"A":   PN = "1"  !CDS_PN = "1";
"B":   PN = "2"  !CDS_PN = "2";
BODY = "CAP_A","I10": #LOCATION = "C3R2" !CDS_LOCATION = "C3R2" &SEC = "1" #&CDS_SEC = "1";
"A":   PN = "1"  !CDS_PN = "1";
"B":   PN = "2"  !CDS_PN = "2";
BODY = "CAP_A","I11": #LOCATION = "C3P51" !CDS_LOCATION = "C3P51" &SEC = "1" #&CDS_SEC = "1";
"A":   PN = "1"  !CDS_PN = "1";
"B":   PN = "2"  !CDS_PN = "2";
BODY = "CAP_A","I12": #LOCATION = "C3P47" !CDS_LOCATION = "C3P47" &SEC = "1" #&CDS_SEC = "1";
"A":   PN = "1"  !CDS_PN = "1";
"B":   PN = "2"  !CDS_PN = "2";
BODY = "LCMXO2_A","I14": #LOCATION = "U8D7" !CDS_LOCATION = "U8D7" #SEC = "3" !CDS_SEC = "3";
"GND<0>":   PN = "B2"  !CDS_PN = "B2";
"GND<1>":   PN = "B15"  !CDS_PN = "B15";
"GND<2>":   PN = "C3"  !CDS_PN = "C3";
"GND<3>":   PN = "C14"  !CDS_PN = "C14";
"GND<4>":   PN = "D4"  !CDS_PN = "D4";
"GND<5>":   PN = "D13"  !CDS_PN = "D13";
"GND<6>":   PN = "E5"  !CDS_PN = "E5";
"GND<7>":   PN = "E12"  !CDS_PN = "E12";
"GND<8>":   PN = "F6"  !CDS_PN = "F6";
"GND<9>":   PN = "F11"  !CDS_PN = "F11";
"GND<10>":   PN = "H8"  !CDS_PN = "H8";
"GND<11>":   PN = "H9"  !CDS_PN = "H9";
"GND<12>":   PN = "J8"  !CDS_PN = "J8";
"GND<13>":   PN = "J9"  !CDS_PN = "J9";
"GND<14>":   PN = "L6"  !CDS_PN = "L6";
"GND<15>":   PN = "L11"  !CDS_PN = "L11";
"GND<16>":   PN = "M5"  !CDS_PN = "M5";
"GND<17>":   PN = "M12"  !CDS_PN = "M12";
"GND<18>":   PN = "N4"  !CDS_PN = "N4";
"GND<19>":   PN = "N13"  !CDS_PN = "N13";
"GND<20>":   PN = "P3"  !CDS_PN = "P3";
"GND<21>":   PN = "P14"  !CDS_PN = "P14";
"GND<22>":   PN = "R2"  !CDS_PN = "R2";
"GND<23>":   PN = "R15"  !CDS_PN = "R15";
"NC<0>":   PN = "A2"  !CDS_PN = "A2";
"VCC<0>":   PN = "A1"  !CDS_PN = "A1";
"VCC<1>":   PN = "A16"  !CDS_PN = "A16";
"VCC<2>":   PN = "T1"  !CDS_PN = "T1";
"VCC<3>":   PN = "T16"  !CDS_PN = "T16";
"VCC<4>":   PN = "G7"  !CDS_PN = "G7";
"VCC<5>":   PN = "G10"  !CDS_PN = "G10";
"VCC<6>":   PN = "K7"  !CDS_PN = "K7";
"VCC<7>":   PN = "K10"  !CDS_PN = "K10";
"VCCIO0<0>":   PN = "G8"  !CDS_PN = "G8";
"VCCIO0<1>":   PN = "D12"  !CDS_PN = "D12";
"VCCIO0<2>":   PN = "G9"  !CDS_PN = "G9";
"VCCIO0<3>":   PN = "D5"  !CDS_PN = "D5";
"VCCIO1<0>":   PN = "E13"  !CDS_PN = "E13";
"VCCIO1<1>":   PN = "H10"  !CDS_PN = "H10";
"VCCIO1<2>":   PN = "J10"  !CDS_PN = "J10";
"VCCIO1<3>":   PN = "M13"  !CDS_PN = "M13";
"VCCIO2<0>":   PN = "K9"  !CDS_PN = "K9";
"VCCIO2<1>":   PN = "N12"  !CDS_PN = "N12";
"VCCIO2<2>":   PN = "K8"  !CDS_PN = "K8";
"VCCIO2<3>":   PN = "N5"  !CDS_PN = "N5";
"VCCIO3<0>":   PN = "M4"  !CDS_PN = "M4";
"VCCIO4<0>":   PN = "J7"  !CDS_PN = "J7";
"VCCIO4<1>":   PN = "H7"  !CDS_PN = "H7";
"VCCIO5<0>":   PN = "E4"  !CDS_PN = "E4";
BODY = "CAP_A","I15": #LOCATION = "C2R5" !CDS_LOCATION = "C2R5" &SEC = "1" #&CDS_SEC = "1";
"A":   PN = "1"  !CDS_PN = "1";
"B":   PN = "2"  !CDS_PN = "2";
BODY = "CAP_A","I16": #LOCATION = "C2P4" !CDS_LOCATION = "C2P4" &SEC = "1" #&CDS_SEC = "1";
"A":   PN = "1"  !CDS_PN = "1";
"B":   PN = "2"  !CDS_PN = "2";
BODY = "CAP_A","I17": #LOCATION = "C3P52" !CDS_LOCATION = "C3P52" &SEC = "1" #&CDS_SEC = "1";
"A":   PN = "1"  !CDS_PN = "1";
"B":   PN = "2"  !CDS_PN = "2";
BODY = "CAP_A","I18": #LOCATION = "C2P6" !CDS_LOCATION = "C2P6" &SEC = "1" #&CDS_SEC = "1";
"A":   PN = "1"  !CDS_PN = "1";
"B":   PN = "2"  !CDS_PN = "2";
BODY = "CAP_A","I19": #LOCATION = "C2R3" !CDS_LOCATION = "C2R3" &SEC = "1" #&CDS_SEC = "1";
"A":   PN = "1"  !CDS_PN = "1";
"B":   PN = "2"  !CDS_PN = "2";
BODY = "CAP_A","I20": #LOCATION = "C2P7" !CDS_LOCATION = "C2P7" &SEC = "1" #&CDS_SEC = "1";
"A":   PN = "1"  !CDS_PN = "1";
"B":   PN = "2"  !CDS_PN = "2";
BODY = "CAP_A","I21": #LOCATION = "C2R4" !CDS_LOCATION = "C2R4" &SEC = "1" #&CDS_SEC = "1";
"A":   PN = "1"  !CDS_PN = "1";
"B":   PN = "2"  !CDS_PN = "2";
BODY = "CAP_A","I22": #LOCATION = "C2P3" !CDS_LOCATION = "C2P3" &SEC = "1" #&CDS_SEC = "1";
"A":   PN = "1"  !CDS_PN = "1";
"B":   PN = "2"  !CDS_PN = "2";
BODY = "CAP_A","I23": #LOCATION = "C3P44" !CDS_LOCATION = "C3P44" &SEC = "1" #&CDS_SEC = "1";
"A":   PN = "1"  !CDS_PN = "1";
"B":   PN = "2"  !CDS_PN = "2";
BODY = "CAP_A","I25": #LOCATION = "C3P48" !CDS_LOCATION = "C3P48" #SEC = "1" !CDS_SEC = "1";
"A":   PN = "1"  !CDS_PN = "1";
"B":   PN = "2"  !CDS_PN = "2";
BODY = "CAP_A","I28": #LOCATION = "C2R2" !CDS_LOCATION = "C2R2" &SEC = "1" #&CDS_SEC = "1";
"A":   PN = "1"  !CDS_PN = "1";
"B":   PN = "2"  !CDS_PN = "2";
BODY = "RES","I33": #LOCATION = "R7E6" !CDS_LOCATION = "R7E6" #SEC = "1" !CDS_SEC = "1";
"A":   PN = "1"  !CDS_PN = "1";
"B":   PN = "2"  !CDS_PN = "2";
BODY = "RES","I34": #LOCATION = "R2R1" !CDS_LOCATION = "R2R1" #SEC = "1" !CDS_SEC = "1";
"A":   PN = "1"  !CDS_PN = "1";
"B":   PN = "2"  !CDS_PN = "2";
BODY = "RES","I38": #LOCATION = "R7E5" !CDS_LOCATION = "R7E5" &SEC = "1" #&CDS_SEC = "1";
"A":   PN = "1"  !CDS_PN = "1";
"B":   PN = "2"  !CDS_PN = "2";
BODY = "RES","I41": #LOCATION = "R2R3" !CDS_LOCATION = "R2R3" &SEC = "1" #&CDS_SEC = "1";
"A":   PN = "1"  !CDS_PN = "1";
"B":   PN = "2"  !CDS_PN = "2";
BODY = "RES","I48": #LOCATION = "R3R16" !CDS_LOCATION = "R3R16" #SEC = "1" !CDS_SEC = "1";
"A":   PN = "1"  !CDS_PN = "1";
"B":   PN = "2"  !CDS_PN = "2";
BODY = "RES","I49": #LOCATION = "R6M9" !CDS_LOCATION = "R6M9" #SEC = "1" !CDS_SEC = "1";
"A":   PN = "1"  !CDS_PN = "1";
"B":   PN = "2"  !CDS_PN = "2";
BODY = "RES","I55": #LOCATION = "R7E18" !CDS_LOCATION = "R7E18" #SEC = "1" !CDS_SEC = "1";
"A":   PN = "1"  !CDS_PN = "1";
"B":   PN = "2"  !CDS_PN = "2";
BODY = "RES","I57": #LOCATION = "R7E19" !CDS_LOCATION = "R7E19" #SEC = "1" !CDS_SEC = "1";
"A":   PN = "1"  !CDS_PN = "1";
"B":   PN = "2"  !CDS_PN = "2";
BODY = "RES","I59": #LOCATION = "R7E20" !CDS_LOCATION = "R7E20" #SEC = "1" !CDS_SEC = "1";
"A":   PN = "1"  !CDS_PN = "1";
"B":   PN = "2"  !CDS_PN = "2";
DRAWING = "@baseboard_fab2_lib.baseboard_fab2(sch_1):page193";
BODY = "CAPP","I29": #LOCATION = "C4C1" !CDS_LOCATION = "C4C1" #SEC = "1" !CDS_SEC = "1";
"A":   PN = "1"  !CDS_PN = "1";
"B":   PN = "2"  !CDS_PN = "2";
BODY = "CAP_A","I31": #LOCATION = "C3C2" !CDS_LOCATION = "C3C2" #SEC = "1" !CDS_SEC = "1";
"A":   PN = "1"  !CDS_PN = "1";
"B":   PN = "2"  !CDS_PN = "2";
BODY = "CAP_A","I38": #LOCATION = "C3C1" !CDS_LOCATION = "C3C1" #SEC = "1" !CDS_SEC = "1";
"A":   PN = "1"  !CDS_PN = "1";
"B":   PN = "2"  !CDS_PN = "2";
BODY = "SCONN120_H61426002","I45": #LOCATION = "J4E1" !CDS_LOCATION = "J4E1" #SEC = "1" !CDS_SEC = "1";
"IOA1":   PN = "A1"  !CDS_PN = "A1";
"IOA2":   PN = "A2"  !CDS_PN = "A2";
"IOA3":   PN = "A3"  !CDS_PN = "A3";
"IOA4":   PN = "A4"  !CDS_PN = "A4";
"IOA5":   PN = "A5"  !CDS_PN = "A5";
"IOA6":   PN = "A6"  !CDS_PN = "A6";
"IOA7":   PN = "A7"  !CDS_PN = "A7";
"IOA8":   PN = "A8"  !CDS_PN = "A8";
"IOA9":   PN = "A9"  !CDS_PN = "A9";
"IOA10":   PN = "A10"  !CDS_PN = "A10";
"IOA11":   PN = "A11"  !CDS_PN = "A11";
"IOA12":   PN = "A12"  !CDS_PN = "A12";
"IOA13":   PN = "A13"  !CDS_PN = "A13";
"IOA14":   PN = "A14"  !CDS_PN = "A14";
"IOA15":   PN = "A15"  !CDS_PN = "A15";
"IOA16":   PN = "A16"  !CDS_PN = "A16";
"IOA17":   PN = "A17"  !CDS_PN = "A17";
"IOA18":   PN = "A18"  !CDS_PN = "A18";
"IOA19":   PN = "A19"  !CDS_PN = "A19";
"IOA20":   PN = "A20"  !CDS_PN = "A20";
"IOB1":   PN = "B1"  !CDS_PN = "B1";
"IOB2":   PN = "B2"  !CDS_PN = "B2";
"IOB3":   PN = "B3"  !CDS_PN = "B3";
"IOB4":   PN = "B4"  !CDS_PN = "B4";
"IOB5":   PN = "B5"  !CDS_PN = "B5";
"IOB6":   PN = "B6"  !CDS_PN = "B6";
"IOB7":   PN = "B7"  !CDS_PN = "B7";
"IOB8":   PN = "B8"  !CDS_PN = "B8";
"IOB9":   PN = "B9"  !CDS_PN = "B9";
"IOB10":   PN = "B10"  !CDS_PN = "B10";
"IOB11":   PN = "B11"  !CDS_PN = "B11";
"IOB12":   PN = "B12"  !CDS_PN = "B12";
"IOB13":   PN = "B13"  !CDS_PN = "B13";
"IOB14":   PN = "B14"  !CDS_PN = "B14";
"IOB15":   PN = "B15"  !CDS_PN = "B15";
"IOB16":   PN = "B16"  !CDS_PN = "B16";
"IOB17":   PN = "B17"  !CDS_PN = "B17";
"IOB18":   PN = "B18"  !CDS_PN = "B18";
"IOB19":   PN = "B19"  !CDS_PN = "B19";
"IOB20":   PN = "B20"  !CDS_PN = "B20";
"IOC1":   PN = "C1"  !CDS_PN = "C1";
"IOC2":   PN = "C2"  !CDS_PN = "C2";
"IOC3":   PN = "C3"  !CDS_PN = "C3";
"IOC4":   PN = "C4"  !CDS_PN = "C4";
"IOC5":   PN = "C5"  !CDS_PN = "C5";
"IOC6":   PN = "C6"  !CDS_PN = "C6";
"IOC7":   PN = "C7"  !CDS_PN = "C7";
"IOC8":   PN = "C8"  !CDS_PN = "C8";
"IOC9":   PN = "C9"  !CDS_PN = "C9";
"IOC10":   PN = "C10"  !CDS_PN = "C10";
"IOC11":   PN = "C11"  !CDS_PN = "C11";
"IOC12":   PN = "C12"  !CDS_PN = "C12";
"IOC13":   PN = "C13"  !CDS_PN = "C13";
"IOC14":   PN = "C14"  !CDS_PN = "C14";
"IOC15":   PN = "C15"  !CDS_PN = "C15";
"IOC16":   PN = "C16"  !CDS_PN = "C16";
"IOC17":   PN = "C17"  !CDS_PN = "C17";
"IOC18":   PN = "C18"  !CDS_PN = "C18";
"IOC19":   PN = "C19"  !CDS_PN = "C19";
"IOC20":   PN = "C20"  !CDS_PN = "C20";
"IOD1":   PN = "D1"  !CDS_PN = "D1";
"IOD2":   PN = "D2"  !CDS_PN = "D2";
"IOD3":   PN = "D3"  !CDS_PN = "D3";
"IOD4":   PN = "D4"  !CDS_PN = "D4";
"IOD5":   PN = "D5"  !CDS_PN = "D5";
"IOD6":   PN = "D6"  !CDS_PN = "D6";
"IOD7":   PN = "D7"  !CDS_PN = "D7";
"IOD8":   PN = "D8"  !CDS_PN = "D8";
"IOD9":   PN = "D9"  !CDS_PN = "D9";
"IOD10":   PN = "D10"  !CDS_PN = "D10";
"IOD11":   PN = "D11"  !CDS_PN = "D11";
"IOD12":   PN = "D12"  !CDS_PN = "D12";
"IOD13":   PN = "D13"  !CDS_PN = "D13";
"IOD14":   PN = "D14"  !CDS_PN = "D14";
"IOD15":   PN = "D15"  !CDS_PN = "D15";
"IOD16":   PN = "D16"  !CDS_PN = "D16";
"IOD17":   PN = "D17"  !CDS_PN = "D17";
"IOD18":   PN = "D18"  !CDS_PN = "D18";
"IOD19":   PN = "D19"  !CDS_PN = "D19";
"IOD20":   PN = "D20"  !CDS_PN = "D20";
"IOE1":   PN = "E1"  !CDS_PN = "E1";
"IOE2":   PN = "E2"  !CDS_PN = "E2";
"IOE3":   PN = "E3"  !CDS_PN = "E3";
"IOE4":   PN = "E4"  !CDS_PN = "E4";
"IOE5":   PN = "E5"  !CDS_PN = "E5";
"IOE6":   PN = "E6"  !CDS_PN = "E6";
"IOE7":   PN = "E7"  !CDS_PN = "E7";
"IOE8":   PN = "E8"  !CDS_PN = "E8";
"IOE9":   PN = "E9"  !CDS_PN = "E9";
"IOE10":   PN = "E10"  !CDS_PN = "E10";
"IOE11":   PN = "E11"  !CDS_PN = "E11";
"IOE12":   PN = "E12"  !CDS_PN = "E12";
"IOE13":   PN = "E13"  !CDS_PN = "E13";
"IOE14":   PN = "E14"  !CDS_PN = "E14";
"IOE15":   PN = "E15"  !CDS_PN = "E15";
"IOE16":   PN = "E16"  !CDS_PN = "E16";
"IOE17":   PN = "E17"  !CDS_PN = "E17";
"IOE18":   PN = "E18"  !CDS_PN = "E18";
"IOE19":   PN = "E19"  !CDS_PN = "E19";
"IOE20":   PN = "E20"  !CDS_PN = "E20";
"IOF1":   PN = "F1"  !CDS_PN = "F1";
"IOF2":   PN = "F2"  !CDS_PN = "F2";
"IOF3":   PN = "F3"  !CDS_PN = "F3";
"IOF4":   PN = "F4"  !CDS_PN = "F4";
"IOF5":   PN = "F5"  !CDS_PN = "F5";
"IOF6":   PN = "F6"  !CDS_PN = "F6";
"IOF7":   PN = "F7"  !CDS_PN = "F7";
"IOF8":   PN = "F8"  !CDS_PN = "F8";
"IOF9":   PN = "F9"  !CDS_PN = "F9";
"IOF10":   PN = "F10"  !CDS_PN = "F10";
"IOF11":   PN = "F11"  !CDS_PN = "F11";
"IOF12":   PN = "F12"  !CDS_PN = "F12";
"IOF13":   PN = "F13"  !CDS_PN = "F13";
"IOF14":   PN = "F14"  !CDS_PN = "F14";
"IOF15":   PN = "F15"  !CDS_PN = "F15";
"IOF16":   PN = "F16"  !CDS_PN = "F16";
"IOF17":   PN = "F17"  !CDS_PN = "F17";
"IOF18":   PN = "F18"  !CDS_PN = "F18";
"IOF19":   PN = "F19"  !CDS_PN = "F19";
"IOF20":   PN = "F20"  !CDS_PN = "F20";
BODY = "SCONN120_H61426002","I46": #LOCATION = "J4B2" !CDS_LOCATION = "J4B2" #SEC = "1" !CDS_SEC = "1";
"IOA1":   PN = "A1"  !CDS_PN = "A1";
"IOA2":   PN = "A2"  !CDS_PN = "A2";
"IOA3":   PN = "A3"  !CDS_PN = "A3";
"IOA4":   PN = "A4"  !CDS_PN = "A4";
"IOA5":   PN = "A5"  !CDS_PN = "A5";
"IOA6":   PN = "A6"  !CDS_PN = "A6";
"IOA7":   PN = "A7"  !CDS_PN = "A7";
"IOA8":   PN = "A8"  !CDS_PN = "A8";
"IOA9":   PN = "A9"  !CDS_PN = "A9";
"IOA10":   PN = "A10"  !CDS_PN = "A10";
"IOA11":   PN = "A11"  !CDS_PN = "A11";
"IOA12":   PN = "A12"  !CDS_PN = "A12";
"IOA13":   PN = "A13"  !CDS_PN = "A13";
"IOA14":   PN = "A14"  !CDS_PN = "A14";
"IOA15":   PN = "A15"  !CDS_PN = "A15";
"IOA16":   PN = "A16"  !CDS_PN = "A16";
"IOA17":   PN = "A17"  !CDS_PN = "A17";
"IOA18":   PN = "A18"  !CDS_PN = "A18";
"IOA19":   PN = "A19"  !CDS_PN = "A19";
"IOA20":   PN = "A20"  !CDS_PN = "A20";
"IOB1":   PN = "B1"  !CDS_PN = "B1";
"IOB2":   PN = "B2"  !CDS_PN = "B2";
"IOB3":   PN = "B3"  !CDS_PN = "B3";
"IOB4":   PN = "B4"  !CDS_PN = "B4";
"IOB5":   PN = "B5"  !CDS_PN = "B5";
"IOB6":   PN = "B6"  !CDS_PN = "B6";
"IOB7":   PN = "B7"  !CDS_PN = "B7";
"IOB8":   PN = "B8"  !CDS_PN = "B8";
"IOB9":   PN = "B9"  !CDS_PN = "B9";
"IOB10":   PN = "B10"  !CDS_PN = "B10";
"IOB11":   PN = "B11"  !CDS_PN = "B11";
"IOB12":   PN = "B12"  !CDS_PN = "B12";
"IOB13":   PN = "B13"  !CDS_PN = "B13";
"IOB14":   PN = "B14"  !CDS_PN = "B14";
"IOB15":   PN = "B15"  !CDS_PN = "B15";
"IOB16":   PN = "B16"  !CDS_PN = "B16";
"IOB17":   PN = "B17"  !CDS_PN = "B17";
"IOB18":   PN = "B18"  !CDS_PN = "B18";
"IOB19":   PN = "B19"  !CDS_PN = "B19";
"IOB20":   PN = "B20"  !CDS_PN = "B20";
"IOC1":   PN = "C1"  !CDS_PN = "C1";
"IOC2":   PN = "C2"  !CDS_PN = "C2";
"IOC3":   PN = "C3"  !CDS_PN = "C3";
"IOC4":   PN = "C4"  !CDS_PN = "C4";
"IOC5":   PN = "C5"  !CDS_PN = "C5";
"IOC6":   PN = "C6"  !CDS_PN = "C6";
"IOC7":   PN = "C7"  !CDS_PN = "C7";
"IOC8":   PN = "C8"  !CDS_PN = "C8";
"IOC9":   PN = "C9"  !CDS_PN = "C9";
"IOC10":   PN = "C10"  !CDS_PN = "C10";
"IOC11":   PN = "C11"  !CDS_PN = "C11";
"IOC12":   PN = "C12"  !CDS_PN = "C12";
"IOC13":   PN = "C13"  !CDS_PN = "C13";
"IOC14":   PN = "C14"  !CDS_PN = "C14";
"IOC15":   PN = "C15"  !CDS_PN = "C15";
"IOC16":   PN = "C16"  !CDS_PN = "C16";
"IOC17":   PN = "C17"  !CDS_PN = "C17";
"IOC18":   PN = "C18"  !CDS_PN = "C18";
"IOC19":   PN = "C19"  !CDS_PN = "C19";
"IOC20":   PN = "C20"  !CDS_PN = "C20";
"IOD1":   PN = "D1"  !CDS_PN = "D1";
"IOD2":   PN = "D2"  !CDS_PN = "D2";
"IOD3":   PN = "D3"  !CDS_PN = "D3";
"IOD4":   PN = "D4"  !CDS_PN = "D4";
"IOD5":   PN = "D5"  !CDS_PN = "D5";
"IOD6":   PN = "D6"  !CDS_PN = "D6";
"IOD7":   PN = "D7"  !CDS_PN = "D7";
"IOD8":   PN = "D8"  !CDS_PN = "D8";
"IOD9":   PN = "D9"  !CDS_PN = "D9";
"IOD10":   PN = "D10"  !CDS_PN = "D10";
"IOD11":   PN = "D11"  !CDS_PN = "D11";
"IOD12":   PN = "D12"  !CDS_PN = "D12";
"IOD13":   PN = "D13"  !CDS_PN = "D13";
"IOD14":   PN = "D14"  !CDS_PN = "D14";
"IOD15":   PN = "D15"  !CDS_PN = "D15";
"IOD16":   PN = "D16"  !CDS_PN = "D16";
"IOD17":   PN = "D17"  !CDS_PN = "D17";
"IOD18":   PN = "D18"  !CDS_PN = "D18";
"IOD19":   PN = "D19"  !CDS_PN = "D19";
"IOD20":   PN = "D20"  !CDS_PN = "D20";
"IOE1":   PN = "E1"  !CDS_PN = "E1";
"IOE2":   PN = "E2"  !CDS_PN = "E2";
"IOE3":   PN = "E3"  !CDS_PN = "E3";
"IOE4":   PN = "E4"  !CDS_PN = "E4";
"IOE5":   PN = "E5"  !CDS_PN = "E5";
"IOE6":   PN = "E6"  !CDS_PN = "E6";
"IOE7":   PN = "E7"  !CDS_PN = "E7";
"IOE8":   PN = "E8"  !CDS_PN = "E8";
"IOE9":   PN = "E9"  !CDS_PN = "E9";
"IOE10":   PN = "E10"  !CDS_PN = "E10";
"IOE11":   PN = "E11"  !CDS_PN = "E11";
"IOE12":   PN = "E12"  !CDS_PN = "E12";
"IOE13":   PN = "E13"  !CDS_PN = "E13";
"IOE14":   PN = "E14"  !CDS_PN = "E14";
"IOE15":   PN = "E15"  !CDS_PN = "E15";
"IOE16":   PN = "E16"  !CDS_PN = "E16";
"IOE17":   PN = "E17"  !CDS_PN = "E17";
"IOE18":   PN = "E18"  !CDS_PN = "E18";
"IOE19":   PN = "E19"  !CDS_PN = "E19";
"IOE20":   PN = "E20"  !CDS_PN = "E20";
"IOF1":   PN = "F1"  !CDS_PN = "F1";
"IOF2":   PN = "F2"  !CDS_PN = "F2";
"IOF3":   PN = "F3"  !CDS_PN = "F3";
"IOF4":   PN = "F4"  !CDS_PN = "F4";
"IOF5":   PN = "F5"  !CDS_PN = "F5";
"IOF6":   PN = "F6"  !CDS_PN = "F6";
"IOF7":   PN = "F7"  !CDS_PN = "F7";
"IOF8":   PN = "F8"  !CDS_PN = "F8";
"IOF9":   PN = "F9"  !CDS_PN = "F9";
"IOF10":   PN = "F10"  !CDS_PN = "F10";
"IOF11":   PN = "F11"  !CDS_PN = "F11";
"IOF12":   PN = "F12"  !CDS_PN = "F12";
"IOF13":   PN = "F13"  !CDS_PN = "F13";
"IOF14":   PN = "F14"  !CDS_PN = "F14";
"IOF15":   PN = "F15"  !CDS_PN = "F15";
"IOF16":   PN = "F16"  !CDS_PN = "F16";
"IOF17":   PN = "F17"  !CDS_PN = "F17";
"IOF18":   PN = "F18"  !CDS_PN = "F18";
"IOF19":   PN = "F19"  !CDS_PN = "F19";
"IOF20":   PN = "F20"  !CDS_PN = "F20";
BODY = "CAPP","I61": #LOCATION = "C4E24" !CDS_LOCATION = "C4E24" &SEC = "1" #&CDS_SEC = "1";
"A":   PN = "1"  !CDS_PN = "1";
"B":   PN = "2"  !CDS_PN = "2";
BODY = "CAPP","I62": #LOCATION = "C6R16" !CDS_LOCATION = "C6R16" #SEC = "1" !CDS_SEC = "1";
"A":   PN = "1"  !CDS_PN = "1";
"B":   PN = "2"  !CDS_PN = "2";
BODY = "CAP_A","I68": #LOCATION = "C4F1" !CDS_LOCATION = "C4F1" #SEC = "1" !CDS_SEC = "1";
"A":   PN = "1"  !CDS_PN = "1";
"B":   PN = "2"  !CDS_PN = "2";
BODY = "CAP_A","I70": #LOCATION = "C4F3" !CDS_LOCATION = "C4F3" #SEC = "1" !CDS_SEC = "1";
"A":   PN = "1"  !CDS_PN = "1";
"B":   PN = "2"  !CDS_PN = "2";
BODY = "CAP_A","I140": #LOCATION = "C3F1" !CDS_LOCATION = "C3F1" #SEC = "1" !CDS_SEC = "1";
"A":   PN = "1"  !CDS_PN = "1";
"B":   PN = "2"  !CDS_PN = "2";
BODY = "CAP_A","I141": #LOCATION = "C4F2" !CDS_LOCATION = "C4F2" #SEC = "1" !CDS_SEC = "1";
"A":   PN = "1"  !CDS_PN = "1";
"B":   PN = "2"  !CDS_PN = "2";
BODY = "RES","I169": #LOCATION = "R4C12" !CDS_LOCATION = "R4C12" #SEC = "1" !CDS_SEC = "1";
"A":   PN = "1"  !CDS_PN = "1";
"B":   PN = "2"  !CDS_PN = "2";
BODY = "RES","I170": #LOCATION = "R4C11" !CDS_LOCATION = "R4C11" #SEC = "1" !CDS_SEC = "1";
"A":   PN = "1"  !CDS_PN = "1";
"B":   PN = "2"  !CDS_PN = "2";
BODY = "CAPP","I175": #LOCATION = "C4E29" !CDS_LOCATION = "C4E29" #SEC = "1" !CDS_SEC = "1";
"A":   PN = "1"  !CDS_PN = "1";
"B":   PN = "2"  !CDS_PN = "2";
DRAWING = "@baseboard_fab2_lib.baseboard_fab2(sch_1):page194";
BODY = "CAP_A","I9": #LOCATION = "C4T2" !CDS_LOCATION = "C4T2" #SEC = "1" !CDS_SEC = "1";
"A":   PN = "1"  !CDS_PN = "1";
"B":   PN = "2"  !CDS_PN = "2";
BODY = "CAP_A","I16": #LOCATION = "C4T1" !CDS_LOCATION = "C4T1" #SEC = "1" !CDS_SEC = "1";
"A":   PN = "1"  !CDS_PN = "1";
"B":   PN = "2"  !CDS_PN = "2";
BODY = "CAPP","I29": #LOCATION = "C4R1" !CDS_LOCATION = "C4R1" #SEC = "1" !CDS_SEC = "1";
"A":   PN = "1"  !CDS_PN = "1";
"B":   PN = "2"  !CDS_PN = "2";
BODY = "CAPP","I31": #LOCATION = "C3R4" !CDS_LOCATION = "C3R4" &SEC = "1" #&CDS_SEC = "1";
"A":   PN = "1"  !CDS_PN = "1";
"B":   PN = "2"  !CDS_PN = "2";
BODY = "SCONN120_H61426002","I55": #LOCATION = "J6E1" !CDS_LOCATION = "J6E1" #SEC = "1" !CDS_SEC = "1";
"IOA1":   PN = "A1"  !CDS_PN = "A1";
"IOA2":   PN = "A2"  !CDS_PN = "A2";
"IOA3":   PN = "A3"  !CDS_PN = "A3";
"IOA4":   PN = "A4"  !CDS_PN = "A4";
"IOA5":   PN = "A5"  !CDS_PN = "A5";
"IOA6":   PN = "A6"  !CDS_PN = "A6";
"IOA7":   PN = "A7"  !CDS_PN = "A7";
"IOA8":   PN = "A8"  !CDS_PN = "A8";
"IOA9":   PN = "A9"  !CDS_PN = "A9";
"IOA10":   PN = "A10"  !CDS_PN = "A10";
"IOA11":   PN = "A11"  !CDS_PN = "A11";
"IOA12":   PN = "A12"  !CDS_PN = "A12";
"IOA13":   PN = "A13"  !CDS_PN = "A13";
"IOA14":   PN = "A14"  !CDS_PN = "A14";
"IOA15":   PN = "A15"  !CDS_PN = "A15";
"IOA16":   PN = "A16"  !CDS_PN = "A16";
"IOA17":   PN = "A17"  !CDS_PN = "A17";
"IOA18":   PN = "A18"  !CDS_PN = "A18";
"IOA19":   PN = "A19"  !CDS_PN = "A19";
"IOA20":   PN = "A20"  !CDS_PN = "A20";
"IOB1":   PN = "B1"  !CDS_PN = "B1";
"IOB2":   PN = "B2"  !CDS_PN = "B2";
"IOB3":   PN = "B3"  !CDS_PN = "B3";
"IOB4":   PN = "B4"  !CDS_PN = "B4";
"IOB5":   PN = "B5"  !CDS_PN = "B5";
"IOB6":   PN = "B6"  !CDS_PN = "B6";
"IOB7":   PN = "B7"  !CDS_PN = "B7";
"IOB8":   PN = "B8"  !CDS_PN = "B8";
"IOB9":   PN = "B9"  !CDS_PN = "B9";
"IOB10":   PN = "B10"  !CDS_PN = "B10";
"IOB11":   PN = "B11"  !CDS_PN = "B11";
"IOB12":   PN = "B12"  !CDS_PN = "B12";
"IOB13":   PN = "B13"  !CDS_PN = "B13";
"IOB14":   PN = "B14"  !CDS_PN = "B14";
"IOB15":   PN = "B15"  !CDS_PN = "B15";
"IOB16":   PN = "B16"  !CDS_PN = "B16";
"IOB17":   PN = "B17"  !CDS_PN = "B17";
"IOB18":   PN = "B18"  !CDS_PN = "B18";
"IOB19":   PN = "B19"  !CDS_PN = "B19";
"IOB20":   PN = "B20"  !CDS_PN = "B20";
"IOC1":   PN = "C1"  !CDS_PN = "C1";
"IOC2":   PN = "C2"  !CDS_PN = "C2";
"IOC3":   PN = "C3"  !CDS_PN = "C3";
"IOC4":   PN = "C4"  !CDS_PN = "C4";
"IOC5":   PN = "C5"  !CDS_PN = "C5";
"IOC6":   PN = "C6"  !CDS_PN = "C6";
"IOC7":   PN = "C7"  !CDS_PN = "C7";
"IOC8":   PN = "C8"  !CDS_PN = "C8";
"IOC9":   PN = "C9"  !CDS_PN = "C9";
"IOC10":   PN = "C10"  !CDS_PN = "C10";
"IOC11":   PN = "C11"  !CDS_PN = "C11";
"IOC12":   PN = "C12"  !CDS_PN = "C12";
"IOC13":   PN = "C13"  !CDS_PN = "C13";
"IOC14":   PN = "C14"  !CDS_PN = "C14";
"IOC15":   PN = "C15"  !CDS_PN = "C15";
"IOC16":   PN = "C16"  !CDS_PN = "C16";
"IOC17":   PN = "C17"  !CDS_PN = "C17";
"IOC18":   PN = "C18"  !CDS_PN = "C18";
"IOC19":   PN = "C19"  !CDS_PN = "C19";
"IOC20":   PN = "C20"  !CDS_PN = "C20";
"IOD1":   PN = "D1"  !CDS_PN = "D1";
"IOD2":   PN = "D2"  !CDS_PN = "D2";
"IOD3":   PN = "D3"  !CDS_PN = "D3";
"IOD4":   PN = "D4"  !CDS_PN = "D4";
"IOD5":   PN = "D5"  !CDS_PN = "D5";
"IOD6":   PN = "D6"  !CDS_PN = "D6";
"IOD7":   PN = "D7"  !CDS_PN = "D7";
"IOD8":   PN = "D8"  !CDS_PN = "D8";
"IOD9":   PN = "D9"  !CDS_PN = "D9";
"IOD10":   PN = "D10"  !CDS_PN = "D10";
"IOD11":   PN = "D11"  !CDS_PN = "D11";
"IOD12":   PN = "D12"  !CDS_PN = "D12";
"IOD13":   PN = "D13"  !CDS_PN = "D13";
"IOD14":   PN = "D14"  !CDS_PN = "D14";
"IOD15":   PN = "D15"  !CDS_PN = "D15";
"IOD16":   PN = "D16"  !CDS_PN = "D16";
"IOD17":   PN = "D17"  !CDS_PN = "D17";
"IOD18":   PN = "D18"  !CDS_PN = "D18";
"IOD19":   PN = "D19"  !CDS_PN = "D19";
"IOD20":   PN = "D20"  !CDS_PN = "D20";
"IOE1":   PN = "E1"  !CDS_PN = "E1";
"IOE2":   PN = "E2"  !CDS_PN = "E2";
"IOE3":   PN = "E3"  !CDS_PN = "E3";
"IOE4":   PN = "E4"  !CDS_PN = "E4";
"IOE5":   PN = "E5"  !CDS_PN = "E5";
"IOE6":   PN = "E6"  !CDS_PN = "E6";
"IOE7":   PN = "E7"  !CDS_PN = "E7";
"IOE8":   PN = "E8"  !CDS_PN = "E8";
"IOE9":   PN = "E9"  !CDS_PN = "E9";
"IOE10":   PN = "E10"  !CDS_PN = "E10";
"IOE11":   PN = "E11"  !CDS_PN = "E11";
"IOE12":   PN = "E12"  !CDS_PN = "E12";
"IOE13":   PN = "E13"  !CDS_PN = "E13";
"IOE14":   PN = "E14"  !CDS_PN = "E14";
"IOE15":   PN = "E15"  !CDS_PN = "E15";
"IOE16":   PN = "E16"  !CDS_PN = "E16";
"IOE17":   PN = "E17"  !CDS_PN = "E17";
"IOE18":   PN = "E18"  !CDS_PN = "E18";
"IOE19":   PN = "E19"  !CDS_PN = "E19";
"IOE20":   PN = "E20"  !CDS_PN = "E20";
"IOF1":   PN = "F1"  !CDS_PN = "F1";
"IOF2":   PN = "F2"  !CDS_PN = "F2";
"IOF3":   PN = "F3"  !CDS_PN = "F3";
"IOF4":   PN = "F4"  !CDS_PN = "F4";
"IOF5":   PN = "F5"  !CDS_PN = "F5";
"IOF6":   PN = "F6"  !CDS_PN = "F6";
"IOF7":   PN = "F7"  !CDS_PN = "F7";
"IOF8":   PN = "F8"  !CDS_PN = "F8";
"IOF9":   PN = "F9"  !CDS_PN = "F9";
"IOF10":   PN = "F10"  !CDS_PN = "F10";
"IOF11":   PN = "F11"  !CDS_PN = "F11";
"IOF12":   PN = "F12"  !CDS_PN = "F12";
"IOF13":   PN = "F13"  !CDS_PN = "F13";
"IOF14":   PN = "F14"  !CDS_PN = "F14";
"IOF15":   PN = "F15"  !CDS_PN = "F15";
"IOF16":   PN = "F16"  !CDS_PN = "F16";
"IOF17":   PN = "F17"  !CDS_PN = "F17";
"IOF18":   PN = "F18"  !CDS_PN = "F18";
"IOF19":   PN = "F19"  !CDS_PN = "F19";
"IOF20":   PN = "F20"  !CDS_PN = "F20";
BODY = "SCONN120_H61426002","I56": #LOCATION = "J6B1" !CDS_LOCATION = "J6B1" #SEC = "1" !CDS_SEC = "1";
"IOA1":   PN = "A1"  !CDS_PN = "A1";
"IOA2":   PN = "A2"  !CDS_PN = "A2";
"IOA3":   PN = "A3"  !CDS_PN = "A3";
"IOA4":   PN = "A4"  !CDS_PN = "A4";
"IOA5":   PN = "A5"  !CDS_PN = "A5";
"IOA6":   PN = "A6"  !CDS_PN = "A6";
"IOA7":   PN = "A7"  !CDS_PN = "A7";
"IOA8":   PN = "A8"  !CDS_PN = "A8";
"IOA9":   PN = "A9"  !CDS_PN = "A9";
"IOA10":   PN = "A10"  !CDS_PN = "A10";
"IOA11":   PN = "A11"  !CDS_PN = "A11";
"IOA12":   PN = "A12"  !CDS_PN = "A12";
"IOA13":   PN = "A13"  !CDS_PN = "A13";
"IOA14":   PN = "A14"  !CDS_PN = "A14";
"IOA15":   PN = "A15"  !CDS_PN = "A15";
"IOA16":   PN = "A16"  !CDS_PN = "A16";
"IOA17":   PN = "A17"  !CDS_PN = "A17";
"IOA18":   PN = "A18"  !CDS_PN = "A18";
"IOA19":   PN = "A19"  !CDS_PN = "A19";
"IOA20":   PN = "A20"  !CDS_PN = "A20";
"IOB1":   PN = "B1"  !CDS_PN = "B1";
"IOB2":   PN = "B2"  !CDS_PN = "B2";
"IOB3":   PN = "B3"  !CDS_PN = "B3";
"IOB4":   PN = "B4"  !CDS_PN = "B4";
"IOB5":   PN = "B5"  !CDS_PN = "B5";
"IOB6":   PN = "B6"  !CDS_PN = "B6";
"IOB7":   PN = "B7"  !CDS_PN = "B7";
"IOB8":   PN = "B8"  !CDS_PN = "B8";
"IOB9":   PN = "B9"  !CDS_PN = "B9";
"IOB10":   PN = "B10"  !CDS_PN = "B10";
"IOB11":   PN = "B11"  !CDS_PN = "B11";
"IOB12":   PN = "B12"  !CDS_PN = "B12";
"IOB13":   PN = "B13"  !CDS_PN = "B13";
"IOB14":   PN = "B14"  !CDS_PN = "B14";
"IOB15":   PN = "B15"  !CDS_PN = "B15";
"IOB16":   PN = "B16"  !CDS_PN = "B16";
"IOB17":   PN = "B17"  !CDS_PN = "B17";
"IOB18":   PN = "B18"  !CDS_PN = "B18";
"IOB19":   PN = "B19"  !CDS_PN = "B19";
"IOB20":   PN = "B20"  !CDS_PN = "B20";
"IOC1":   PN = "C1"  !CDS_PN = "C1";
"IOC2":   PN = "C2"  !CDS_PN = "C2";
"IOC3":   PN = "C3"  !CDS_PN = "C3";
"IOC4":   PN = "C4"  !CDS_PN = "C4";
"IOC5":   PN = "C5"  !CDS_PN = "C5";
"IOC6":   PN = "C6"  !CDS_PN = "C6";
"IOC7":   PN = "C7"  !CDS_PN = "C7";
"IOC8":   PN = "C8"  !CDS_PN = "C8";
"IOC9":   PN = "C9"  !CDS_PN = "C9";
"IOC10":   PN = "C10"  !CDS_PN = "C10";
"IOC11":   PN = "C11"  !CDS_PN = "C11";
"IOC12":   PN = "C12"  !CDS_PN = "C12";
"IOC13":   PN = "C13"  !CDS_PN = "C13";
"IOC14":   PN = "C14"  !CDS_PN = "C14";
"IOC15":   PN = "C15"  !CDS_PN = "C15";
"IOC16":   PN = "C16"  !CDS_PN = "C16";
"IOC17":   PN = "C17"  !CDS_PN = "C17";
"IOC18":   PN = "C18"  !CDS_PN = "C18";
"IOC19":   PN = "C19"  !CDS_PN = "C19";
"IOC20":   PN = "C20"  !CDS_PN = "C20";
"IOD1":   PN = "D1"  !CDS_PN = "D1";
"IOD2":   PN = "D2"  !CDS_PN = "D2";
"IOD3":   PN = "D3"  !CDS_PN = "D3";
"IOD4":   PN = "D4"  !CDS_PN = "D4";
"IOD5":   PN = "D5"  !CDS_PN = "D5";
"IOD6":   PN = "D6"  !CDS_PN = "D6";
"IOD7":   PN = "D7"  !CDS_PN = "D7";
"IOD8":   PN = "D8"  !CDS_PN = "D8";
"IOD9":   PN = "D9"  !CDS_PN = "D9";
"IOD10":   PN = "D10"  !CDS_PN = "D10";
"IOD11":   PN = "D11"  !CDS_PN = "D11";
"IOD12":   PN = "D12"  !CDS_PN = "D12";
"IOD13":   PN = "D13"  !CDS_PN = "D13";
"IOD14":   PN = "D14"  !CDS_PN = "D14";
"IOD15":   PN = "D15"  !CDS_PN = "D15";
"IOD16":   PN = "D16"  !CDS_PN = "D16";
"IOD17":   PN = "D17"  !CDS_PN = "D17";
"IOD18":   PN = "D18"  !CDS_PN = "D18";
"IOD19":   PN = "D19"  !CDS_PN = "D19";
"IOD20":   PN = "D20"  !CDS_PN = "D20";
"IOE1":   PN = "E1"  !CDS_PN = "E1";
"IOE2":   PN = "E2"  !CDS_PN = "E2";
"IOE3":   PN = "E3"  !CDS_PN = "E3";
"IOE4":   PN = "E4"  !CDS_PN = "E4";
"IOE5":   PN = "E5"  !CDS_PN = "E5";
"IOE6":   PN = "E6"  !CDS_PN = "E6";
"IOE7":   PN = "E7"  !CDS_PN = "E7";
"IOE8":   PN = "E8"  !CDS_PN = "E8";
"IOE9":   PN = "E9"  !CDS_PN = "E9";
"IOE10":   PN = "E10"  !CDS_PN = "E10";
"IOE11":   PN = "E11"  !CDS_PN = "E11";
"IOE12":   PN = "E12"  !CDS_PN = "E12";
"IOE13":   PN = "E13"  !CDS_PN = "E13";
"IOE14":   PN = "E14"  !CDS_PN = "E14";
"IOE15":   PN = "E15"  !CDS_PN = "E15";
"IOE16":   PN = "E16"  !CDS_PN = "E16";
"IOE17":   PN = "E17"  !CDS_PN = "E17";
"IOE18":   PN = "E18"  !CDS_PN = "E18";
"IOE19":   PN = "E19"  !CDS_PN = "E19";
"IOE20":   PN = "E20"  !CDS_PN = "E20";
"IOF1":   PN = "F1"  !CDS_PN = "F1";
"IOF2":   PN = "F2"  !CDS_PN = "F2";
"IOF3":   PN = "F3"  !CDS_PN = "F3";
"IOF4":   PN = "F4"  !CDS_PN = "F4";
"IOF5":   PN = "F5"  !CDS_PN = "F5";
"IOF6":   PN = "F6"  !CDS_PN = "F6";
"IOF7":   PN = "F7"  !CDS_PN = "F7";
"IOF8":   PN = "F8"  !CDS_PN = "F8";
"IOF9":   PN = "F9"  !CDS_PN = "F9";
"IOF10":   PN = "F10"  !CDS_PN = "F10";
"IOF11":   PN = "F11"  !CDS_PN = "F11";
"IOF12":   PN = "F12"  !CDS_PN = "F12";
"IOF13":   PN = "F13"  !CDS_PN = "F13";
"IOF14":   PN = "F14"  !CDS_PN = "F14";
"IOF15":   PN = "F15"  !CDS_PN = "F15";
"IOF16":   PN = "F16"  !CDS_PN = "F16";
"IOF17":   PN = "F17"  !CDS_PN = "F17";
"IOF18":   PN = "F18"  !CDS_PN = "F18";
"IOF19":   PN = "F19"  !CDS_PN = "F19";
"IOF20":   PN = "F20"  !CDS_PN = "F20";
BODY = "CAP_A","I86": #LOCATION = "C3N40" !CDS_LOCATION = "C3N40" #SEC = "1" !CDS_SEC = "1";
"A":   PN = "1"  !CDS_PN = "1";
"B":   PN = "2"  !CDS_PN = "2";
BODY = "CAP_A","I99": #LOCATION = "C3M46" !CDS_LOCATION = "C3M46" #SEC = "1" !CDS_SEC = "1";
"A":   PN = "1"  !CDS_PN = "1";
"B":   PN = "2"  !CDS_PN = "2";
BODY = "CAPP","I101": #LOCATION = "C3N14" !CDS_LOCATION = "C3N14" #SEC = "1" !CDS_SEC = "1";
"A":   PN = "1"  !CDS_PN = "1";
"B":   PN = "2"  !CDS_PN = "2";
BODY = "CAP_A","I149": #LOCATION = "C3T1" !CDS_LOCATION = "C3T1" #SEC = "1" !CDS_SEC = "1";
"A":   PN = "1"  !CDS_PN = "1";
"B":   PN = "2"  !CDS_PN = "2";
BODY = "CAP_A","I150": #LOCATION = "C3T2" !CDS_LOCATION = "C3T2" #SEC = "1" !CDS_SEC = "1";
"A":   PN = "1"  !CDS_PN = "1";
"B":   PN = "2"  !CDS_PN = "2";
BODY = "RES","I155": #LOCATION = "R7C24" !CDS_LOCATION = "R7C24" #SEC = "1" !CDS_SEC = "1";
"A":   PN = "1"  !CDS_PN = "1";
"B":   PN = "2"  !CDS_PN = "2";
BODY = "RES","I156": #LOCATION = "R3N29" !CDS_LOCATION = "R3N29" #SEC = "1" !CDS_SEC = "1";
"A":   PN = "1"  !CDS_PN = "1";
"B":   PN = "2"  !CDS_PN = "2";
DRAWING = "@baseboard_fab2_lib.baseboard_fab2(sch_1):page195";
BODY = "CONN3_G98259001","I26": #LOCATION = "RM1E1" !CDS_LOCATION = "RM1E1" &SEC = "1" #&CDS_SEC = "1";
"IO1":   PN = "1"  !CDS_PN = "1";
"IO2":   PN = "2"  !CDS_PN = "2";
"IO3":   PN = "3"  !CDS_PN = "3";
BODY = "CAP","I31": #LOCATION = "C9R5" !CDS_LOCATION = "C9R5" #SEC = "1" !CDS_SEC = "1";
"A":   PN = "1"  !CDS_PN = "1";
"B":   PN = "2"  !CDS_PN = "2";
BODY = "CAP","I32": #LOCATION = "C1E12" !CDS_LOCATION = "C1E12" #SEC = "1" !CDS_SEC = "1";
"A":   PN = "1"  !CDS_PN = "1";
"B":   PN = "2"  !CDS_PN = "2";
BODY = "CAP","I35": #LOCATION = "C1E15" !CDS_LOCATION = "C1E15" #SEC = "1" !CDS_SEC = "1";
"A":   PN = "1"  !CDS_PN = "1";
"B":   PN = "2"  !CDS_PN = "2";
BODY = "CAP_A","I36": #LOCATION = "C9R12" !CDS_LOCATION = "C9R12" #SEC = "1" !CDS_SEC = "1";
"A":   PN = "1"  !CDS_PN = "1";
"B":   PN = "2"  !CDS_PN = "2";
BODY = "CAP_A","I37": #LOCATION = "C9R6" !CDS_LOCATION = "C9R6" #SEC = "1" !CDS_SEC = "1";
"A":   PN = "1"  !CDS_PN = "1";
"B":   PN = "2"  !CDS_PN = "2";
BODY = "CAP_A","I38": #LOCATION = "C1E17" !CDS_LOCATION = "C1E17" #SEC = "1" !CDS_SEC = "1";
"A":   PN = "1"  !CDS_PN = "1";
"B":   PN = "2"  !CDS_PN = "2";
BODY = "CAP_A","I39": #LOCATION = "C1E16" !CDS_LOCATION = "C1E16" #SEC = "1" !CDS_SEC = "1";
"A":   PN = "1"  !CDS_PN = "1";
"B":   PN = "2"  !CDS_PN = "2";
BODY = "MTG_KEYHOLE","I49": #LOCATION = "TH4G1" !CDS_LOCATION = "TH4G1" &SEC = "1" #&CDS_SEC = "1";
"1":   PN = "1"  !CDS_PN = "1";
BODY = "MTG_KEYHOLE","I52": #LOCATION = "TH9G1" !CDS_LOCATION = "TH9G1" &SEC = "1" #&CDS_SEC = "1";
"1":   PN = "1"  !CDS_PN = "1";
BODY = "MTG_KEYHOLE","I54": #LOCATION = "TH9A1" !CDS_LOCATION = "TH9A1" &SEC = "1" #&CDS_SEC = "1";
"1":   PN = "1"  !CDS_PN = "1";
BODY = "MTG_KEYHOLE","I56": #LOCATION = "TH1A1" !CDS_LOCATION = "TH1A1" &SEC = "1" #&CDS_SEC = "1";
"1":   PN = "1"  !CDS_PN = "1";
BODY = "MTG_KEYHOLE","I62": #LOCATION = "TH4A1" !CDS_LOCATION = "TH4A1" &SEC = "1" #&CDS_SEC = "1";
"1":   PN = "1"  !CDS_PN = "1";
BODY = "MTG_KEYHOLE","I65": #LOCATION = "TH7A1" !CDS_LOCATION = "TH7A1" &SEC = "1" #&CDS_SEC = "1";
"1":   PN = "1"  !CDS_PN = "1";
BODY = "MTG_KEYHOLE","I67": #LOCATION = "TH7G1" !CDS_LOCATION = "TH7G1" &SEC = "1" #&CDS_SEC = "1";
"1":   PN = "1"  !CDS_PN = "1";
BODY = "CAPP","I82": #LOCATION = "C4F6" !CDS_LOCATION = "C4F6" &SEC = "1" #&CDS_SEC = "1";
"A":   PN = "1"  !CDS_PN = "1";
"B":   PN = "2"  !CDS_PN = "2";
BODY = "CAPP","I83": #LOCATION = "C4B13" !CDS_LOCATION = "C4B13" &SEC = "1" #&CDS_SEC = "1";
"A":   PN = "1"  !CDS_PN = "1";
"B":   PN = "2"  !CDS_PN = "2";
BODY = "CAPP","I84": #LOCATION = "C1B14" !CDS_LOCATION = "C1B14" &SEC = "1" #&CDS_SEC = "1";
"A":   PN = "1"  !CDS_PN = "1";
"B":   PN = "2"  !CDS_PN = "2";
BODY = "CAPP","I85": #LOCATION = "C1F7" !CDS_LOCATION = "C1F7" &SEC = "1" #&CDS_SEC = "1";
"A":   PN = "1"  !CDS_PN = "1";
"B":   PN = "2"  !CDS_PN = "2";
BODY = "CAPP","I96": #LOCATION = "C4F5" !CDS_LOCATION = "C4F5" #SEC = "1" !CDS_SEC = "1";
"A":   PN = "1"  !CDS_PN = "1";
"B":   PN = "2"  !CDS_PN = "2";
BODY = "CAPP","I97": #LOCATION = "C4B14" !CDS_LOCATION = "C4B14" #SEC = "1" !CDS_SEC = "1";
"A":   PN = "1"  !CDS_PN = "1";
"B":   PN = "2"  !CDS_PN = "2";
BODY = "CAPP","I98": #LOCATION = "C3T6" !CDS_LOCATION = "C3T6" #SEC = "1" !CDS_SEC = "1";
"A":   PN = "1"  !CDS_PN = "1";
"B":   PN = "2"  !CDS_PN = "2";
BODY = "CAPP","I99": #LOCATION = "C9M3" !CDS_LOCATION = "C9M3" #SEC = "1" !CDS_SEC = "1";
"A":   PN = "1"  !CDS_PN = "1";
"B":   PN = "2"  !CDS_PN = "2";
BODY = "CAPP","I100": #LOCATION = "C3B6" !CDS_LOCATION = "C3B6" #SEC = "1" !CDS_SEC = "1";
"A":   PN = "1"  !CDS_PN = "1";
"B":   PN = "2"  !CDS_PN = "2";
BODY = "CAPP","I101": #LOCATION = "C1R23" !CDS_LOCATION = "C1R23" #SEC = "1" !CDS_SEC = "1";
"A":   PN = "1"  !CDS_PN = "1";
"B":   PN = "2"  !CDS_PN = "2";
BODY = "CAPP","I102": #LOCATION = "C4M6" !CDS_LOCATION = "C4M6" #SEC = "1" !CDS_SEC = "1";
"A":   PN = "1"  !CDS_PN = "1";
"B":   PN = "2"  !CDS_PN = "2";
BODY = "CAPP","I103": #LOCATION = "C1M5" !CDS_LOCATION = "C1M5" #SEC = "1" !CDS_SEC = "1";
"A":   PN = "1"  !CDS_PN = "1";
"B":   PN = "2"  !CDS_PN = "2";
BODY = "CAPP","I104": #LOCATION = "C3T13" !CDS_LOCATION = "C3T13" #SEC = "1" !CDS_SEC = "1";
"A":   PN = "1"  !CDS_PN = "1";
"B":   PN = "2"  !CDS_PN = "2";
BODY = "CAPP","I105": #LOCATION = "C4M7" !CDS_LOCATION = "C4M7" #SEC = "1" !CDS_SEC = "1";
"A":   PN = "1"  !CDS_PN = "1";
"B":   PN = "2"  !CDS_PN = "2";
BODY = "CAPP","I106": #LOCATION = "C3T15" !CDS_LOCATION = "C3T15" #SEC = "1" !CDS_SEC = "1";
"A":   PN = "1"  !CDS_PN = "1";
"B":   PN = "2"  !CDS_PN = "2";
BODY = "CAPP","I108": #LOCATION = "C7M6" !CDS_LOCATION = "C7M6" #SEC = "1" !CDS_SEC = "1";
"A":   PN = "1"  !CDS_PN = "1";
"B":   PN = "2"  !CDS_PN = "2";
BODY = "CAPP","I109": #LOCATION = "C6N5" !CDS_LOCATION = "C6N5" #SEC = "1" !CDS_SEC = "1";
"A":   PN = "1"  !CDS_PN = "1";
"B":   PN = "2"  !CDS_PN = "2";
BODY = "CAPP","I111": #LOCATION = "C9T3" !CDS_LOCATION = "C9T3" #SEC = "1" !CDS_SEC = "1";
"A":   PN = "1"  !CDS_PN = "1";
"B":   PN = "2"  !CDS_PN = "2";
BODY = "CAPP","I112": #LOCATION = "C4F4" !CDS_LOCATION = "C4F4" #SEC = "1" !CDS_SEC = "1";
"A":   PN = "1"  !CDS_PN = "1";
"B":   PN = "2"  !CDS_PN = "2";
BODY = "CAPP","I113": #LOCATION = "C3T3" !CDS_LOCATION = "C3T3" #SEC = "1" !CDS_SEC = "1";
"A":   PN = "1"  !CDS_PN = "1";
"B":   PN = "2"  !CDS_PN = "2";
BODY = "FCI-CONN12-2R-GP","I114": #LOCATION = "J1E1" !CDS_LOCATION = "J1E1" #SEC = "1" !CDS_SEC = "1";
"1_1":   PN = "1_1"  !CDS_PN = "1_1";
"1_2":   PN = "1_2"  !CDS_PN = "1_2";
"1_3":   PN = "1_3"  !CDS_PN = "1_3";
"2_1":   PN = "2_1"  !CDS_PN = "2_1";
"2_2":   PN = "2_2"  !CDS_PN = "2_2";
"2_3":   PN = "2_3"  !CDS_PN = "2_3";
"3_1":   PN = "3_1"  !CDS_PN = "3_1";
"3_2":   PN = "3_2"  !CDS_PN = "3_2";
"3_3":   PN = "3_3"  !CDS_PN = "3_3";
"4_1":   PN = "4_1"  !CDS_PN = "4_1";
"4_2":   PN = "4_2"  !CDS_PN = "4_2";
"4_3":   PN = "4_3"  !CDS_PN = "4_3";
"NP1":   PN = "NP1"  !CDS_PN = "NP1";
BODY = "FCI-CONN12-2R-GP","I115": #LOCATION = "J1D1" !CDS_LOCATION = "J1D1" #SEC = "1" !CDS_SEC = "1";
"1_1":   PN = "1_1"  !CDS_PN = "1_1";
"1_2":   PN = "1_2"  !CDS_PN = "1_2";
"1_3":   PN = "1_3"  !CDS_PN = "1_3";
"2_1":   PN = "2_1"  !CDS_PN = "2_1";
"2_2":   PN = "2_2"  !CDS_PN = "2_2";
"2_3":   PN = "2_3"  !CDS_PN = "2_3";
"3_1":   PN = "3_1"  !CDS_PN = "3_1";
"3_2":   PN = "3_2"  !CDS_PN = "3_2";
"3_3":   PN = "3_3"  !CDS_PN = "3_3";
"4_1":   PN = "4_1"  !CDS_PN = "4_1";
"4_2":   PN = "4_2"  !CDS_PN = "4_2";
"4_3":   PN = "4_3"  !CDS_PN = "4_3";
"NP1":   PN = "NP1"  !CDS_PN = "NP1";
BODY = "STFT363B238R224H453-GP","I117": #LOCATION = "RM1G1" !CDS_LOCATION = "RM1G1" #SEC = "1" !CDS_SEC = "1";
"1":   PN = "1"  !CDS_PN = "1";
DRAWING = "@baseboard_fab2_lib.baseboard_fab2(sch_1):page196";
BODY = "RES","I46": #LOCATION = "R2U43" !CDS_LOCATION = "R2U43" #SEC = "1" !CDS_SEC = "1";
"A":   PN = "1"  !CDS_PN = "1";
"B":   PN = "2"  !CDS_PN = "2";
BODY = "BATTERY","I47": #LOCATION = "BT8G1" !CDS_LOCATION = "BT8G1";
BODY = "VERT_BATT_3PIN","I51": #LOCATION = "XBT8G1" !CDS_LOCATION = "XBT8G1" #SEC = "1" !CDS_SEC = "1";
"N":   PN = "3"  !CDS_PN = "3";
"P1":   PN = "1"  !CDS_PN = "1";
"P2":   PN = "2"  !CDS_PN = "2";
BODY = "DIODE2A_DUAL","I53": #LOCATION = "CR2U1" !CDS_LOCATION = "CR2U1" #SEC = "1" !CDS_SEC = "1";
"A1":   PN = "1"  !CDS_PN = "1";
"A2":   PN = "2"  !CDS_PN = "2";
"C":   PN = "3"  !CDS_PN = "3";
BODY = "RES","I59": #LOCATION = "R3P44" !CDS_LOCATION = "R3P44" #SEC = "1" !CDS_SEC = "1";
"A":   PN = "1"  !CDS_PN = "1";
"B":   PN = "2"  !CDS_PN = "2";
BODY = "CAP","I60": #LOCATION = "C3P45" !CDS_LOCATION = "C3P45" #SEC = "1" !CDS_SEC = "1";
"A":   PN = "1"  !CDS_PN = "1";
"B":   PN = "2"  !CDS_PN = "2";
BODY = "RES","I65": #LOCATION = "R2P20" !CDS_LOCATION = "R2P20" #SEC = "1" !CDS_SEC = "1";
"A":   PN = "1"  !CDS_PN = "1";
"B":   PN = "2"  !CDS_PN = "2";
BODY = "RES","I68": #LOCATION = "R1L16" !CDS_LOCATION = "R1L16" #SEC = "1" !CDS_SEC = "1";
"A":   PN = "1"  !CDS_PN = "1";
"B":   PN = "2"  !CDS_PN = "2";
BODY = "ADM1085","I70": #LOCATION = "U7D3" !CDS_LOCATION = "U7D3" #SEC = "1" !CDS_SEC = "1";
"CEXT":   PN = "5"  !CDS_PN = "5";
"ENIN":   PN = "1"  !CDS_PN = "1";
"ENOUT":   PN = "4"  !CDS_PN = "4";
"GND":   PN = "2"  !CDS_PN = "2";
"VCC":   PN = "6"  !CDS_PN = "6";
"VIN":   PN = "3"  !CDS_PN = "3";
BODY = "RES","I71": #LOCATION = "R3P50" !CDS_LOCATION = "R3P50" #SEC = "1" !CDS_SEC = "1";
"A":   PN = "1"  !CDS_PN = "1";
"B":   PN = "2"  !CDS_PN = "2";
BODY = "CAP_A","I72": #LOCATION = "C3P46" !CDS_LOCATION = "C3P46" #SEC = "1" !CDS_SEC = "1";
"A":   PN = "1"  !CDS_PN = "1";
"B":   PN = "2"  !CDS_PN = "2";
BODY = "RES","I74": #LOCATION = "R3P48" !CDS_LOCATION = "R3P48" #SEC = "1" !CDS_SEC = "1";
"A":   PN = "1"  !CDS_PN = "1";
"B":   PN = "2"  !CDS_PN = "2";
BODY = "RES","I75": #LOCATION = "R3P51" !CDS_LOCATION = "R3P51" #SEC = "1" !CDS_SEC = "1";
"A":   PN = "1"  !CDS_PN = "1";
"B":   PN = "2"  !CDS_PN = "2";
BODY = "ADM809","I80": #LOCATION = "U1L3" !CDS_LOCATION = "U1L3" &SEC = "1" #&CDS_SEC = "1";
"RESET_N":   PN = "2"  !CDS_PN = "2";
"VCC":   PN = "3"  !CDS_PN = "3";
BODY = "CAP_A","I81": #LOCATION = "C1L16" !CDS_LOCATION = "C1L16" #SEC = "1" !CDS_SEC = "1";
"A":   PN = "1"  !CDS_PN = "1";
"B":   PN = "2"  !CDS_PN = "2";
BODY = "ADM809","I89": #LOCATION = "U8E2" !CDS_LOCATION = "U8E2" &SEC = "1" #&CDS_SEC = "1";
"RESET_N":   PN = "2"  !CDS_PN = "2";
"VCC":   PN = "3"  !CDS_PN = "3";
BODY = "RES","I90": #LOCATION = "R8E7" !CDS_LOCATION = "R8E7" #SEC = "1" !CDS_SEC = "1";
"A":   PN = "1"  !CDS_PN = "1";
"B":   PN = "2"  !CDS_PN = "2";
BODY = "CAP_A","I94": #LOCATION = "C8E3" !CDS_LOCATION = "C8E3" #SEC = "1" !CDS_SEC = "1";
"A":   PN = "1"  !CDS_PN = "1";
"B":   PN = "2"  !CDS_PN = "2";
BODY = "CAP_A","I102": #LOCATION = "C2U26" !CDS_LOCATION = "C2U26" #SEC = "1" !CDS_SEC = "1";
"A":   PN = "1"  !CDS_PN = "1";
"B":   PN = "2"  !CDS_PN = "2";
BODY = "DIODE","I103": #LOCATION = "CR7E1" !CDS_LOCATION = "CR7E1" #SEC = "1" !CDS_SEC = "1";
"A":   PN = "2"  !CDS_PN = "2";
"C":   PN = "1"  !CDS_PN = "1";
BODY = "TPS3700","I104": #LOCATION = "U8D8" !CDS_LOCATION = "U8D8" &SEC = "1" #&CDS_SEC = "1";
"GND":   PN = "5"  !CDS_PN = "5";
"INAP":   PN = "4"  !CDS_PN = "4";
"INBN":   PN = "3"  !CDS_PN = "3";
"OUTA":   PN = "6"  !CDS_PN = "6";
"OUTB":   PN = "1"  !CDS_PN = "1";
"VDD":   PN = "2"  !CDS_PN = "2";
BODY = "CAP_A","I105": #LOCATION = "C8D4" !CDS_LOCATION = "C8D4" &SEC = "1" #&CDS_SEC = "1";
"A":   PN = "1"  !CDS_PN = "1";
"B":   PN = "2"  !CDS_PN = "2";
BODY = "RES","I106": #LOCATION = "R8D42" !CDS_LOCATION = "R8D42" #SEC = "1" !CDS_SEC = "1";
"A":   PN = "1"  !CDS_PN = "1";
"B":   PN = "2"  !CDS_PN = "2";
BODY = "RES","I112": #LOCATION = "R8D38" !CDS_LOCATION = "R8D38" #SEC = "1" !CDS_SEC = "1";
"A":   PN = "1"  !CDS_PN = "1";
"B":   PN = "2"  !CDS_PN = "2";
BODY = "RES","I114": #LOCATION = "R8D39" !CDS_LOCATION = "R8D39" #SEC = "1" !CDS_SEC = "1";
"A":   PN = "1"  !CDS_PN = "1";
"B":   PN = "2"  !CDS_PN = "2";
BODY = "RES","I115": #LOCATION = "R8D37" !CDS_LOCATION = "R8D37" #SEC = "1" !CDS_SEC = "1";
"A":   PN = "1"  !CDS_PN = "1";
"B":   PN = "2"  !CDS_PN = "2";
BODY = "RES","I120": #LOCATION = "R8D41" !CDS_LOCATION = "R8D41" #SEC = "1" !CDS_SEC = "1";
"A":   PN = "1"  !CDS_PN = "1";
"B":   PN = "2"  !CDS_PN = "2";
BODY = "RES","I121": #LOCATION = "R2P18" !CDS_LOCATION = "R2P18" #SEC = "1" !CDS_SEC = "1";
"A":   PN = "1"  !CDS_PN = "1";
"B":   PN = "2"  !CDS_PN = "2";
BODY = "RES","I122": #LOCATION = "R2P21" !CDS_LOCATION = "R2P21" #SEC = "1" !CDS_SEC = "1";
"A":   PN = "1"  !CDS_PN = "1";
"B":   PN = "2"  !CDS_PN = "2";
BODY = "DIODE","I128": #LOCATION = "CR8E1" !CDS_LOCATION = "CR8E1" #SEC = "1" !CDS_SEC = "1";
"A":   PN = "2"  !CDS_PN = "2";
"C":   PN = "1"  !CDS_PN = "1";
BODY = "FET_N","I129": #LOCATION = "Q1P2" !CDS_LOCATION = "Q1P2" &SEC = "1" #&CDS_SEC = "1";
"DRN":   PN = "3"  !CDS_PN = "3";
"GATE":   PN = "1"  !CDS_PN = "1";
"SRC":   PN = "2"  !CDS_PN = "2";
BODY = "RES","I130": #LOCATION = "R8D40" !CDS_LOCATION = "R8D40" #SEC = "1" !CDS_SEC = "1";
"A":   PN = "1"  !CDS_PN = "1";
"B":   PN = "2"  !CDS_PN = "2";
DRAWING = "@baseboard_fab2_lib.baseboard_fab2(sch_1):page198";
BODY = "SLG55021","I1": #LOCATION = "EU2T1" !CDS_LOCATION = "EU2T1" &SEC = "1" #&CDS_SEC = "1";
"D":   PN = "5"  !CDS_PN = "5";
"G":   PN = "7"  !CDS_PN = "7";
"GND":   PN = "4"  !CDS_PN = "4";
"ON":   PN = "2"  !CDS_PN = "2";
"PG":   PN = "8"  !CDS_PN = "8";
"S":   PN = "6"  !CDS_PN = "6";
"SHDN_N":   PN = "3"  !CDS_PN = "3";
"THPAD":   PN = "9"  !CDS_PN = "9";
"VCC":   PN = "1"  !CDS_PN = "1";
BODY = "SLG55021","I13": #LOCATION = "EU8B1" !CDS_LOCATION = "EU8B1" #SEC = "1" !CDS_SEC = "1";
"D":   PN = "5"  !CDS_PN = "5";
"G":   PN = "7"  !CDS_PN = "7";
"GND":   PN = "4"  !CDS_PN = "4";
"ON":   PN = "2"  !CDS_PN = "2";
"PG":   PN = "8"  !CDS_PN = "8";
"S":   PN = "6"  !CDS_PN = "6";
"SHDN_N":   PN = "3"  !CDS_PN = "3";
"THPAD":   PN = "9"  !CDS_PN = "9";
"VCC":   PN = "1"  !CDS_PN = "1";
BODY = "SLG55021","I19": #LOCATION = "EU7E1" !CDS_LOCATION = "EU7E1" #SEC = "1" !CDS_SEC = "1";
"D":   PN = "5"  !CDS_PN = "5";
"G":   PN = "7"  !CDS_PN = "7";
"GND":   PN = "4"  !CDS_PN = "4";
"ON":   PN = "2"  !CDS_PN = "2";
"PG":   PN = "8"  !CDS_PN = "8";
"S":   PN = "6"  !CDS_PN = "6";
"SHDN_N":   PN = "3"  !CDS_PN = "3";
"THPAD":   PN = "9"  !CDS_PN = "9";
"VCC":   PN = "1"  !CDS_PN = "1";
BODY = "CAP_A","I24": #LOCATION = "C8F17" !CDS_LOCATION = "C8F17" #SEC = "1" !CDS_SEC = "1";
"A":   PN = "1"  !CDS_PN = "1";
"B":   PN = "2"  !CDS_PN = "2";
BODY = "CAP_A","I26": #LOCATION = "C8B8" !CDS_LOCATION = "C8B8" #SEC = "1" !CDS_SEC = "1";
"A":   PN = "1"  !CDS_PN = "1";
"B":   PN = "2"  !CDS_PN = "2";
BODY = "CAP_A","I28": #LOCATION = "C8E19" !CDS_LOCATION = "C8E19" #SEC = "1" !CDS_SEC = "1";
"A":   PN = "1"  !CDS_PN = "1";
"B":   PN = "2"  !CDS_PN = "2";
BODY = "CAP_A","I37": #LOCATION = "C8B5" !CDS_LOCATION = "C8B5" #SEC = "1" !CDS_SEC = "1";
"A":   PN = "1"  !CDS_PN = "1";
"B":   PN = "2"  !CDS_PN = "2";
BODY = "CAP","I38": #LOCATION = "C8B12" !CDS_LOCATION = "C8B12" #SEC = "1" !CDS_SEC = "1";
"A":   PN = "1"  !CDS_PN = "1";
"B":   PN = "2"  !CDS_PN = "2";
BODY = "CAP","I40": #LOCATION = "C8B6" !CDS_LOCATION = "C8B6" #SEC = "1" !CDS_SEC = "1";
"A":   PN = "1"  !CDS_PN = "1";
"B":   PN = "2"  !CDS_PN = "2";
BODY = "CAP_A","I41": #LOCATION = "C8B7" !CDS_LOCATION = "C8B7" #SEC = "1" !CDS_SEC = "1";
"A":   PN = "1"  !CDS_PN = "1";
"B":   PN = "2"  !CDS_PN = "2";
BODY = "CAP_A","I43": #LOCATION = "C2T36" !CDS_LOCATION = "C2T36" #SEC = "1" !CDS_SEC = "1";
"A":   PN = "1"  !CDS_PN = "1";
"B":   PN = "2"  !CDS_PN = "2";
BODY = "CAP","I44": #LOCATION = "C2U1" !CDS_LOCATION = "C2U1" #SEC = "1" !CDS_SEC = "1";
"A":   PN = "1"  !CDS_PN = "1";
"B":   PN = "2"  !CDS_PN = "2";
BODY = "CAP_A","I46": #LOCATION = "C2U19" !CDS_LOCATION = "C2U19" #SEC = "1" !CDS_SEC = "1";
"A":   PN = "1"  !CDS_PN = "1";
"B":   PN = "2"  !CDS_PN = "2";
BODY = "CAP","I47": #LOCATION = "C2U2" !CDS_LOCATION = "C2U2" #SEC = "1" !CDS_SEC = "1";
"A":   PN = "1"  !CDS_PN = "1";
"B":   PN = "2"  !CDS_PN = "2";
BODY = "CAP_A","I49": #LOCATION = "C7E9" !CDS_LOCATION = "C7E9" #SEC = "1" !CDS_SEC = "1";
"A":   PN = "1"  !CDS_PN = "1";
"B":   PN = "2"  !CDS_PN = "2";
BODY = "CAP","I50": #LOCATION = "C7E8" !CDS_LOCATION = "C7E8" #SEC = "1" !CDS_SEC = "1";
"A":   PN = "1"  !CDS_PN = "1";
"B":   PN = "2"  !CDS_PN = "2";
BODY = "CAP_A","I52": #LOCATION = "C7E5" !CDS_LOCATION = "C7E5" #SEC = "1" !CDS_SEC = "1";
"A":   PN = "1"  !CDS_PN = "1";
"B":   PN = "2"  !CDS_PN = "2";
BODY = "CAP","I53": #LOCATION = "C7E6" !CDS_LOCATION = "C7E6" #SEC = "1" !CDS_SEC = "1";
"A":   PN = "1"  !CDS_PN = "1";
"B":   PN = "2"  !CDS_PN = "2";
BODY = "CAP","I61": #LOCATION = "C1B18" !CDS_LOCATION = "C1B18" #SEC = "1" !CDS_SEC = "1";
"A":   PN = "1"  !CDS_PN = "1";
"B":   PN = "2"  !CDS_PN = "2";
BODY = "CAP_A","I64": #LOCATION = "C1B19" !CDS_LOCATION = "C1B19" #SEC = "1" !CDS_SEC = "1";
"A":   PN = "1"  !CDS_PN = "1";
"B":   PN = "2"  !CDS_PN = "2";
BODY = "CAP_A","I67": #LOCATION = "C9M6" !CDS_LOCATION = "C9M6" #SEC = "1" !CDS_SEC = "1";
"A":   PN = "1"  !CDS_PN = "1";
"B":   PN = "2"  !CDS_PN = "2";
BODY = "SLG55021","I69": #LOCATION = "EU9M1" !CDS_LOCATION = "EU9M1" #SEC = "1" !CDS_SEC = "1";
"D":   PN = "5"  !CDS_PN = "5";
"G":   PN = "7"  !CDS_PN = "7";
"GND":   PN = "4"  !CDS_PN = "4";
"ON":   PN = "2"  !CDS_PN = "2";
"PG":   PN = "8"  !CDS_PN = "8";
"S":   PN = "6"  !CDS_PN = "6";
"SHDN_N":   PN = "3"  !CDS_PN = "3";
"THPAD":   PN = "9"  !CDS_PN = "9";
"VCC":   PN = "1"  !CDS_PN = "1";
BODY = "CAP","I74": #LOCATION = "C9M10" !CDS_LOCATION = "C9M10" #SEC = "1" !CDS_SEC = "1";
"A":   PN = "1"  !CDS_PN = "1";
"B":   PN = "2"  !CDS_PN = "2";
BODY = "CAP_A","I76": #LOCATION = "C9M9" !CDS_LOCATION = "C9M9" #SEC = "1" !CDS_SEC = "1";
"A":   PN = "1"  !CDS_PN = "1";
"B":   PN = "2"  !CDS_PN = "2";
BODY = "RES","I78": #LOCATION = "R8E12" !CDS_LOCATION = "R8E12" #SEC = "1" !CDS_SEC = "1";
"A":   PN = "1"  !CDS_PN = "1";
"B":   PN = "2"  !CDS_PN = "2";
BODY = "RES","I83": #LOCATION = "R8B4" !CDS_LOCATION = "R8B4" #SEC = "1" !CDS_SEC = "1";
"A":   PN = "1"  !CDS_PN = "1";
"B":   PN = "2"  !CDS_PN = "2";
BODY = "MOSFET_N","I85": #LOCATION = "Q8G1" !CDS_LOCATION = "Q8G1" #SEC = "1" !CDS_SEC = "1";
"DRN":   PN = "5"  !CDS_PN = "5";
"GATE":   PN = "4"  !CDS_PN = "4";
"SRC":   PN = "1"  !CDS_PN = "1";
BODY = "MOSFET_N","I86": #LOCATION = "Q1B1" !CDS_LOCATION = "Q1B1" #SEC = "1" !CDS_SEC = "1";
"DRN":   PN = "5"  !CDS_PN = "5";
"GATE":   PN = "4"  !CDS_PN = "4";
"SRC":   PN = "1"  !CDS_PN = "1";
BODY = "MOSFET_N","I87": #LOCATION = "Q8B1" !CDS_LOCATION = "Q8B1" #SEC = "1" !CDS_SEC = "1";
"DRN":   PN = "5"  !CDS_PN = "5";
"GATE":   PN = "4"  !CDS_PN = "4";
"SRC":   PN = "1"  !CDS_PN = "1";
BODY = "MOSFET_N","I88": #LOCATION = "Q7E7" !CDS_LOCATION = "Q7E7" #SEC = "1" !CDS_SEC = "1";
"DRN":   PN = "5"  !CDS_PN = "5";
"GATE":   PN = "4"  !CDS_PN = "4";
"SRC":   PN = "1"  !CDS_PN = "1";
DRAWING = "@baseboard_fab2_lib.baseboard_fab2(sch_1):page199";
BODY = "RES","I2": #LOCATION = "R9P30" !CDS_LOCATION = "R9P30" #SEC = "1" !CDS_SEC = "1";
"A":   PN = "1"  !CDS_PN = "1";
"B":   PN = "2"  !CDS_PN = "2";
BODY = "CAP","I3": #LOCATION = "C1D25" !CDS_LOCATION = "C1D25" #SEC = "1" !CDS_SEC = "1";
"A":   PN = "1"  !CDS_PN = "1";
"B":   PN = "2"  !CDS_PN = "2";
BODY = "CAP_A","I7": #LOCATION = "C1D27" !CDS_LOCATION = "C1D27" #SEC = "1" !CDS_SEC = "1";
"A":   PN = "1"  !CDS_PN = "1";
"B":   PN = "2"  !CDS_PN = "2";
BODY = "RES","I9": #LOCATION = "R1D43" !CDS_LOCATION = "R1D43" #SEC = "1" !CDS_SEC = "1";
"A":   PN = "1"  !CDS_PN = "1";
"B":   PN = "2"  !CDS_PN = "2";
BODY = "ADM1278","I10": #LOCATION = "EU1D2" !CDS_LOCATION = "EU1D2" #SEC = "1" !CDS_SEC = "1";
"ADR1":   PN = "7"  !CDS_PN = "7";
"ADR2":   PN = "8"  !CDS_PN = "8";
"CSOUT":   PN = "19"  !CDS_PN = "19";
"ENABLE":   PN = "12"  !CDS_PN = "12";
"EP":   PN = "33"  !CDS_PN = "33";
"FAULT_N":   PN = "6"  !CDS_PN = "6";
"GATE":   PN = "24"  !CDS_PN = "24";
"GND":   PN = "22"  !CDS_PN = "22";
"GPO1_ALERT1_N_CONV":   PN = "13"  !CDS_PN = "13";
"GPO2_ALERT2_N":   PN = "14"  !CDS_PN = "14";
"HSN":   PN = "27"  !CDS_PN = "27";
"HSP":   PN = "28"  !CDS_PN = "28";
"ISET":   PN = "3"  !CDS_PN = "3";
"ISTART":   PN = "4"  !CDS_PN = "4";
"MCLK":   PN = "10"  !CDS_PN = "10";
"MDAT":   PN = "11"  !CDS_PN = "11";
"MON":   PN = "26"  !CDS_PN = "26";
"MOP":   PN = "29"  !CDS_PN = "29";
"OV":   PN = "32"  !CDS_PN = "32";
"PGND":   PN = "23"  !CDS_PN = "23";
"PSET":   PN = "1"  !CDS_PN = "1";
"PWGIN":   PN = "21"  !CDS_PN = "21";
"PWRGD":   PN = "18"  !CDS_PN = "18";
"RETRY_N":   PN = "17"  !CDS_PN = "17";
"SCL":   PN = "16"  !CDS_PN = "16";
"SDA":   PN = "15"  !CDS_PN = "15";
"SPISS_N":   PN = "9"  !CDS_PN = "9";
"TEMP":   PN = "25"  !CDS_PN = "25";
"TIMER":   PN = "5"  !CDS_PN = "5";
"UV":   PN = "31"  !CDS_PN = "31";
"VCAP":   PN = "2"  !CDS_PN = "2";
"VCC":   PN = "30"  !CDS_PN = "30";
"VOUT":   PN = "20"  !CDS_PN = "20";
BODY = "RES","I12": #LOCATION = "R9P29" !CDS_LOCATION = "R9P29" #SEC = "1" !CDS_SEC = "1";
"A":   PN = "1"  !CDS_PN = "1";
"B":   PN = "2"  !CDS_PN = "2";
BODY = "RES","I13": #LOCATION = "R1D42" !CDS_LOCATION = "R1D42" #SEC = "1" !CDS_SEC = "1";
"A":   PN = "1"  !CDS_PN = "1";
"B":   PN = "2"  !CDS_PN = "2";
BODY = "RES","I15": #LOCATION = "R1D37" !CDS_LOCATION = "R1D37" #SEC = "1" !CDS_SEC = "1";
"A":   PN = "1"  !CDS_PN = "1";
"B":   PN = "2"  !CDS_PN = "2";
BODY = "RES","I16": #LOCATION = "R1D39" !CDS_LOCATION = "R1D39" #SEC = "1" !CDS_SEC = "1";
"A":   PN = "1"  !CDS_PN = "1";
"B":   PN = "2"  !CDS_PN = "2";
BODY = "RES","I17": #LOCATION = "R1D32" !CDS_LOCATION = "R1D32" #SEC = "1" !CDS_SEC = "1";
"A":   PN = "1"  !CDS_PN = "1";
"B":   PN = "2"  !CDS_PN = "2";
BODY = "RES","I19": #LOCATION = "R1D41" !CDS_LOCATION = "R1D41" #SEC = "1" !CDS_SEC = "1";
"A":   PN = "1"  !CDS_PN = "1";
"B":   PN = "2"  !CDS_PN = "2";
BODY = "CAP","I24": #LOCATION = "C9P14" !CDS_LOCATION = "C9P14" #SEC = "1" !CDS_SEC = "1";
"A":   PN = "1"  !CDS_PN = "1";
"B":   PN = "2"  !CDS_PN = "2";
BODY = "RES","I26": #LOCATION = "R1D28" !CDS_LOCATION = "R1D28" #SEC = "1" !CDS_SEC = "1";
"A":   PN = "1"  !CDS_PN = "1";
"B":   PN = "2"  !CDS_PN = "2";
BODY = "RES","I27": #LOCATION = "R1D24" !CDS_LOCATION = "R1D24" #SEC = "1" !CDS_SEC = "1";
"A":   PN = "1"  !CDS_PN = "1";
"B":   PN = "2"  !CDS_PN = "2";
BODY = "RES","I28": #LOCATION = "R1D25" !CDS_LOCATION = "R1D25" #SEC = "1" !CDS_SEC = "1";
"A":   PN = "1"  !CDS_PN = "1";
"B":   PN = "2"  !CDS_PN = "2";
BODY = "RES","I33": #LOCATION = "R9P17" !CDS_LOCATION = "R9P17" #SEC = "1" !CDS_SEC = "1";
"A":   PN = "1"  !CDS_PN = "1";
"B":   PN = "2"  !CDS_PN = "2";
BODY = "RES","I36": #LOCATION = "R9P16" !CDS_LOCATION = "R9P16" #SEC = "1" !CDS_SEC = "1";
"A":   PN = "1"  !CDS_PN = "1";
"B":   PN = "2"  !CDS_PN = "2";
BODY = "RES","I38": #LOCATION = "R1D27" !CDS_LOCATION = "R1D27" #SEC = "1" !CDS_SEC = "1";
"A":   PN = "1"  !CDS_PN = "1";
"B":   PN = "2"  !CDS_PN = "2";
BODY = "RES","I41": #LOCATION = "R9P18" !CDS_LOCATION = "R9P18" #SEC = "1" !CDS_SEC = "1";
"A":   PN = "1"  !CDS_PN = "1";
"B":   PN = "2"  !CDS_PN = "2";
BODY = "RES","I43": #LOCATION = "R1D31" !CDS_LOCATION = "R1D31" #SEC = "1" !CDS_SEC = "1";
"A":   PN = "1"  !CDS_PN = "1";
"B":   PN = "2"  !CDS_PN = "2";
BODY = "CAP_A","I53": #LOCATION = "C1D11" !CDS_LOCATION = "C1D11" #SEC = "1" !CDS_SEC = "1";
"A":   PN = "1"  !CDS_PN = "1";
"B":   PN = "2"  !CDS_PN = "2";
BODY = "RES","I54": #LOCATION = "R9P23" !CDS_LOCATION = "R9P23" #SEC = "1" !CDS_SEC = "1";
"A":   PN = "1"  !CDS_PN = "1";
"B":   PN = "2"  !CDS_PN = "2";
BODY = "RES","I55": #LOCATION = "R9P24" !CDS_LOCATION = "R9P24" #SEC = "1" !CDS_SEC = "1";
"A":   PN = "1"  !CDS_PN = "1";
"B":   PN = "2"  !CDS_PN = "2";
BODY = "NPN","I58": #LOCATION = "Q1D3" !CDS_LOCATION = "Q1D3" #SEC = "1" !CDS_SEC = "1";
"B":   PN = "1"  !CDS_PN = "1";
"C":   PN = "3"  !CDS_PN = "3";
"E":   PN = "2"  !CDS_PN = "2";
BODY = "RES","I65": #LOCATION = "R1D36" !CDS_LOCATION = "R1D36" #SEC = "1" !CDS_SEC = "1";
"A":   PN = "1"  !CDS_PN = "1";
"B":   PN = "2"  !CDS_PN = "2";
BODY = "CAP_A","I67": #LOCATION = "C9P12" !CDS_LOCATION = "C9P12" #SEC = "1" !CDS_SEC = "1";
"A":   PN = "1"  !CDS_PN = "1";
"B":   PN = "2"  !CDS_PN = "2";
BODY = "FET_N_DUAL","I82": #LOCATION = "Q1D1" !CDS_LOCATION = "Q1D1" #SEC = "2" !CDS_SEC = "2";
"DRAIN<0>":   PN = "3"  !CDS_PN = "3";
"GATE<0>":   PN = "5"  !CDS_PN = "5";
"SOURCE<0>":   PN = "4"  !CDS_PN = "4";
BODY = "RES","I84": #LOCATION = "R1D13" !CDS_LOCATION = "R1D13" #SEC = "1" !CDS_SEC = "1";
"A":   PN = "1"  !CDS_PN = "1";
"B":   PN = "2"  !CDS_PN = "2";
BODY = "RES","I85": #LOCATION = "R1D16" !CDS_LOCATION = "R1D16" #SEC = "1" !CDS_SEC = "1";
"A":   PN = "1"  !CDS_PN = "1";
"B":   PN = "2"  !CDS_PN = "2";
BODY = "FET_N_DUAL","I86": #LOCATION = "Q1D1" !CDS_LOCATION = "Q1D1" #SEC = "1" !CDS_SEC = "1";
"DRAIN<0>":   PN = "6"  !CDS_PN = "6";
"GATE<0>":   PN = "2"  !CDS_PN = "2";
"SOURCE<0>":   PN = "1"  !CDS_PN = "1";
BODY = "RES","I92": #LOCATION = "R1D15" !CDS_LOCATION = "R1D15" #SEC = "1" !CDS_SEC = "1";
"A":   PN = "1"  !CDS_PN = "1";
"B":   PN = "2"  !CDS_PN = "2";
BODY = "ZENER","I99": #LOCATION = "VR1D1" !CDS_LOCATION = "VR1D1" #SEC = "1" !CDS_SEC = "1";
"A":   PN = "2"  !CDS_PN = "2";
"C":   PN = "1"  !CDS_PN = "1";
BODY = "RES","I100": #LOCATION = "R1D40" !CDS_LOCATION = "R1D40" #SEC = "1" !CDS_SEC = "1";
"A":   PN = "1"  !CDS_PN = "1";
"B":   PN = "2"  !CDS_PN = "2";
BODY = "RES","I102": #LOCATION = "R1D34" !CDS_LOCATION = "R1D34" #SEC = "1" !CDS_SEC = "1";
"A":   PN = "1"  !CDS_PN = "1";
"B":   PN = "2"  !CDS_PN = "2";
BODY = "CAP_A","I105": #LOCATION = "C9P15" !CDS_LOCATION = "C9P15" #SEC = "1" !CDS_SEC = "1";
"A":   PN = "1"  !CDS_PN = "1";
"B":   PN = "2"  !CDS_PN = "2";
BODY = "CAP_A","I107": #LOCATION = "C1D26" !CDS_LOCATION = "C1D26" #SEC = "1" !CDS_SEC = "1";
"A":   PN = "1"  !CDS_PN = "1";
"B":   PN = "2"  !CDS_PN = "2";
BODY = "RES","I108": #LOCATION = "R1D33" !CDS_LOCATION = "R1D33" #SEC = "1" !CDS_SEC = "1";
"A":   PN = "1"  !CDS_PN = "1";
"B":   PN = "2"  !CDS_PN = "2";
BODY = "RES","I109": #LOCATION = "R1D26" !CDS_LOCATION = "R1D26" #SEC = "1" !CDS_SEC = "1";
"A":   PN = "1"  !CDS_PN = "1";
"B":   PN = "2"  !CDS_PN = "2";
BODY = "RES","I110": #LOCATION = "R1D30" !CDS_LOCATION = "R1D30" #SEC = "1" !CDS_SEC = "1";
"A":   PN = "1"  !CDS_PN = "1";
"B":   PN = "2"  !CDS_PN = "2";
BODY = "CAP","I119": #LOCATION = "C1D19" !CDS_LOCATION = "C1D19" #SEC = "1" !CDS_SEC = "1";
"A":   PN = "1"  !CDS_PN = "1";
"B":   PN = "2"  !CDS_PN = "2";
BODY = "CAP_A","I121": #LOCATION = "C1D21" !CDS_LOCATION = "C1D21" #SEC = "1" !CDS_SEC = "1";
"A":   PN = "1"  !CDS_PN = "1";
"B":   PN = "2"  !CDS_PN = "2";
BODY = "RES","I87": #LOCATION = "R1D18" !CDS_LOCATION = "R1D18" #SEC = "1" !CDS_SEC = "1";
"A":   PN = "1"  !CDS_PN = "1";
"B":   PN = "2"  !CDS_PN = "2";
BODY = "RES","I88": #LOCATION = "R1D11" !CDS_LOCATION = "R1D11" #SEC = "1" !CDS_SEC = "1";
"A":   PN = "1"  !CDS_PN = "1";
"B":   PN = "2"  !CDS_PN = "2";
BODY = "FET_N","I130": #LOCATION = "Q1W5" !CDS_LOCATION = "Q1W5" #SEC = "1" !CDS_SEC = "1";
"DRN":   PN = "3"  !CDS_PN = "3";
"GATE":   PN = "1"  !CDS_PN = "1";
"SRC":   PN = "2"  !CDS_PN = "2";
BODY = "CLX-CONN3A-1-GP","I131": #LOCATION = "J1B4" !CDS_LOCATION = "J1B4" #SEC = "1" !CDS_SEC = "1";
"1":   PN = "1"  !CDS_PN = "1";
"2":   PN = "2"  !CDS_PN = "2";
"3":   PN = "3"  !CDS_PN = "3";
BODY = "CAP","I132": #LOCATION = "C1W16" !CDS_LOCATION = "C1W16" #SEC = "1" !CDS_SEC = "1";
"A":   PN = "1"  !CDS_PN = "1";
"B":   PN = "2"  !CDS_PN = "2";
BODY = "RES","I134": #LOCATION = "R1W20" !CDS_LOCATION = "R1W20" #SEC = "1" !CDS_SEC = "1";
"A":   PN = "1"  !CDS_PN = "1";
"B":   PN = "2"  !CDS_PN = "2";
BODY = "RES","I135": #LOCATION = "R1W21" !CDS_LOCATION = "R1W21" #SEC = "1" !CDS_SEC = "1";
"A":   PN = "1"  !CDS_PN = "1";
"B":   PN = "2"  !CDS_PN = "2";
BODY = "RES","I137": #LOCATION = "R1D29" !CDS_LOCATION = "R1D29" #SEC = "1" !CDS_SEC = "1";
"A":   PN = "1"  !CDS_PN = "1";
"B":   PN = "2"  !CDS_PN = "2";
BODY = "RES","I138": #LOCATION = "R9P28" !CDS_LOCATION = "R9P28" #SEC = "1" !CDS_SEC = "1";
"A":   PN = "1"  !CDS_PN = "1";
"B":   PN = "2"  !CDS_PN = "2";
DRAWING = "@baseboard_fab2_lib.baseboard_fab2(sch_1):page200";
BODY = "CAP_A","I36": #LOCATION = "C9P17" !CDS_LOCATION = "C9P17" #SEC = "1" !CDS_SEC = "1";
"A":   PN = "1"  !CDS_PN = "1";
"B":   PN = "2"  !CDS_PN = "2";
BODY = "CAP_A","I40": #LOCATION = "C9P16" !CDS_LOCATION = "C9P16" &SEC = "1" #&CDS_SEC = "1";
"A":   PN = "1"  !CDS_PN = "1";
"B":   PN = "2"  !CDS_PN = "2";
BODY = "CAP_A","I42": #LOCATION = "C1D22" !CDS_LOCATION = "C1D22" &SEC = "1" #&CDS_SEC = "1";
"A":   PN = "1"  !CDS_PN = "1";
"B":   PN = "2"  !CDS_PN = "2";
BODY = "RES","I43": #LOCATION = "R1D45" !CDS_LOCATION = "R1D45" &SEC = "1" #&CDS_SEC = "1";
"A":   PN = "1"  !CDS_PN = "1";
"B":   PN = "2"  !CDS_PN = "2";
BODY = "RES","I44": #LOCATION = "R1D44" !CDS_LOCATION = "R1D44" &SEC = "1" #&CDS_SEC = "1";
"A":   PN = "1"  !CDS_PN = "1";
"B":   PN = "2"  !CDS_PN = "2";
BODY = "RES","I47": #LOCATION = "R9P27" !CDS_LOCATION = "R9P27" &SEC = "1" #&CDS_SEC = "1";
"A":   PN = "1"  !CDS_PN = "1";
"B":   PN = "2"  !CDS_PN = "2";
BODY = "RES","I48": #LOCATION = "R1D46" !CDS_LOCATION = "R1D46" &SEC = "1" #&CDS_SEC = "1";
"A":   PN = "1"  !CDS_PN = "1";
"B":   PN = "2"  !CDS_PN = "2";
BODY = "RES_PWR","I49": #LOCATION = "R9R1" !CDS_LOCATION = "R9R1" #SEC = "1" !CDS_SEC = "1";
"1":   PN = "1"  !CDS_PN = "1";
"2":   PN = "2"  !CDS_PN = "2";
"3":   PN = "3"  !CDS_PN = "3";
"4":   PN = "4"  !CDS_PN = "4";
"5":   PN = "5"  !CDS_PN = "5";
"6":   PN = "6"  !CDS_PN = "6";
BODY = "RES_PWR","I50": #LOCATION = "R1D49" !CDS_LOCATION = "R1D49" #SEC = "1" !CDS_SEC = "1";
"1":   PN = "1"  !CDS_PN = "1";
"2":   PN = "2"  !CDS_PN = "2";
"3":   PN = "3"  !CDS_PN = "3";
"4":   PN = "4"  !CDS_PN = "4";
"5":   PN = "5"  !CDS_PN = "5";
"6":   PN = "6"  !CDS_PN = "6";
BODY = "RES","I51": #LOCATION = "R9P26" !CDS_LOCATION = "R9P26" &SEC = "1" #&CDS_SEC = "1";
"A":   PN = "1"  !CDS_PN = "1";
"B":   PN = "2"  !CDS_PN = "2";
BODY = "RES","I52": #LOCATION = "R1D47" !CDS_LOCATION = "R1D47" &SEC = "1" #&CDS_SEC = "1";
"A":   PN = "1"  !CDS_PN = "1";
"B":   PN = "2"  !CDS_PN = "2";
BODY = "MOSFETN_1D3S","I54": #LOCATION = "EU1E3" !CDS_LOCATION = "EU1E3" #SEC = "1" !CDS_SEC = "1";
"D":   PN = "5"  !CDS_PN = "5";
"G":   PN = "4"  !CDS_PN = "4";
"S1":   PN = "1"  !CDS_PN = "1";
"S2":   PN = "2"  !CDS_PN = "2";
"S3":   PN = "3"  !CDS_PN = "3";
BODY = "RES","I56": #LOCATION = "R1E1" !CDS_LOCATION = "R1E1" #SEC = "1" !CDS_SEC = "1";
"A":   PN = "1"  !CDS_PN = "1";
"B":   PN = "2"  !CDS_PN = "2";
BODY = "MOSFETN_1D3S","I57": #LOCATION = "EU9R1" !CDS_LOCATION = "EU9R1" #SEC = "1" !CDS_SEC = "1";
"D":   PN = "5"  !CDS_PN = "5";
"G":   PN = "4"  !CDS_PN = "4";
"S1":   PN = "1"  !CDS_PN = "1";
"S2":   PN = "2"  !CDS_PN = "2";
"S3":   PN = "3"  !CDS_PN = "3";
BODY = "RES","I58": #LOCATION = "R9R4" !CDS_LOCATION = "R9R4" &SEC = "1" #&CDS_SEC = "1";
"A":   PN = "1"  !CDS_PN = "1";
"B":   PN = "2"  !CDS_PN = "2";
BODY = "MOSFETN_1D3S","I59": #LOCATION = "EU1E1" !CDS_LOCATION = "EU1E1" #SEC = "1" !CDS_SEC = "1";
"D":   PN = "5"  !CDS_PN = "5";
"G":   PN = "4"  !CDS_PN = "4";
"S1":   PN = "1"  !CDS_PN = "1";
"S2":   PN = "2"  !CDS_PN = "2";
"S3":   PN = "3"  !CDS_PN = "3";
BODY = "RES","I60": #LOCATION = "R1D48" !CDS_LOCATION = "R1D48" #SEC = "1" !CDS_SEC = "1";
"A":   PN = "1"  !CDS_PN = "1";
"B":   PN = "2"  !CDS_PN = "2";
BODY = "RES","I70": #LOCATION = "R9P19" !CDS_LOCATION = "R9P19" #SEC = "1" !CDS_SEC = "1";
"A":   PN = "1"  !CDS_PN = "1";
"B":   PN = "2"  !CDS_PN = "2";
BODY = "RES","I71": #LOCATION = "R9P21" !CDS_LOCATION = "R9P21" #SEC = "1" !CDS_SEC = "1";
"A":   PN = "1"  !CDS_PN = "1";
"B":   PN = "2"  !CDS_PN = "2";
BODY = "RES","I86": #LOCATION = "R9P20" !CDS_LOCATION = "R9P20" #SEC = "1" !CDS_SEC = "1";
"A":   PN = "1"  !CDS_PN = "1";
"B":   PN = "2"  !CDS_PN = "2";
BODY = "TTL1G126_A","I103": #LOCATION = "U1D1" !CDS_LOCATION = "U1D1" #SEC = "1" !CDS_SEC = "1";
"A":   PN = "2"  !CDS_PN = "2";
"OE":   PN = "1"  !CDS_PN = "1";
"Y":   PN = "4"  !CDS_PN = "4";
BODY = "RES","I108": #LOCATION = "R9P11" !CDS_LOCATION = "R9P11" #SEC = "1" !CDS_SEC = "1";
"A":   PN = "1"  !CDS_PN = "1";
"B":   PN = "2"  !CDS_PN = "2";
BODY = "RES","I149": #LOCATION = "R9P6" !CDS_LOCATION = "R9P6" #SEC = "1" !CDS_SEC = "1";
"A":   PN = "1"  !CDS_PN = "1";
"B":   PN = "2"  !CDS_PN = "2";
BODY = "RES","I154": #LOCATION = "R1D51" !CDS_LOCATION = "R1D51" #SEC = "1" !CDS_SEC = "1";
"A":   PN = "1"  !CDS_PN = "1";
"B":   PN = "2"  !CDS_PN = "2";
BODY = "CAP","I155": #LOCATION = "C1E2" !CDS_LOCATION = "C1E2" #SEC = "1" !CDS_SEC = "1";
"A":   PN = "1"  !CDS_PN = "1";
"B":   PN = "2"  !CDS_PN = "2";
BODY = "RES","I158": #LOCATION = "R1D22" !CDS_LOCATION = "R1D22" #SEC = "1" !CDS_SEC = "1";
"A":   PN = "1"  !CDS_PN = "1";
"B":   PN = "2"  !CDS_PN = "2";
BODY = "TPS3700","I163": #LOCATION = "U9P1" !CDS_LOCATION = "U9P1" #SEC = "1" !CDS_SEC = "1";
"GND":   PN = "5"  !CDS_PN = "5";
"INAP":   PN = "4"  !CDS_PN = "4";
"INBN":   PN = "3"  !CDS_PN = "3";
"OUTA":   PN = "6"  !CDS_PN = "6";
"OUTB":   PN = "1"  !CDS_PN = "1";
"VDD":   PN = "2"  !CDS_PN = "2";
BODY = "TPS3700","I170": #LOCATION = "U1D2" !CDS_LOCATION = "U1D2" #SEC = "1" !CDS_SEC = "1";
"GND":   PN = "5"  !CDS_PN = "5";
"INAP":   PN = "4"  !CDS_PN = "4";
"INBN":   PN = "3"  !CDS_PN = "3";
"OUTA":   PN = "6"  !CDS_PN = "6";
"OUTB":   PN = "1"  !CDS_PN = "1";
"VDD":   PN = "2"  !CDS_PN = "2";
BODY = "RES","I174": #LOCATION = "R1D12" !CDS_LOCATION = "R1D12" #SEC = "1" !CDS_SEC = "1";
"A":   PN = "1"  !CDS_PN = "1";
"B":   PN = "2"  !CDS_PN = "2";
BODY = "RES","I175": #LOCATION = "R1D19" !CDS_LOCATION = "R1D19" #SEC = "1" !CDS_SEC = "1";
"A":   PN = "1"  !CDS_PN = "1";
"B":   PN = "2"  !CDS_PN = "2";
BODY = "CAP_A","I185": #LOCATION = "C9P6" !CDS_LOCATION = "C9P6" #SEC = "1" !CDS_SEC = "1";
"A":   PN = "1"  !CDS_PN = "1";
"B":   PN = "2"  !CDS_PN = "2";
BODY = "CAP_A","I187": #LOCATION = "C1D9" !CDS_LOCATION = "C1D9" #SEC = "1" !CDS_SEC = "1";
"A":   PN = "1"  !CDS_PN = "1";
"B":   PN = "2"  !CDS_PN = "2";
BODY = "RES","I191": #LOCATION = "R1D23" !CDS_LOCATION = "R1D23" #SEC = "1" !CDS_SEC = "1";
"A":   PN = "1"  !CDS_PN = "1";
"B":   PN = "2"  !CDS_PN = "2";
BODY = "RES","I192": #LOCATION = "R9P10" !CDS_LOCATION = "R9P10" #SEC = "1" !CDS_SEC = "1";
"A":   PN = "1"  !CDS_PN = "1";
"B":   PN = "2"  !CDS_PN = "2";
BODY = "FET_N_DUAL","I196": #LOCATION = "Q9P1" !CDS_LOCATION = "Q9P1" #SEC = "1" !CDS_SEC = "1";
"DRAIN<0>":   PN = "6"  !CDS_PN = "6";
"GATE<0>":   PN = "2"  !CDS_PN = "2";
"SOURCE<0>":   PN = "1"  !CDS_PN = "1";
BODY = "FET_N_DUAL","I199": #LOCATION = "Q9P1" !CDS_LOCATION = "Q9P1" #SEC = "2" !CDS_SEC = "2";
"DRAIN<0>":   PN = "3"  !CDS_PN = "3";
"GATE<0>":   PN = "5"  !CDS_PN = "5";
"SOURCE<0>":   PN = "4"  !CDS_PN = "4";
BODY = "TPS3700","I200": #LOCATION = "U9P2" !CDS_LOCATION = "U9P2" &SEC = "1" #&CDS_SEC = "1";
"GND":   PN = "5"  !CDS_PN = "5";
"INAP":   PN = "4"  !CDS_PN = "4";
"INBN":   PN = "3"  !CDS_PN = "3";
"OUTA":   PN = "6"  !CDS_PN = "6";
"OUTB":   PN = "1"  !CDS_PN = "1";
"VDD":   PN = "2"  !CDS_PN = "2";
BODY = "CAP_A","I201": #LOCATION = "C9P11" !CDS_LOCATION = "C9P11" #SEC = "1" !CDS_SEC = "1";
"A":   PN = "1"  !CDS_PN = "1";
"B":   PN = "2"  !CDS_PN = "2";
BODY = "FET_N","I203": #LOCATION = "Q1D2" !CDS_LOCATION = "Q1D2" #SEC = "1" !CDS_SEC = "1";
"DRN":   PN = "3"  !CDS_PN = "3";
"GATE":   PN = "1"  !CDS_PN = "1";
"SRC":   PN = "2"  !CDS_PN = "2";
BODY = "RES","I204": #LOCATION = "R1D21" !CDS_LOCATION = "R1D21" #SEC = "1" !CDS_SEC = "1";
"A":   PN = "1"  !CDS_PN = "1";
"B":   PN = "2"  !CDS_PN = "2";
BODY = "RES","I210": #LOCATION = "R9P4" !CDS_LOCATION = "R9P4" #SEC = "1" !CDS_SEC = "1";
"A":   PN = "1"  !CDS_PN = "1";
"B":   PN = "2"  !CDS_PN = "2";
BODY = "DIODE","I213": #LOCATION = "CR9P2" !CDS_LOCATION = "CR9P2" #SEC = "1" !CDS_SEC = "1";
"A":   PN = "2"  !CDS_PN = "2";
"C":   PN = "1"  !CDS_PN = "1";
BODY = "DIODE","I214": #LOCATION = "CR9P1" !CDS_LOCATION = "CR9P1" #SEC = "1" !CDS_SEC = "1";
"A":   PN = "2"  !CDS_PN = "2";
"C":   PN = "1"  !CDS_PN = "1";
BODY = "RES","I215": #LOCATION = "R9P5" !CDS_LOCATION = "R9P5" #SEC = "1" !CDS_SEC = "1";
"A":   PN = "1"  !CDS_PN = "1";
"B":   PN = "2"  !CDS_PN = "2";
BODY = "RES","I218": #LOCATION = "R9P12" !CDS_LOCATION = "R9P12" #SEC = "1" !CDS_SEC = "1";
"A":   PN = "1"  !CDS_PN = "1";
"B":   PN = "2"  !CDS_PN = "2";
BODY = "DIODE","I220": #LOCATION = "CR1F5" !CDS_LOCATION = "CR1F5" #SEC = "1" !CDS_SEC = "1";
"A":   PN = "2"  !CDS_PN = "2";
"C":   PN = "1"  !CDS_PN = "1";
BODY = "RES","I222": #LOCATION = "R9P33" !CDS_LOCATION = "R9P33" &SEC = "1" #&CDS_SEC = "1";
"A":   PN = "1"  !CDS_PN = "1";
"B":   PN = "2"  !CDS_PN = "2";
BODY = "FET_N","I225": #LOCATION = "Q6W1" !CDS_LOCATION = "Q6W1" &SEC = "1" #&CDS_SEC = "1";
"DRN":   PN = "3"  !CDS_PN = "3";
"GATE":   PN = "1"  !CDS_PN = "1";
"SRC":   PN = "2"  !CDS_PN = "2";
BODY = "SC22P50V2JN-4GP","I235": #LOCATION = "C9W1" !CDS_LOCATION = "C9W1" #SEC = "1" !CDS_SEC = "1";
"1":   PN = "1"  !CDS_PN = "1";
"2":   PN = "2"  !CDS_PN = "2";
BODY = "SC22P50V2JN-4GP","I236": #LOCATION = "C9W2" !CDS_LOCATION = "C9W2" #SEC = "1" !CDS_SEC = "1";
"1":   PN = "1"  !CDS_PN = "1";
"2":   PN = "2"  !CDS_PN = "2";
BODY = "RES","I243": #LOCATION = "R9P15" !CDS_LOCATION = "R9P15" #SEC = "1" !CDS_SEC = "1";
"A":   PN = "1"  !CDS_PN = "1";
"B":   PN = "2"  !CDS_PN = "2";
BODY = "RES","I244": #LOCATION = "R1D10" !CDS_LOCATION = "R1D10" #SEC = "1" !CDS_SEC = "1";
"A":   PN = "1"  !CDS_PN = "1";
"B":   PN = "2"  !CDS_PN = "2";
BODY = "RES","I246": #LOCATION = "R1D14" !CDS_LOCATION = "R1D14" #SEC = "1" !CDS_SEC = "1";
"A":   PN = "1"  !CDS_PN = "1";
"B":   PN = "2"  !CDS_PN = "2";
BODY = "270KR2F-GP","I249": #LOCATION = "R9P13" !CDS_LOCATION = "R9P13" #SEC = "1" !CDS_SEC = "1";
"1":   PN = "1"  !CDS_PN = "1";
"2":   PN = "2"  !CDS_PN = "2";
BODY = "232KR2F-2-GP","I250": #LOCATION = "R6W3" !CDS_LOCATION = "R6W3" #SEC = "1" !CDS_SEC = "1";
"1":   PN = "1"  !CDS_PN = "1";
"2":   PN = "2"  !CDS_PN = "2";
BODY = "RES","I251": #LOCATION = "R9P9" !CDS_LOCATION = "R9P9" #SEC = "1" !CDS_SEC = "1";
"A":   PN = "1"  !CDS_PN = "1";
"B":   PN = "2"  !CDS_PN = "2";
BODY = "RES","I252": #LOCATION = "R9P7" !CDS_LOCATION = "R9P7" #SEC = "1" !CDS_SEC = "1";
"A":   PN = "1"  !CDS_PN = "1";
"B":   PN = "2"  !CDS_PN = "2";
BODY = "RES","I253": #LOCATION = "R1D20" !CDS_LOCATION = "R1D20" #SEC = "1" !CDS_SEC = "1";
"A":   PN = "1"  !CDS_PN = "1";
"B":   PN = "2"  !CDS_PN = "2";
DRAWING = "@baseboard_fab2_lib.baseboard_fab2(sch_1):page201";
BODY = "RES","I22": #LOCATION = "R4D31" !CDS_LOCATION = "R4D31" #SEC = "1" !CDS_SEC = "1";
"A":   PN = "1"  !CDS_PN = "1";
"B":   PN = "2"  !CDS_PN = "2";
BODY = "RES","I25": #LOCATION = "R4D58" !CDS_LOCATION = "R4D58" #SEC = "1" !CDS_SEC = "1";
"A":   PN = "1"  !CDS_PN = "1";
"B":   PN = "2"  !CDS_PN = "2";
BODY = "RES","I26": #LOCATION = "R4D67" !CDS_LOCATION = "R4D67" #SEC = "1" !CDS_SEC = "1";
"A":   PN = "1"  !CDS_PN = "1";
"B":   PN = "2"  !CDS_PN = "2";
BODY = "RES","I27": #LOCATION = "R4E5" !CDS_LOCATION = "R4E5" #SEC = "1" !CDS_SEC = "1";
"A":   PN = "1"  !CDS_PN = "1";
"B":   PN = "2"  !CDS_PN = "2";
BODY = "CAP_A","I30": #LOCATION = "C4D25" !CDS_LOCATION = "C4D25" #SEC = "1" !CDS_SEC = "1";
"A":   PN = "1"  !CDS_PN = "1";
"B":   PN = "2"  !CDS_PN = "2";
BODY = "CAP_A","I32": #LOCATION = "C4D26" !CDS_LOCATION = "C4D26" #SEC = "1" !CDS_SEC = "1";
"A":   PN = "1"  !CDS_PN = "1";
"B":   PN = "2"  !CDS_PN = "2";
BODY = "CAP_A","I37": #LOCATION = "C4D15" !CDS_LOCATION = "C4D15" #SEC = "1" !CDS_SEC = "1";
"A":   PN = "1"  !CDS_PN = "1";
"B":   PN = "2"  !CDS_PN = "2";
BODY = "CAP_A","I39": #LOCATION = "C4D19" !CDS_LOCATION = "C4D19" #SEC = "1" !CDS_SEC = "1";
"A":   PN = "1"  !CDS_PN = "1";
"B":   PN = "2"  !CDS_PN = "2";
BODY = "RES","I40": #LOCATION = "R4D26" !CDS_LOCATION = "R4D26" #SEC = "1" !CDS_SEC = "1";
"A":   PN = "1"  !CDS_PN = "1";
"B":   PN = "2"  !CDS_PN = "2";
BODY = "RES","I54": #LOCATION = "R4D27" !CDS_LOCATION = "R4D27" #SEC = "1" !CDS_SEC = "1";
"A":   PN = "1"  !CDS_PN = "1";
"B":   PN = "2"  !CDS_PN = "2";
BODY = "RES","I55": #LOCATION = "R4D32" !CDS_LOCATION = "R4D32" #SEC = "1" !CDS_SEC = "1";
"A":   PN = "1"  !CDS_PN = "1";
"B":   PN = "2"  !CDS_PN = "2";
BODY = "RES","I56": #LOCATION = "R4E6" !CDS_LOCATION = "R4E6" #SEC = "1" !CDS_SEC = "1";
"A":   PN = "1"  !CDS_PN = "1";
"B":   PN = "2"  !CDS_PN = "2";
BODY = "CAP","I64": #LOCATION = "C4D29" !CDS_LOCATION = "C4D29" #SEC = "1" !CDS_SEC = "1";
"A":   PN = "1"  !CDS_PN = "1";
"B":   PN = "2"  !CDS_PN = "2";
BODY = "CAP","I66": #LOCATION = "C4D17" !CDS_LOCATION = "C4D17" #SEC = "1" !CDS_SEC = "1";
"A":   PN = "1"  !CDS_PN = "1";
"B":   PN = "2"  !CDS_PN = "2";
BODY = "CAP","I68": #LOCATION = "C4D18" !CDS_LOCATION = "C4D18" #SEC = "1" !CDS_SEC = "1";
"A":   PN = "1"  !CDS_PN = "1";
"B":   PN = "2"  !CDS_PN = "2";
BODY = "CAP","I70": #LOCATION = "C4D45" !CDS_LOCATION = "C4D45" #SEC = "1" !CDS_SEC = "1";
"A":   PN = "1"  !CDS_PN = "1";
"B":   PN = "2"  !CDS_PN = "2";
BODY = "RES","I98": #LOCATION = "R4D66" !CDS_LOCATION = "R4D66" #SEC = "1" !CDS_SEC = "1";
"A":   PN = "1"  !CDS_PN = "1";
"B":   PN = "2"  !CDS_PN = "2";
BODY = "RES","I102": #LOCATION = "R6P32" !CDS_LOCATION = "R6P32" #SEC = "1" !CDS_SEC = "1";
"A":   PN = "1"  !CDS_PN = "1";
"B":   PN = "2"  !CDS_PN = "2";
BODY = "RES","I103": #LOCATION = "R6P37" !CDS_LOCATION = "R6P37" #SEC = "1" !CDS_SEC = "1";
"A":   PN = "1"  !CDS_PN = "1";
"B":   PN = "2"  !CDS_PN = "2";
BODY = "RES","I109": #LOCATION = "R4E8" !CDS_LOCATION = "R4E8" #SEC = "1" !CDS_SEC = "1";
"A":   PN = "1"  !CDS_PN = "1";
"B":   PN = "2"  !CDS_PN = "2";
BODY = "RES","I110": #LOCATION = "R4D39" !CDS_LOCATION = "R4D39" #SEC = "1" !CDS_SEC = "1";
"A":   PN = "1"  !CDS_PN = "1";
"B":   PN = "2"  !CDS_PN = "2";
BODY = "RES","I111": #LOCATION = "R4E3" !CDS_LOCATION = "R4E3" #SEC = "1" !CDS_SEC = "1";
"A":   PN = "1"  !CDS_PN = "1";
"B":   PN = "2"  !CDS_PN = "2";
BODY = "RES","I116": #LOCATION = "R4E20" !CDS_LOCATION = "R4E20" #SEC = "1" !CDS_SEC = "1";
"A":   PN = "1"  !CDS_PN = "1";
"B":   PN = "2"  !CDS_PN = "2";
BODY = "RES","I120": #LOCATION = "R6P27" !CDS_LOCATION = "R6P27" #SEC = "1" !CDS_SEC = "1";
"A":   PN = "1"  !CDS_PN = "1";
"B":   PN = "2"  !CDS_PN = "2";
BODY = "RES","I121": #LOCATION = "R6P28" !CDS_LOCATION = "R6P28" #SEC = "1" !CDS_SEC = "1";
"A":   PN = "1"  !CDS_PN = "1";
"B":   PN = "2"  !CDS_PN = "2";
BODY = "RES","I124": #LOCATION = "R4D63" !CDS_LOCATION = "R4D63" #SEC = "1" !CDS_SEC = "1";
"A":   PN = "1"  !CDS_PN = "1";
"B":   PN = "2"  !CDS_PN = "2";
BODY = "CAP","I125": #LOCATION = "C4D42" !CDS_LOCATION = "C4D42" #SEC = "1" !CDS_SEC = "1";
"A":   PN = "1"  !CDS_PN = "1";
"B":   PN = "2"  !CDS_PN = "2";
BODY = "RES","I127": #LOCATION = "R4D65" !CDS_LOCATION = "R4D65" #SEC = "1" !CDS_SEC = "1";
"A":   PN = "1"  !CDS_PN = "1";
"B":   PN = "2"  !CDS_PN = "2";
BODY = "RES","I128": #LOCATION = "R6P45" !CDS_LOCATION = "R6P45" #SEC = "1" !CDS_SEC = "1";
"A":   PN = "1"  !CDS_PN = "1";
"B":   PN = "2"  !CDS_PN = "2";
BODY = "RES","I131": #LOCATION = "R6P18" !CDS_LOCATION = "R6P18" #SEC = "1" !CDS_SEC = "1";
"A":   PN = "1"  !CDS_PN = "1";
"B":   PN = "2"  !CDS_PN = "2";
BODY = "RES","I132": #LOCATION = "R6P16" !CDS_LOCATION = "R6P16" #SEC = "1" !CDS_SEC = "1";
"A":   PN = "1"  !CDS_PN = "1";
"B":   PN = "2"  !CDS_PN = "2";
BODY = "PXE1610B","I155": #LOCATION = "EU4D4" !CDS_LOCATION = "EU4D4" &SEC = "1" #&CDS_SEC = "1";
"AIREF1":   PN = "23"  !CDS_PN = "23";
"AIREF2":   PN = "25"  !CDS_PN = "25";
"AIREF3":   PN = "27"  !CDS_PN = "27";
"AIREF4":   PN = "29"  !CDS_PN = "29";
"AIREF5":   PN = "31"  !CDS_PN = "31";
"AIREF6":   PN = "33"  !CDS_PN = "33";
"AISEN1":   PN = "24"  !CDS_PN = "24";
"AISEN2":   PN = "26"  !CDS_PN = "26";
"AISEN3":   PN = "28"  !CDS_PN = "28";
"AISEN4":   PN = "30"  !CDS_PN = "30";
"AISEN5":   PN = "32"  !CDS_PN = "32";
"AISEN6":   PN = "34"  !CDS_PN = "34";
"APWM1":   PN = "7"  !CDS_PN = "7";
"APWM2":   PN = "6"  !CDS_PN = "6";
"APWM3":   PN = "5"  !CDS_PN = "5";
"APWM4":   PN = "4"  !CDS_PN = "4";
"APWM5":   PN = "3"  !CDS_PN = "3";
"APWM6":   PN = "2"  !CDS_PN = "2";
"ATSEN":   PN = "43"  !CDS_PN = "43";
"AVREF":   PN = "22"  !CDS_PN = "22";
"AVREN":   PN = "12"  !CDS_PN = "12";
"AVRRDY":   PN = "11"  !CDS_PN = "11";
"AVSEN":   PN = "21"  !CDS_PN = "21";
"BIREF1":   PN = "37"  !CDS_PN = "37";
"BISEN1":   PN = "38"  !CDS_PN = "38";
"BPWM1":   PN = "1"  !CDS_PN = "1";
"BTSEN":   PN = "42"  !CDS_PN = "42";
"BVREF":   PN = "36"  !CDS_PN = "36";
"BVSEN":   PN = "35"  !CDS_PN = "35";
"IINSEN":   PN = "46"  !CDS_PN = "46";
"MP0":   PN = "15"  !CDS_PN = "15";
"MP1":   PN = "16"  !CDS_PN = "16";
"MP2":   PN = "20"  !CDS_PN = "20";
"MP3":   PN = "39"  !CDS_PN = "39";
"MP4":   PN = "40"  !CDS_PN = "40";
"PINALRT_N":   PN = "14"  !CDS_PN = "14";
"RESET_N":   PN = "10"  !CDS_PN = "10";
"SCL":   PN = "9"  !CDS_PN = "9";
"SDA":   PN = "8"  !CDS_PN = "8";
"THPAD":   PN = "49"  !CDS_PN = "49";
"VALRT_N":   PN = "19"  !CDS_PN = "19";
"VCLK":   PN = "17"  !CDS_PN = "17";
"VD12":   PN = "48"  !CDS_PN = "48";
"VDD":   PN = "47"  !CDS_PN = "47";
"VDIO":   PN = "18"  !CDS_PN = "18";
"VINSEN":   PN = "45"  !CDS_PN = "45";
"VRHOT_N":   PN = "13"  !CDS_PN = "13";
"XADDR1":   PN = "44"  !CDS_PN = "44";
"XADDR2":   PN = "41"  !CDS_PN = "41";
BODY = "SC22P50V2JN-4GP","I168": #LOCATION = "CF1" !CDS_LOCATION = "CF1" &SEC = "1" #&CDS_SEC = "1";
"1":   PN = "1"  !CDS_PN = "1";
"2":   PN = "2"  !CDS_PN = "2";
BODY = "SC22P50V2JN-4GP","I169": #LOCATION = "CF2" !CDS_LOCATION = "CF2" &SEC = "1" #&CDS_SEC = "1";
"1":   PN = "1"  !CDS_PN = "1";
"2":   PN = "2"  !CDS_PN = "2";
BODY = "SC22P50V2JN-4GP","I170": #LOCATION = "CF3" !CDS_LOCATION = "CF3" &SEC = "1" #&CDS_SEC = "1";
"1":   PN = "1"  !CDS_PN = "1";
"2":   PN = "2"  !CDS_PN = "2";
BODY = "SC22P50V2JN-4GP","I171": #LOCATION = "CF4" !CDS_LOCATION = "CF4" &SEC = "1" #&CDS_SEC = "1";
"1":   PN = "1"  !CDS_PN = "1";
"2":   PN = "2"  !CDS_PN = "2";
BODY = "SC22P50V2JN-4GP","I172": #LOCATION = "CF5" !CDS_LOCATION = "CF5" &SEC = "1" #&CDS_SEC = "1";
"1":   PN = "1"  !CDS_PN = "1";
"2":   PN = "2"  !CDS_PN = "2";
BODY = "SC22P50V2JN-4GP","I173": #LOCATION = "CF6" !CDS_LOCATION = "CF6" &SEC = "1" #&CDS_SEC = "1";
"1":   PN = "1"  !CDS_PN = "1";
"2":   PN = "2"  !CDS_PN = "2";
BODY = "RES","I180": #LOCATION = "RF6" !CDS_LOCATION = "RF6" #SEC = "1" !CDS_SEC = "1";
"A":   PN = "1"  !CDS_PN = "1";
"B":   PN = "2"  !CDS_PN = "2";
BODY = "RES","I182": #LOCATION = "RF1" !CDS_LOCATION = "RF1" #SEC = "1" !CDS_SEC = "1";
"A":   PN = "1"  !CDS_PN = "1";
"B":   PN = "2"  !CDS_PN = "2";
BODY = "RES","I183": #LOCATION = "RF2" !CDS_LOCATION = "RF2" #SEC = "1" !CDS_SEC = "1";
"A":   PN = "1"  !CDS_PN = "1";
"B":   PN = "2"  !CDS_PN = "2";
BODY = "RES","I184": #LOCATION = "RF3" !CDS_LOCATION = "RF3" #SEC = "1" !CDS_SEC = "1";
"A":   PN = "1"  !CDS_PN = "1";
"B":   PN = "2"  !CDS_PN = "2";
BODY = "RES","I185": #LOCATION = "RF4" !CDS_LOCATION = "RF4" #SEC = "1" !CDS_SEC = "1";
"A":   PN = "1"  !CDS_PN = "1";
"B":   PN = "2"  !CDS_PN = "2";
BODY = "RES","I186": #LOCATION = "RF5" !CDS_LOCATION = "RF5" #SEC = "1" !CDS_SEC = "1";
"A":   PN = "1"  !CDS_PN = "1";
"B":   PN = "2"  !CDS_PN = "2";
BODY = "RES","I187": #LOCATION = "R4E4" !CDS_LOCATION = "R4E4" #SEC = "1" !CDS_SEC = "1";
"A":   PN = "1"  !CDS_PN = "1";
"B":   PN = "2"  !CDS_PN = "2";
BODY = "RES","I189": #LOCATION = "R4E9" !CDS_LOCATION = "R4E9" #SEC = "1" !CDS_SEC = "1";
"A":   PN = "1"  !CDS_PN = "1";
"B":   PN = "2"  !CDS_PN = "2";
BODY = "RES","I190": #LOCATION = "R4E10" !CDS_LOCATION = "R4E10" #SEC = "1" !CDS_SEC = "1";
"A":   PN = "1"  !CDS_PN = "1";
"B":   PN = "2"  !CDS_PN = "2";
BODY = "PIN-CON3-27-GP","I191": #LOCATION = "J8D4" !CDS_LOCATION = "J8D4" #SEC = "1" !CDS_SEC = "1";
"1":   PN = "1"  !CDS_PN = "1";
"2":   PN = "2"  !CDS_PN = "2";
"3":   PN = "3"  !CDS_PN = "3";
BODY = "CAP_A","I192": #LOCATION = "C4D20" !CDS_LOCATION = "C4D20" #SEC = "1" !CDS_SEC = "1";
"A":   PN = "1"  !CDS_PN = "1";
"B":   PN = "2"  !CDS_PN = "2";
DRAWING = "@baseboard_fab2_lib.baseboard_fab2(sch_1):page202";
BODY = "CAP_A","I9": #LOCATION = "C6R7" !CDS_LOCATION = "C6R7" #SEC = "1" !CDS_SEC = "1";
"A":   PN = "1"  !CDS_PN = "1";
"B":   PN = "2"  !CDS_PN = "2";
BODY = "CAP","I18": #LOCATION = "C4E5" !CDS_LOCATION = "C4E5" #SEC = "1" !CDS_SEC = "1";
"A":   PN = "1"  !CDS_PN = "1";
"B":   PN = "2"  !CDS_PN = "2";
BODY = "CAP","I22": #LOCATION = "C4E17" !CDS_LOCATION = "C4E17" #SEC = "1" !CDS_SEC = "1";
"A":   PN = "1"  !CDS_PN = "1";
"B":   PN = "2"  !CDS_PN = "2";
BODY = "CAP","I24": #LOCATION = "C4E27" !CDS_LOCATION = "C4E27" #SEC = "1" !CDS_SEC = "1";
"A":   PN = "1"  !CDS_PN = "1";
"B":   PN = "2"  !CDS_PN = "2";
BODY = "CAP_A","I27": #LOCATION = "C4E11" !CDS_LOCATION = "C4E11" #SEC = "1" !CDS_SEC = "1";
"A":   PN = "1"  !CDS_PN = "1";
"B":   PN = "2"  !CDS_PN = "2";
BODY = "CAP","I32": #LOCATION = "C4D50" !CDS_LOCATION = "C4D50" #SEC = "1" !CDS_SEC = "1";
"A":   PN = "1"  !CDS_PN = "1";
"B":   PN = "2"  !CDS_PN = "2";
BODY = "CAP","I34": #LOCATION = "C4E10" !CDS_LOCATION = "C4E10" #SEC = "1" !CDS_SEC = "1";
"A":   PN = "1"  !CDS_PN = "1";
"B":   PN = "2"  !CDS_PN = "2";
BODY = "CAP_A","I35": #LOCATION = "C4E20" !CDS_LOCATION = "C4E20" #SEC = "1" !CDS_SEC = "1";
"A":   PN = "1"  !CDS_PN = "1";
"B":   PN = "2"  !CDS_PN = "2";
BODY = "CAP","I36": #LOCATION = "C4E19" !CDS_LOCATION = "C4E19" #SEC = "1" !CDS_SEC = "1";
"A":   PN = "1"  !CDS_PN = "1";
"B":   PN = "2"  !CDS_PN = "2";
BODY = "CAP","I37": #LOCATION = "C6R11" !CDS_LOCATION = "C6R11" #SEC = "1" !CDS_SEC = "1";
"A":   PN = "1"  !CDS_PN = "1";
"B":   PN = "2"  !CDS_PN = "2";
BODY = "CAP","I38": #LOCATION = "C6P13" !CDS_LOCATION = "C6P13" #SEC = "1" !CDS_SEC = "1";
"A":   PN = "1"  !CDS_PN = "1";
"B":   PN = "2"  !CDS_PN = "2";
BODY = "CAP","I42": #LOCATION = "C6R13" !CDS_LOCATION = "C6R13" #SEC = "1" !CDS_SEC = "1";
"A":   PN = "1"  !CDS_PN = "1";
"B":   PN = "2"  !CDS_PN = "2";
BODY = "CAP","I45": #LOCATION = "C4E26" !CDS_LOCATION = "C4E26" #SEC = "1" !CDS_SEC = "1";
"A":   PN = "1"  !CDS_PN = "1";
"B":   PN = "2"  !CDS_PN = "2";
BODY = "CAP_A","I46": #LOCATION = "C4D49" !CDS_LOCATION = "C4D49" #SEC = "1" !CDS_SEC = "1";
"A":   PN = "1"  !CDS_PN = "1";
"B":   PN = "2"  !CDS_PN = "2";
BODY = "CAP","I47": #LOCATION = "C4D48" !CDS_LOCATION = "C4D48" #SEC = "1" !CDS_SEC = "1";
"A":   PN = "1"  !CDS_PN = "1";
"B":   PN = "2"  !CDS_PN = "2";
BODY = "CAP","I48": #LOCATION = "C6R4" !CDS_LOCATION = "C6R4" #SEC = "1" !CDS_SEC = "1";
"A":   PN = "1"  !CDS_PN = "1";
"B":   PN = "2"  !CDS_PN = "2";
BODY = "CAP","I49": #LOCATION = "C6P22" !CDS_LOCATION = "C6P22" #SEC = "1" !CDS_SEC = "1";
"A":   PN = "1"  !CDS_PN = "1";
"B":   PN = "2"  !CDS_PN = "2";
BODY = "CAP","I51": #LOCATION = "C6N8" !CDS_LOCATION = "C6N8" #SEC = "1" !CDS_SEC = "1";
"A":   PN = "1"  !CDS_PN = "1";
"B":   PN = "2"  !CDS_PN = "2";
BODY = "CAP_A","I61": #LOCATION = "C4E3" !CDS_LOCATION = "C4E3" #SEC = "1" !CDS_SEC = "1";
"A":   PN = "1"  !CDS_PN = "1";
"B":   PN = "2"  !CDS_PN = "2";
BODY = "CAP_A","I62": #LOCATION = "C6P16" !CDS_LOCATION = "C6P16" #SEC = "1" !CDS_SEC = "1";
"A":   PN = "1"  !CDS_PN = "1";
"B":   PN = "2"  !CDS_PN = "2";
BODY = "IR354XX","I63": #LOCATION = "EU4E1" !CDS_LOCATION = "EU4E1" &SEC = "1" #&CDS_SEC = "1";
"BOOST":   PN = "33"  !CDS_PN = "33";
"EN":   PN = "35"  !CDS_PN = "35";
"GL<0>":   PN = "6"  !CDS_PN = "6";
"GL<1>":   PN = "41"  !CDS_PN = "41";
"IOUT":   PN = "38"  !CDS_PN = "38";
"LGND":   PN = "2"  !CDS_PN = "2";
"NC":   PN = "31"  !CDS_PN = "31";
"OCSET":   PN = "37"  !CDS_PN = "37";
"PGND<0>":   PN = "5"  !CDS_PN = "5";
"PGND<1>":   PN = "7"  !CDS_PN = "7";
"PGND<2>":   PN = "40"  !CDS_PN = "40";
"PHASE":   PN = "32"  !CDS_PN = "32";
"PWM":   PN = "34"  !CDS_PN = "34";
"REFIN":   PN = "39"  !CDS_PN = "39";
"SW":   PN = "10"  !CDS_PN = "10";
"TOUT_FLT":   PN = "36"  !CDS_PN = "36";
"VCC":   PN = "3"  !CDS_PN = "3";
"VDRV":   PN = "4"  !CDS_PN = "4";
"VIN<0>":   PN = "25"  !CDS_PN = "25";
"VIN<1>":   PN = "30"  !CDS_PN = "30";
"VOS":   PN = "1"  !CDS_PN = "1";
BODY = "IR354XX","I64": #LOCATION = "EU4D6" !CDS_LOCATION = "EU4D6" &SEC = "1" #&CDS_SEC = "1";
"BOOST":   PN = "33"  !CDS_PN = "33";
"EN":   PN = "35"  !CDS_PN = "35";
"GL<0>":   PN = "6"  !CDS_PN = "6";
"GL<1>":   PN = "41"  !CDS_PN = "41";
"IOUT":   PN = "38"  !CDS_PN = "38";
"LGND":   PN = "2"  !CDS_PN = "2";
"NC":   PN = "31"  !CDS_PN = "31";
"OCSET":   PN = "37"  !CDS_PN = "37";
"PGND<0>":   PN = "5"  !CDS_PN = "5";
"PGND<1>":   PN = "7"  !CDS_PN = "7";
"PGND<2>":   PN = "40"  !CDS_PN = "40";
"PHASE":   PN = "32"  !CDS_PN = "32";
"PWM":   PN = "34"  !CDS_PN = "34";
"REFIN":   PN = "39"  !CDS_PN = "39";
"SW":   PN = "10"  !CDS_PN = "10";
"TOUT_FLT":   PN = "36"  !CDS_PN = "36";
"VCC":   PN = "3"  !CDS_PN = "3";
"VDRV":   PN = "4"  !CDS_PN = "4";
"VIN<0>":   PN = "25"  !CDS_PN = "25";
"VIN<1>":   PN = "30"  !CDS_PN = "30";
"VOS":   PN = "1"  !CDS_PN = "1";
BODY = "RES","I65": #LOCATION = "R4E22" !CDS_LOCATION = "R4E22" #SEC = "1" !CDS_SEC = "1";
"A":   PN = "1"  !CDS_PN = "1";
"B":   PN = "2"  !CDS_PN = "2";
BODY = "RES","I67": #LOCATION = "R4E19" !CDS_LOCATION = "R4E19" &SEC = "1" #&CDS_SEC = "1";
"A":   PN = "1"  !CDS_PN = "1";
"B":   PN = "2"  !CDS_PN = "2";
BODY = "CAP_A","I70": #LOCATION = "CT1" !CDS_LOCATION = "CT1" #SEC = "1" !CDS_SEC = "1";
"A":   PN = "1"  !CDS_PN = "1";
"B":   PN = "2"  !CDS_PN = "2";
BODY = "CAP","I78": #LOCATION = "CT2" !CDS_LOCATION = "CT2" #SEC = "1" !CDS_SEC = "1";
"A":   PN = "1"  !CDS_PN = "1";
"B":   PN = "2"  !CDS_PN = "2";
BODY = "CAP_A","I81": #LOCATION = "CT6" !CDS_LOCATION = "CT6" #SEC = "1" !CDS_SEC = "1";
"A":   PN = "1"  !CDS_PN = "1";
"B":   PN = "2"  !CDS_PN = "2";
BODY = "CAP","I87": #LOCATION = "CT4" !CDS_LOCATION = "CT4" #SEC = "1" !CDS_SEC = "1";
"A":   PN = "1"  !CDS_PN = "1";
"B":   PN = "2"  !CDS_PN = "2";
BODY = "CAP","I97": #LOCATION = "CT3" !CDS_LOCATION = "CT3" #SEC = "1" !CDS_SEC = "1";
"A":   PN = "1"  !CDS_PN = "1";
"B":   PN = "2"  !CDS_PN = "2";
BODY = "CAP","I98": #LOCATION = "CT5" !CDS_LOCATION = "CT5" #SEC = "1" !CDS_SEC = "1";
"A":   PN = "1"  !CDS_PN = "1";
"B":   PN = "2"  !CDS_PN = "2";
BODY = "RES","I101": #LOCATION = "RT1" !CDS_LOCATION = "RT1" #SEC = "1" !CDS_SEC = "1";
"A":   PN = "1"  !CDS_PN = "1";
"B":   PN = "2"  !CDS_PN = "2";
BODY = "RES","I102": #LOCATION = "RT3" !CDS_LOCATION = "RT3" #SEC = "1" !CDS_SEC = "1";
"A":   PN = "1"  !CDS_PN = "1";
"B":   PN = "2"  !CDS_PN = "2";
BODY = "RES","I107": #LOCATION = "R6R2" !CDS_LOCATION = "R6R2" #SEC = "1" !CDS_SEC = "1";
"A":   PN = "1"  !CDS_PN = "1";
"B":   PN = "2"  !CDS_PN = "2";
BODY = "RES","I108": #LOCATION = "R6R6" !CDS_LOCATION = "R6R6" #SEC = "1" !CDS_SEC = "1";
"A":   PN = "1"  !CDS_PN = "1";
"B":   PN = "2"  !CDS_PN = "2";
BODY = "IND-120NH-30-GP","I109": #LOCATION = "L4E1" !CDS_LOCATION = "L4E1" #SEC = "1" !CDS_SEC = "1";
"F":   PN = "2"  !CDS_PN = "2";
"S":   PN = "1"  !CDS_PN = "1";
BODY = "IND-120NH-30-GP","I110": #LOCATION = "L4D3" !CDS_LOCATION = "L4D3" #SEC = "1" !CDS_SEC = "1";
"F":   PN = "2"  !CDS_PN = "2";
"S":   PN = "1"  !CDS_PN = "1";
BODY = "SC1U10V2KX-4-GP","I111": #LOCATION = "C4E25" !CDS_LOCATION = "C4E25" #SEC = "1" !CDS_SEC = "1";
"1":   PN = "1"  !CDS_PN = "1";
"2":   PN = "2"  !CDS_PN = "2";
BODY = "SC1U10V2KX-4-GP","I112": #LOCATION = "C4E6" !CDS_LOCATION = "C4E6" #SEC = "1" !CDS_SEC = "1";
"1":   PN = "1"  !CDS_PN = "1";
"2":   PN = "2"  !CDS_PN = "2";
BODY = "1R3F-GP","I114": #LOCATION = "RT2" !CDS_LOCATION = "RT2" #SEC = "1" !CDS_SEC = "1";
"1":   PN = "1"  !CDS_PN = "1";
"2":   PN = "2"  !CDS_PN = "2";
BODY = "1R3F-GP","I115": #LOCATION = "RT4" !CDS_LOCATION = "RT4" #SEC = "1" !CDS_SEC = "1";
"1":   PN = "1"  !CDS_PN = "1";
"2":   PN = "2"  !CDS_PN = "2";
DRAWING = "@baseboard_fab2_lib.baseboard_fab2(sch_1):page203";
BODY = "CAP","I1": #LOCATION = "C6P24" !CDS_LOCATION = "C6P24" #SEC = "1" !CDS_SEC = "1";
"A":   PN = "1"  !CDS_PN = "1";
"B":   PN = "2"  !CDS_PN = "2";
BODY = "CAP","I2": #LOCATION = "C6R6" !CDS_LOCATION = "C6R6" #SEC = "1" !CDS_SEC = "1";
"A":   PN = "1"  !CDS_PN = "1";
"B":   PN = "2"  !CDS_PN = "2";
BODY = "CAP","I3": #LOCATION = "C4D9" !CDS_LOCATION = "C4D9" #SEC = "1" !CDS_SEC = "1";
"A":   PN = "1"  !CDS_PN = "1";
"B":   PN = "2"  !CDS_PN = "2";
BODY = "CAPP","I16": #LOCATION = "C6R3" !CDS_LOCATION = "C6R3" #SEC = "1" !CDS_SEC = "1";
"A":   PN = "1"  !CDS_PN = "1";
"B":   PN = "2"  !CDS_PN = "2";
BODY = "CAPP","I18": #LOCATION = "C6R9" !CDS_LOCATION = "C6R9" #SEC = "1" !CDS_SEC = "1";
"A":   PN = "1"  !CDS_PN = "1";
"B":   PN = "2"  !CDS_PN = "2";
BODY = "CAP_A","I25": #LOCATION = "C6P3" !CDS_LOCATION = "C6P3" #SEC = "1" !CDS_SEC = "1";
"A":   PN = "1"  !CDS_PN = "1";
"B":   PN = "2"  !CDS_PN = "2";
BODY = "CAPP","I28": #LOCATION = "C6P23" !CDS_LOCATION = "C6P23" #SEC = "1" !CDS_SEC = "1";
"A":   PN = "1"  !CDS_PN = "1";
"B":   PN = "2"  !CDS_PN = "2";
BODY = "CAPP","I29": #LOCATION = "C6P14" !CDS_LOCATION = "C6P14" #SEC = "1" !CDS_SEC = "1";
"A":   PN = "1"  !CDS_PN = "1";
"B":   PN = "2"  !CDS_PN = "2";
BODY = "CAPP","I30": #LOCATION = "C6P18" !CDS_LOCATION = "C6P18" #SEC = "1" !CDS_SEC = "1";
"A":   PN = "1"  !CDS_PN = "1";
"B":   PN = "2"  !CDS_PN = "2";
BODY = "CAPP","I32": #LOCATION = "C6P8" !CDS_LOCATION = "C6P8" #SEC = "1" !CDS_SEC = "1";
"A":   PN = "1"  !CDS_PN = "1";
"B":   PN = "2"  !CDS_PN = "2";
BODY = "CAPP","I34": #LOCATION = "C6N9" !CDS_LOCATION = "C6N9" #SEC = "1" !CDS_SEC = "1";
"A":   PN = "1"  !CDS_PN = "1";
"B":   PN = "2"  !CDS_PN = "2";
BODY = "CAP","I40": #LOCATION = "C4D13" !CDS_LOCATION = "C4D13" #SEC = "1" !CDS_SEC = "1";
"A":   PN = "1"  !CDS_PN = "1";
"B":   PN = "2"  !CDS_PN = "2";
BODY = "CAP","I42": #LOCATION = "C4D28" !CDS_LOCATION = "C4D28" #SEC = "1" !CDS_SEC = "1";
"A":   PN = "1"  !CDS_PN = "1";
"B":   PN = "2"  !CDS_PN = "2";
BODY = "CAP","I45": #LOCATION = "C4D16" !CDS_LOCATION = "C4D16" #SEC = "1" !CDS_SEC = "1";
"A":   PN = "1"  !CDS_PN = "1";
"B":   PN = "2"  !CDS_PN = "2";
BODY = "CAP_A","I46": #LOCATION = "C4D35" !CDS_LOCATION = "C4D35" #SEC = "1" !CDS_SEC = "1";
"A":   PN = "1"  !CDS_PN = "1";
"B":   PN = "2"  !CDS_PN = "2";
BODY = "CAP","I47": #LOCATION = "C4D30" !CDS_LOCATION = "C4D30" #SEC = "1" !CDS_SEC = "1";
"A":   PN = "1"  !CDS_PN = "1";
"B":   PN = "2"  !CDS_PN = "2";
BODY = "CAP","I48": #LOCATION = "C4D5" !CDS_LOCATION = "C4D5" #SEC = "1" !CDS_SEC = "1";
"A":   PN = "1"  !CDS_PN = "1";
"B":   PN = "2"  !CDS_PN = "2";
BODY = "CAP","I51": #LOCATION = "C4D7" !CDS_LOCATION = "C4D7" #SEC = "1" !CDS_SEC = "1";
"A":   PN = "1"  !CDS_PN = "1";
"B":   PN = "2"  !CDS_PN = "2";
BODY = "CAP_A","I52": #LOCATION = "C4D11" !CDS_LOCATION = "C4D11" #SEC = "1" !CDS_SEC = "1";
"A":   PN = "1"  !CDS_PN = "1";
"B":   PN = "2"  !CDS_PN = "2";
BODY = "CAP","I53": #LOCATION = "C4D10" !CDS_LOCATION = "C4D10" #SEC = "1" !CDS_SEC = "1";
"A":   PN = "1"  !CDS_PN = "1";
"B":   PN = "2"  !CDS_PN = "2";
BODY = "CAP","I54": #LOCATION = "C6P19" !CDS_LOCATION = "C6P19" #SEC = "1" !CDS_SEC = "1";
"A":   PN = "1"  !CDS_PN = "1";
"B":   PN = "2"  !CDS_PN = "2";
BODY = "CAP","I57": #LOCATION = "C6P20" !CDS_LOCATION = "C6P20" #SEC = "1" !CDS_SEC = "1";
"A":   PN = "1"  !CDS_PN = "1";
"B":   PN = "2"  !CDS_PN = "2";
BODY = "CAP","I58": #LOCATION = "C6P15" !CDS_LOCATION = "C6P15" #SEC = "1" !CDS_SEC = "1";
"A":   PN = "1"  !CDS_PN = "1";
"B":   PN = "2"  !CDS_PN = "2";
BODY = "CAP","I59": #LOCATION = "C6P7" !CDS_LOCATION = "C6P7" #SEC = "1" !CDS_SEC = "1";
"A":   PN = "1"  !CDS_PN = "1";
"B":   PN = "2"  !CDS_PN = "2";
BODY = "CAP_A","I66": #LOCATION = "C6P21" !CDS_LOCATION = "C6P21" #SEC = "1" !CDS_SEC = "1";
"A":   PN = "1"  !CDS_PN = "1";
"B":   PN = "2"  !CDS_PN = "2";
BODY = "RES","I67": #LOCATION = "R4E13" !CDS_LOCATION = "R4E13" #SEC = "1" !CDS_SEC = "1";
"A":   PN = "1"  !CDS_PN = "1";
"B":   PN = "2"  !CDS_PN = "2";
BODY = "CAP_A","I68": #LOCATION = "C4D34" !CDS_LOCATION = "C4D34" #SEC = "1" !CDS_SEC = "1";
"A":   PN = "1"  !CDS_PN = "1";
"B":   PN = "2"  !CDS_PN = "2";
BODY = "CAP_A","I69": #LOCATION = "C4D4" !CDS_LOCATION = "C4D4" #SEC = "1" !CDS_SEC = "1";
"A":   PN = "1"  !CDS_PN = "1";
"B":   PN = "2"  !CDS_PN = "2";
BODY = "IR354XX","I70": #LOCATION = "EU4D3" !CDS_LOCATION = "EU4D3" #SEC = "1" !CDS_SEC = "1";
"BOOST":   PN = "33"  !CDS_PN = "33";
"EN":   PN = "35"  !CDS_PN = "35";
"GL<0>":   PN = "6"  !CDS_PN = "6";
"GL<1>":   PN = "41"  !CDS_PN = "41";
"IOUT":   PN = "38"  !CDS_PN = "38";
"LGND":   PN = "2"  !CDS_PN = "2";
"NC":   PN = "31"  !CDS_PN = "31";
"OCSET":   PN = "37"  !CDS_PN = "37";
"PGND<0>":   PN = "5"  !CDS_PN = "5";
"PGND<1>":   PN = "7"  !CDS_PN = "7";
"PGND<2>":   PN = "40"  !CDS_PN = "40";
"PHASE":   PN = "32"  !CDS_PN = "32";
"PWM":   PN = "34"  !CDS_PN = "34";
"REFIN":   PN = "39"  !CDS_PN = "39";
"SW":   PN = "10"  !CDS_PN = "10";
"TOUT_FLT":   PN = "36"  !CDS_PN = "36";
"VCC":   PN = "3"  !CDS_PN = "3";
"VDRV":   PN = "4"  !CDS_PN = "4";
"VIN<0>":   PN = "25"  !CDS_PN = "25";
"VIN<1>":   PN = "30"  !CDS_PN = "30";
"VOS":   PN = "1"  !CDS_PN = "1";
BODY = "IR354XX","I71": #LOCATION = "EU4D1" !CDS_LOCATION = "EU4D1" &SEC = "1" #&CDS_SEC = "1";
"BOOST":   PN = "33"  !CDS_PN = "33";
"EN":   PN = "35"  !CDS_PN = "35";
"GL<0>":   PN = "6"  !CDS_PN = "6";
"GL<1>":   PN = "41"  !CDS_PN = "41";
"IOUT":   PN = "38"  !CDS_PN = "38";
"LGND":   PN = "2"  !CDS_PN = "2";
"NC":   PN = "31"  !CDS_PN = "31";
"OCSET":   PN = "37"  !CDS_PN = "37";
"PGND<0>":   PN = "5"  !CDS_PN = "5";
"PGND<1>":   PN = "7"  !CDS_PN = "7";
"PGND<2>":   PN = "40"  !CDS_PN = "40";
"PHASE":   PN = "32"  !CDS_PN = "32";
"PWM":   PN = "34"  !CDS_PN = "34";
"REFIN":   PN = "39"  !CDS_PN = "39";
"SW":   PN = "10"  !CDS_PN = "10";
"TOUT_FLT":   PN = "36"  !CDS_PN = "36";
"VCC":   PN = "3"  !CDS_PN = "3";
"VDRV":   PN = "4"  !CDS_PN = "4";
"VIN<0>":   PN = "25"  !CDS_PN = "25";
"VIN<1>":   PN = "30"  !CDS_PN = "30";
"VOS":   PN = "1"  !CDS_PN = "1";
BODY = "RES","I89": #LOCATION = "R4D72" !CDS_LOCATION = "R4D72" #SEC = "1" !CDS_SEC = "1";
"A":   PN = "1"  !CDS_PN = "1";
"B":   PN = "2"  !CDS_PN = "2";
BODY = "RES","I91": #LOCATION = "R4D71" !CDS_LOCATION = "R4D71" #SEC = "1" !CDS_SEC = "1";
"A":   PN = "1"  !CDS_PN = "1";
"B":   PN = "2"  !CDS_PN = "2";
BODY = "CAP_A","I93": #LOCATION = "CT40" !CDS_LOCATION = "CT40" #SEC = "1" !CDS_SEC = "1";
"A":   PN = "1"  !CDS_PN = "1";
"B":   PN = "2"  !CDS_PN = "2";
BODY = "CAP_A","I96": #LOCATION = "CT39" !CDS_LOCATION = "CT39" #SEC = "1" !CDS_SEC = "1";
"A":   PN = "1"  !CDS_PN = "1";
"B":   PN = "2"  !CDS_PN = "2";
BODY = "CAP","I99": #LOCATION = "CT37" !CDS_LOCATION = "CT37" #SEC = "1" !CDS_SEC = "1";
"A":   PN = "1"  !CDS_PN = "1";
"B":   PN = "2"  !CDS_PN = "2";
BODY = "CAP","I108": #LOCATION = "CT42" !CDS_LOCATION = "CT42" #SEC = "1" !CDS_SEC = "1";
"A":   PN = "1"  !CDS_PN = "1";
"B":   PN = "2"  !CDS_PN = "2";
BODY = "CAP","I118": #LOCATION = "CT38" !CDS_LOCATION = "CT38" #SEC = "1" !CDS_SEC = "1";
"A":   PN = "1"  !CDS_PN = "1";
"B":   PN = "2"  !CDS_PN = "2";
BODY = "CAP","I119": #LOCATION = "CT41" !CDS_LOCATION = "CT41" #SEC = "1" !CDS_SEC = "1";
"A":   PN = "1"  !CDS_PN = "1";
"B":   PN = "2"  !CDS_PN = "2";
BODY = "RES","I122": #LOCATION = "RT25" !CDS_LOCATION = "RT25" #SEC = "1" !CDS_SEC = "1";
"A":   PN = "1"  !CDS_PN = "1";
"B":   PN = "2"  !CDS_PN = "2";
BODY = "RES","I123": #LOCATION = "RT28" !CDS_LOCATION = "RT28" #SEC = "1" !CDS_SEC = "1";
"A":   PN = "1"  !CDS_PN = "1";
"B":   PN = "2"  !CDS_PN = "2";
BODY = "RES","I128": #LOCATION = "R6P19" !CDS_LOCATION = "R6P19" #SEC = "1" !CDS_SEC = "1";
"A":   PN = "1"  !CDS_PN = "1";
"B":   PN = "2"  !CDS_PN = "2";
BODY = "RES","I129": #LOCATION = "R6P10" !CDS_LOCATION = "R6P10" #SEC = "1" !CDS_SEC = "1";
"A":   PN = "1"  !CDS_PN = "1";
"B":   PN = "2"  !CDS_PN = "2";
BODY = "IND-120NH-30-GP","I130": #LOCATION = "L4D2" !CDS_LOCATION = "L4D2" #SEC = "1" !CDS_SEC = "1";
"F":   PN = "2"  !CDS_PN = "2";
"S":   PN = "1"  !CDS_PN = "1";
BODY = "IND-120NH-30-GP","I131": #LOCATION = "L4D1" !CDS_LOCATION = "L4D1" #SEC = "1" !CDS_SEC = "1";
"F":   PN = "2"  !CDS_PN = "2";
"S":   PN = "1"  !CDS_PN = "1";
BODY = "SC1U10V2KX-4-GP","I132": #LOCATION = "C4D14" !CDS_LOCATION = "C4D14" #SEC = "1" !CDS_SEC = "1";
"1":   PN = "1"  !CDS_PN = "1";
"2":   PN = "2"  !CDS_PN = "2";
BODY = "SC1U10V2KX-4-GP","I133": #LOCATION = "C4D6" !CDS_LOCATION = "C4D6" #SEC = "1" !CDS_SEC = "1";
"1":   PN = "1"  !CDS_PN = "1";
"2":   PN = "2"  !CDS_PN = "2";
BODY = "1R3F-GP","I134": #LOCATION = "RT26" !CDS_LOCATION = "RT26" #SEC = "1" !CDS_SEC = "1";
"1":   PN = "1"  !CDS_PN = "1";
"2":   PN = "2"  !CDS_PN = "2";
BODY = "1R3F-GP","I135": #LOCATION = "RT27" !CDS_LOCATION = "RT27" #SEC = "1" !CDS_SEC = "1";
"1":   PN = "1"  !CDS_PN = "1";
"2":   PN = "2"  !CDS_PN = "2";
DRAWING = "@baseboard_fab2_lib.baseboard_fab2(sch_1):page204";
BODY = "CAP_A","I9": #LOCATION = "C4D12" !CDS_LOCATION = "C4D12" #SEC = "1" !CDS_SEC = "1";
"A":   PN = "1"  !CDS_PN = "1";
"B":   PN = "2"  !CDS_PN = "2";
BODY = "CAP","I18": #LOCATION = "C4D47" !CDS_LOCATION = "C4D47" #SEC = "1" !CDS_SEC = "1";
"A":   PN = "1"  !CDS_PN = "1";
"B":   PN = "2"  !CDS_PN = "2";
BODY = "CAP","I22": #LOCATION = "C4C17" !CDS_LOCATION = "C4C17" #SEC = "1" !CDS_SEC = "1";
"A":   PN = "1"  !CDS_PN = "1";
"B":   PN = "2"  !CDS_PN = "2";
BODY = "CAP","I34": #LOCATION = "C4D46" !CDS_LOCATION = "C4D46" #SEC = "1" !CDS_SEC = "1";
"A":   PN = "1"  !CDS_PN = "1";
"B":   PN = "2"  !CDS_PN = "2";
BODY = "CAP_A","I35": #LOCATION = "C4C19" !CDS_LOCATION = "C4C19" #SEC = "1" !CDS_SEC = "1";
"A":   PN = "1"  !CDS_PN = "1";
"B":   PN = "2"  !CDS_PN = "2";
BODY = "CAP","I36": #LOCATION = "C4C18" !CDS_LOCATION = "C4C18" #SEC = "1" !CDS_SEC = "1";
"A":   PN = "1"  !CDS_PN = "1";
"B":   PN = "2"  !CDS_PN = "2";
BODY = "CAP","I37": #LOCATION = "C6N10" !CDS_LOCATION = "C6N10" #SEC = "1" !CDS_SEC = "1";
"A":   PN = "1"  !CDS_PN = "1";
"B":   PN = "2"  !CDS_PN = "2";
BODY = "CAP","I38": #LOCATION = "C6P17" !CDS_LOCATION = "C6P17" #SEC = "1" !CDS_SEC = "1";
"A":   PN = "1"  !CDS_PN = "1";
"B":   PN = "2"  !CDS_PN = "2";
BODY = "CAP","I42": #LOCATION = "C6N11" !CDS_LOCATION = "C6N11" #SEC = "1" !CDS_SEC = "1";
"A":   PN = "1"  !CDS_PN = "1";
"B":   PN = "2"  !CDS_PN = "2";
BODY = "CAPP","I48": #LOCATION = "C4D2" !CDS_LOCATION = "C4D2" #SEC = "1" !CDS_SEC = "1";
"A":   PN = "1"  !CDS_PN = "1";
"B":   PN = "2"  !CDS_PN = "2";
BODY = "CAPP","I50": #LOCATION = "C4E16" !CDS_LOCATION = "C4E16" #SEC = "1" !CDS_SEC = "1";
"A":   PN = "1"  !CDS_PN = "1";
"B":   PN = "2"  !CDS_PN = "2";
BODY = "RES","I60": #LOCATION = "R4E14" !CDS_LOCATION = "R4E14" &SEC = "1" #&CDS_SEC = "1";
"A":   PN = "1"  !CDS_PN = "1";
"B":   PN = "2"  !CDS_PN = "2";
BODY = "RES","I61": #LOCATION = "R4E16" !CDS_LOCATION = "R4E16" &SEC = "1" #&CDS_SEC = "1";
"A":   PN = "1"  !CDS_PN = "1";
"B":   PN = "2"  !CDS_PN = "2";
BODY = "RES","I62": #LOCATION = "R4E17" !CDS_LOCATION = "R4E17" &SEC = "1" #&CDS_SEC = "1";
"A":   PN = "1"  !CDS_PN = "1";
"B":   PN = "2"  !CDS_PN = "2";
BODY = "RES","I63": #LOCATION = "R4E15" !CDS_LOCATION = "R4E15" &SEC = "1" #&CDS_SEC = "1";
"A":   PN = "1"  !CDS_PN = "1";
"B":   PN = "2"  !CDS_PN = "2";
BODY = "RES","I64": #LOCATION = "R4E18" !CDS_LOCATION = "R4E18" &SEC = "1" #&CDS_SEC = "1";
"A":   PN = "1"  !CDS_PN = "1";
"B":   PN = "2"  !CDS_PN = "2";
BODY = "CAPP","I67": #LOCATION = "C4C12" !CDS_LOCATION = "C4C12" #SEC = "1" !CDS_SEC = "1";
"A":   PN = "1"  !CDS_PN = "1";
"B":   PN = "2"  !CDS_PN = "2";
BODY = "CAP_A","I70": #LOCATION = "C6R2" !CDS_LOCATION = "C6R2" #SEC = "1" !CDS_SEC = "1";
"A":   PN = "1"  !CDS_PN = "1";
"B":   PN = "2"  !CDS_PN = "2";
BODY = "IR354XX","I71": #LOCATION = "EU4C2" !CDS_LOCATION = "EU4C2" &SEC = "1" #&CDS_SEC = "1";
"BOOST":   PN = "33"  !CDS_PN = "33";
"EN":   PN = "35"  !CDS_PN = "35";
"GL<0>":   PN = "6"  !CDS_PN = "6";
"GL<1>":   PN = "41"  !CDS_PN = "41";
"IOUT":   PN = "38"  !CDS_PN = "38";
"LGND":   PN = "2"  !CDS_PN = "2";
"NC":   PN = "31"  !CDS_PN = "31";
"OCSET":   PN = "37"  !CDS_PN = "37";
"PGND<0>":   PN = "5"  !CDS_PN = "5";
"PGND<1>":   PN = "7"  !CDS_PN = "7";
"PGND<2>":   PN = "40"  !CDS_PN = "40";
"PHASE":   PN = "32"  !CDS_PN = "32";
"PWM":   PN = "34"  !CDS_PN = "34";
"REFIN":   PN = "39"  !CDS_PN = "39";
"SW":   PN = "10"  !CDS_PN = "10";
"TOUT_FLT":   PN = "36"  !CDS_PN = "36";
"VCC":   PN = "3"  !CDS_PN = "3";
"VDRV":   PN = "4"  !CDS_PN = "4";
"VIN<0>":   PN = "25"  !CDS_PN = "25";
"VIN<1>":   PN = "30"  !CDS_PN = "30";
"VOS":   PN = "1"  !CDS_PN = "1";
BODY = "RES","I83": #LOCATION = "R4D68" !CDS_LOCATION = "R4D68" #SEC = "1" !CDS_SEC = "1";
"A":   PN = "1"  !CDS_PN = "1";
"B":   PN = "2"  !CDS_PN = "2";
BODY = "CAP_A","I85": #LOCATION = "CT36" !CDS_LOCATION = "CT36" #SEC = "1" !CDS_SEC = "1";
"A":   PN = "1"  !CDS_PN = "1";
"B":   PN = "2"  !CDS_PN = "2";
BODY = "CAP","I88": #LOCATION = "CT34" !CDS_LOCATION = "CT34" #SEC = "1" !CDS_SEC = "1";
"A":   PN = "1"  !CDS_PN = "1";
"B":   PN = "2"  !CDS_PN = "2";
BODY = "CAP","I97": #LOCATION = "CT35" !CDS_LOCATION = "CT35" #SEC = "1" !CDS_SEC = "1";
"A":   PN = "1"  !CDS_PN = "1";
"B":   PN = "2"  !CDS_PN = "2";
BODY = "RES","I99": #LOCATION = "RT23" !CDS_LOCATION = "RT23" #SEC = "1" !CDS_SEC = "1";
"A":   PN = "1"  !CDS_PN = "1";
"B":   PN = "2"  !CDS_PN = "2";
BODY = "RES","I103": #LOCATION = "R6P47" !CDS_LOCATION = "R6P47" #SEC = "1" !CDS_SEC = "1";
"A":   PN = "1"  !CDS_PN = "1";
"B":   PN = "2"  !CDS_PN = "2";
BODY = "IND-120NH-30-GP","I104": #LOCATION = "L4C3" !CDS_LOCATION = "L4C3" #SEC = "1" !CDS_SEC = "1";
"F":   PN = "2"  !CDS_PN = "2";
"S":   PN = "1"  !CDS_PN = "1";
BODY = "IND-80NH-1-GP","I105": #LOCATION = "L4C1" !CDS_LOCATION = "L4C1" #SEC = "1" !CDS_SEC = "1";
"F":   PN = "2"  !CDS_PN = "2";
"S":   PN = "1"  !CDS_PN = "1";
BODY = "SC1U10V2KX-4-GP","I113": #LOCATION = "C4C14" !CDS_LOCATION = "C4C14" #SEC = "1" !CDS_SEC = "1";
"1":   PN = "1"  !CDS_PN = "1";
"2":   PN = "2"  !CDS_PN = "2";
BODY = "1R3F-GP","I114": #LOCATION = "RT24" !CDS_LOCATION = "RT24" #SEC = "1" !CDS_SEC = "1";
"1":   PN = "1"  !CDS_PN = "1";
"2":   PN = "2"  !CDS_PN = "2";
DRAWING = "@baseboard_fab2_lib.baseboard_fab2(sch_1):page205";
BODY = "CAP_A","I5": #LOCATION = "C6N7" !CDS_LOCATION = "C6N7" #SEC = "1" !CDS_SEC = "1";
"A":   PN = "1"  !CDS_PN = "1";
"B":   PN = "2"  !CDS_PN = "2";
BODY = "CAPP","I12": #LOCATION = "C6N1" !CDS_LOCATION = "C6N1" #SEC = "1" !CDS_SEC = "1";
"A":   PN = "1"  !CDS_PN = "1";
"B":   PN = "2"  !CDS_PN = "2";
BODY = "CAPP","I14": #LOCATION = "C6N4" !CDS_LOCATION = "C6N4" #SEC = "1" !CDS_SEC = "1";
"A":   PN = "1"  !CDS_PN = "1";
"B":   PN = "2"  !CDS_PN = "2";
BODY = "CAP","I16": #LOCATION = "C4C5" !CDS_LOCATION = "C4C5" #SEC = "1" !CDS_SEC = "1";
"A":   PN = "1"  !CDS_PN = "1";
"B":   PN = "2"  !CDS_PN = "2";
BODY = "CAP","I20": #LOCATION = "C4C6" !CDS_LOCATION = "C4C6" #SEC = "1" !CDS_SEC = "1";
"A":   PN = "1"  !CDS_PN = "1";
"B":   PN = "2"  !CDS_PN = "2";
BODY = "RES","I24": #LOCATION = "R4C5" !CDS_LOCATION = "R4C5" #SEC = "1" !CDS_SEC = "1";
"A":   PN = "1"  !CDS_PN = "1";
"B":   PN = "2"  !CDS_PN = "2";
BODY = "CAP","I25": #LOCATION = "C4C8" !CDS_LOCATION = "C4C8" #SEC = "1" !CDS_SEC = "1";
"A":   PN = "1"  !CDS_PN = "1";
"B":   PN = "2"  !CDS_PN = "2";
BODY = "RES","I26": #LOCATION = "R4C4" !CDS_LOCATION = "R4C4" #SEC = "1" !CDS_SEC = "1";
"A":   PN = "1"  !CDS_PN = "1";
"B":   PN = "2"  !CDS_PN = "2";
BODY = "RES","I29": #LOCATION = "R4C1" !CDS_LOCATION = "R4C1" #SEC = "1" !CDS_SEC = "1";
"A":   PN = "1"  !CDS_PN = "1";
"B":   PN = "2"  !CDS_PN = "2";
BODY = "RES","I30": #LOCATION = "R4C2" !CDS_LOCATION = "R4C2" #SEC = "1" !CDS_SEC = "1";
"A":   PN = "1"  !CDS_PN = "1";
"B":   PN = "2"  !CDS_PN = "2";
BODY = "CAP_A","I31": #LOCATION = "C4C10" !CDS_LOCATION = "C4C10" #SEC = "1" !CDS_SEC = "1";
"A":   PN = "1"  !CDS_PN = "1";
"B":   PN = "2"  !CDS_PN = "2";
BODY = "CAP","I32": #LOCATION = "C4C9" !CDS_LOCATION = "C4C9" #SEC = "1" !CDS_SEC = "1";
"A":   PN = "1"  !CDS_PN = "1";
"B":   PN = "2"  !CDS_PN = "2";
BODY = "CAP","I33": #LOCATION = "C6N2" !CDS_LOCATION = "C6N2" #SEC = "1" !CDS_SEC = "1";
"A":   PN = "1"  !CDS_PN = "1";
"B":   PN = "2"  !CDS_PN = "2";
BODY = "CAP","I34": #LOCATION = "C6N3" !CDS_LOCATION = "C6N3" #SEC = "1" !CDS_SEC = "1";
"A":   PN = "1"  !CDS_PN = "1";
"B":   PN = "2"  !CDS_PN = "2";
BODY = "CAP","I35": #LOCATION = "C6N6" !CDS_LOCATION = "C6N6" #SEC = "1" !CDS_SEC = "1";
"A":   PN = "1"  !CDS_PN = "1";
"B":   PN = "2"  !CDS_PN = "2";
BODY = "RES","I37": #LOCATION = "R4C3" !CDS_LOCATION = "R4C3" #SEC = "1" !CDS_SEC = "1";
"A":   PN = "1"  !CDS_PN = "1";
"B":   PN = "2"  !CDS_PN = "2";
BODY = "CAP_A","I43": #LOCATION = "C4C11" !CDS_LOCATION = "C4C11" #SEC = "1" !CDS_SEC = "1";
"A":   PN = "1"  !CDS_PN = "1";
"B":   PN = "2"  !CDS_PN = "2";
BODY = "RES","I45": #LOCATION = "R6N4" !CDS_LOCATION = "R6N4" #SEC = "1" !CDS_SEC = "1";
"A":   PN = "1"  !CDS_PN = "1";
"B":   PN = "2"  !CDS_PN = "2";
BODY = "IR354XX","I46": #LOCATION = "EU4C1" !CDS_LOCATION = "EU4C1" &SEC = "1" #&CDS_SEC = "1";
"BOOST":   PN = "33"  !CDS_PN = "33";
"EN":   PN = "35"  !CDS_PN = "35";
"GL<0>":   PN = "6"  !CDS_PN = "6";
"GL<1>":   PN = "41"  !CDS_PN = "41";
"IOUT":   PN = "38"  !CDS_PN = "38";
"LGND":   PN = "2"  !CDS_PN = "2";
"NC":   PN = "31"  !CDS_PN = "31";
"OCSET":   PN = "37"  !CDS_PN = "37";
"PGND<0>":   PN = "5"  !CDS_PN = "5";
"PGND<1>":   PN = "7"  !CDS_PN = "7";
"PGND<2>":   PN = "40"  !CDS_PN = "40";
"PHASE":   PN = "32"  !CDS_PN = "32";
"PWM":   PN = "34"  !CDS_PN = "34";
"REFIN":   PN = "39"  !CDS_PN = "39";
"SW":   PN = "10"  !CDS_PN = "10";
"TOUT_FLT":   PN = "36"  !CDS_PN = "36";
"VCC":   PN = "3"  !CDS_PN = "3";
"VDRV":   PN = "4"  !CDS_PN = "4";
"VIN<0>":   PN = "25"  !CDS_PN = "25";
"VIN<1>":   PN = "30"  !CDS_PN = "30";
"VOS":   PN = "1"  !CDS_PN = "1";
BODY = "RES","I62": #LOCATION = "R4C13" !CDS_LOCATION = "R4C13" &SEC = "1" #&CDS_SEC = "1";
"A":   PN = "1"  !CDS_PN = "1";
"B":   PN = "2"  !CDS_PN = "2";
BODY = "CAP","I65": #LOCATION = "CT58" !CDS_LOCATION = "CT58" #SEC = "1" !CDS_SEC = "1";
"A":   PN = "1"  !CDS_PN = "1";
"B":   PN = "2"  !CDS_PN = "2";
BODY = "CAP_A","I69": #LOCATION = "CT60" !CDS_LOCATION = "CT60" #SEC = "1" !CDS_SEC = "1";
"A":   PN = "1"  !CDS_PN = "1";
"B":   PN = "2"  !CDS_PN = "2";
BODY = "CAP","I76": #LOCATION = "CT59" !CDS_LOCATION = "CT59" #SEC = "1" !CDS_SEC = "1";
"A":   PN = "1"  !CDS_PN = "1";
"B":   PN = "2"  !CDS_PN = "2";
BODY = "RES","I78": #LOCATION = "RT40" !CDS_LOCATION = "RT40" #SEC = "1" !CDS_SEC = "1";
"A":   PN = "1"  !CDS_PN = "1";
"B":   PN = "2"  !CDS_PN = "2";
BODY = "RES","I81": #LOCATION = "R6N3" !CDS_LOCATION = "R6N3" #SEC = "1" !CDS_SEC = "1";
"A":   PN = "1"  !CDS_PN = "1";
"B":   PN = "2"  !CDS_PN = "2";
BODY = "IND-300NH-20-GP","I82": #LOCATION = "L4C2" !CDS_LOCATION = "L4C2" #SEC = "1" !CDS_SEC = "1";
"F":   PN = "2"  !CDS_PN = "2";
"S":   PN = "1"  !CDS_PN = "1";
BODY = "SC1U10V2KX-4-GP","I83": #LOCATION = "C4C4" !CDS_LOCATION = "C4C4" #SEC = "1" !CDS_SEC = "1";
"1":   PN = "1"  !CDS_PN = "1";
"2":   PN = "2"  !CDS_PN = "2";
BODY = "1R3F-GP","I84": #LOCATION = "RT39" !CDS_LOCATION = "RT39" #SEC = "1" !CDS_SEC = "1";
"1":   PN = "1"  !CDS_PN = "1";
"2":   PN = "2"  !CDS_PN = "2";
DRAWING = "@baseboard_fab2_lib.baseboard_fab2(sch_1):page206";
BODY = "RES","I4": #LOCATION = "R9P1" !CDS_LOCATION = "R9P1" #SEC = "1" !CDS_SEC = "1";
"A":   PN = "1"  !CDS_PN = "1";
"B":   PN = "2"  !CDS_PN = "2";
BODY = "RES","I6": #LOCATION = "R1D6" !CDS_LOCATION = "R1D6" #SEC = "1" !CDS_SEC = "1";
"A":   PN = "1"  !CDS_PN = "1";
"B":   PN = "2"  !CDS_PN = "2";
BODY = "CAP_A","I29": #LOCATION = "C1C13" !CDS_LOCATION = "C1C13" #SEC = "1" !CDS_SEC = "1";
"A":   PN = "1"  !CDS_PN = "1";
"B":   PN = "2"  !CDS_PN = "2";
BODY = "CAP_A","I31": #LOCATION = "C1C14" !CDS_LOCATION = "C1C14" #SEC = "1" !CDS_SEC = "1";
"A":   PN = "1"  !CDS_PN = "1";
"B":   PN = "2"  !CDS_PN = "2";
BODY = "RES","I33": #LOCATION = "R1D53" !CDS_LOCATION = "R1D53" #SEC = "1" !CDS_SEC = "1";
"A":   PN = "1"  !CDS_PN = "1";
"B":   PN = "2"  !CDS_PN = "2";
BODY = "RES","I34": #LOCATION = "R1C18" !CDS_LOCATION = "R1C18" #SEC = "1" !CDS_SEC = "1";
"A":   PN = "1"  !CDS_PN = "1";
"B":   PN = "2"  !CDS_PN = "2";
BODY = "RES","I35": #LOCATION = "R1C28" !CDS_LOCATION = "R1C28" #SEC = "1" !CDS_SEC = "1";
"A":   PN = "1"  !CDS_PN = "1";
"B":   PN = "2"  !CDS_PN = "2";
BODY = "RES","I36": #LOCATION = "R1D8" !CDS_LOCATION = "R1D8" #SEC = "1" !CDS_SEC = "1";
"A":   PN = "1"  !CDS_PN = "1";
"B":   PN = "2"  !CDS_PN = "2";
BODY = "RES","I37": #LOCATION = "R1D3" !CDS_LOCATION = "R1D3" #SEC = "1" !CDS_SEC = "1";
"A":   PN = "1"  !CDS_PN = "1";
"B":   PN = "2"  !CDS_PN = "2";
BODY = "RES","I38": #LOCATION = "R1D2" !CDS_LOCATION = "R1D2" #SEC = "1" !CDS_SEC = "1";
"A":   PN = "1"  !CDS_PN = "1";
"B":   PN = "2"  !CDS_PN = "2";
BODY = "CAP_A","I41": #LOCATION = "C1C7" !CDS_LOCATION = "C1C7" &SEC = "1" #&CDS_SEC = "1";
"A":   PN = "1"  !CDS_PN = "1";
"B":   PN = "2"  !CDS_PN = "2";
BODY = "CAP_A","I42": #LOCATION = "C1C9" !CDS_LOCATION = "C1C9" #SEC = "1" !CDS_SEC = "1";
"A":   PN = "1"  !CDS_PN = "1";
"B":   PN = "2"  !CDS_PN = "2";
BODY = "RES","I46": #LOCATION = "R1C14" !CDS_LOCATION = "R1C14" #SEC = "1" !CDS_SEC = "1";
"A":   PN = "1"  !CDS_PN = "1";
"B":   PN = "2"  !CDS_PN = "2";
BODY = "RES","I49": #LOCATION = "R1C13" !CDS_LOCATION = "R1C13" #SEC = "1" !CDS_SEC = "1";
"A":   PN = "1"  !CDS_PN = "1";
"B":   PN = "2"  !CDS_PN = "2";
BODY = "RES","I53": #LOCATION = "R9P2" !CDS_LOCATION = "R9P2" #SEC = "1" !CDS_SEC = "1";
"A":   PN = "1"  !CDS_PN = "1";
"B":   PN = "2"  !CDS_PN = "2";
BODY = "RES","I54": #LOCATION = "R1D9" !CDS_LOCATION = "R1D9" &SEC = "1" #&CDS_SEC = "1";
"A":   PN = "1"  !CDS_PN = "1";
"B":   PN = "2"  !CDS_PN = "2";
BODY = "RES","I56": #LOCATION = "R1C16" !CDS_LOCATION = "R1C16" #SEC = "1" !CDS_SEC = "1";
"A":   PN = "1"  !CDS_PN = "1";
"B":   PN = "2"  !CDS_PN = "2";
BODY = "CAP","I68": #LOCATION = "C1C16" !CDS_LOCATION = "C1C16" #SEC = "1" !CDS_SEC = "1";
"A":   PN = "1"  !CDS_PN = "1";
"B":   PN = "2"  !CDS_PN = "2";
BODY = "CAP","I69": #LOCATION = "C1C10" !CDS_LOCATION = "C1C10" #SEC = "1" !CDS_SEC = "1";
"A":   PN = "1"  !CDS_PN = "1";
"B":   PN = "2"  !CDS_PN = "2";
BODY = "CAP","I71": #LOCATION = "C1C11" !CDS_LOCATION = "C1C11" #SEC = "1" !CDS_SEC = "1";
"A":   PN = "1"  !CDS_PN = "1";
"B":   PN = "2"  !CDS_PN = "2";
BODY = "RES","I77": #LOCATION = "R1C21" !CDS_LOCATION = "R1C21" #SEC = "1" !CDS_SEC = "1";
"A":   PN = "1"  !CDS_PN = "1";
"B":   PN = "2"  !CDS_PN = "2";
BODY = "CAP","I78": #LOCATION = "C1D1" !CDS_LOCATION = "C1D1" #SEC = "1" !CDS_SEC = "1";
"A":   PN = "1"  !CDS_PN = "1";
"B":   PN = "2"  !CDS_PN = "2";
BODY = "RES","I79": #LOCATION = "R1D4" !CDS_LOCATION = "R1D4" #SEC = "1" !CDS_SEC = "1";
"A":   PN = "1"  !CDS_PN = "1";
"B":   PN = "2"  !CDS_PN = "2";
BODY = "RES","I111": #LOCATION = "R9N7" !CDS_LOCATION = "R9N7" #SEC = "1" !CDS_SEC = "1";
"A":   PN = "1"  !CDS_PN = "1";
"B":   PN = "2"  !CDS_PN = "2";
BODY = "RES","I112": #LOCATION = "R9N8" !CDS_LOCATION = "R9N8" #SEC = "1" !CDS_SEC = "1";
"A":   PN = "1"  !CDS_PN = "1";
"B":   PN = "2"  !CDS_PN = "2";
BODY = "RES","I113": #LOCATION = "R1C30" !CDS_LOCATION = "R1C30" #SEC = "1" !CDS_SEC = "1";
"A":   PN = "1"  !CDS_PN = "1";
"B":   PN = "2"  !CDS_PN = "2";
BODY = "CAP","I114": #LOCATION = "C1C23" !CDS_LOCATION = "C1C23" #SEC = "1" !CDS_SEC = "1";
"A":   PN = "1"  !CDS_PN = "1";
"B":   PN = "2"  !CDS_PN = "2";
BODY = "RES","I116": #LOCATION = "R1D1" !CDS_LOCATION = "R1D1" #SEC = "1" !CDS_SEC = "1";
"A":   PN = "1"  !CDS_PN = "1";
"B":   PN = "2"  !CDS_PN = "2";
BODY = "RES","I117": #LOCATION = "R9P3" !CDS_LOCATION = "R9P3" #SEC = "1" !CDS_SEC = "1";
"A":   PN = "1"  !CDS_PN = "1";
"B":   PN = "2"  !CDS_PN = "2";
BODY = "RES","I119": #LOCATION = "R9N16" !CDS_LOCATION = "R9N16" #SEC = "1" !CDS_SEC = "1";
"A":   PN = "1"  !CDS_PN = "1";
"B":   PN = "2"  !CDS_PN = "2";
BODY = "RES","I120": #LOCATION = "R9N14" !CDS_LOCATION = "R9N14" #SEC = "1" !CDS_SEC = "1";
"A":   PN = "1"  !CDS_PN = "1";
"B":   PN = "2"  !CDS_PN = "2";
BODY = "PXE1610B","I130": #LOCATION = "EU1C2" !CDS_LOCATION = "EU1C2" #SEC = "1" !CDS_SEC = "1";
"AIREF1":   PN = "23"  !CDS_PN = "23";
"AIREF2":   PN = "25"  !CDS_PN = "25";
"AIREF3":   PN = "27"  !CDS_PN = "27";
"AIREF4":   PN = "29"  !CDS_PN = "29";
"AIREF5":   PN = "31"  !CDS_PN = "31";
"AIREF6":   PN = "33"  !CDS_PN = "33";
"AISEN1":   PN = "24"  !CDS_PN = "24";
"AISEN2":   PN = "26"  !CDS_PN = "26";
"AISEN3":   PN = "28"  !CDS_PN = "28";
"AISEN4":   PN = "30"  !CDS_PN = "30";
"AISEN5":   PN = "32"  !CDS_PN = "32";
"AISEN6":   PN = "34"  !CDS_PN = "34";
"APWM1":   PN = "7"  !CDS_PN = "7";
"APWM2":   PN = "6"  !CDS_PN = "6";
"APWM3":   PN = "5"  !CDS_PN = "5";
"APWM4":   PN = "4"  !CDS_PN = "4";
"APWM5":   PN = "3"  !CDS_PN = "3";
"APWM6":   PN = "2"  !CDS_PN = "2";
"ATSEN":   PN = "43"  !CDS_PN = "43";
"AVREF":   PN = "22"  !CDS_PN = "22";
"AVREN":   PN = "12"  !CDS_PN = "12";
"AVRRDY":   PN = "11"  !CDS_PN = "11";
"AVSEN":   PN = "21"  !CDS_PN = "21";
"BIREF1":   PN = "37"  !CDS_PN = "37";
"BISEN1":   PN = "38"  !CDS_PN = "38";
"BPWM1":   PN = "1"  !CDS_PN = "1";
"BTSEN":   PN = "42"  !CDS_PN = "42";
"BVREF":   PN = "36"  !CDS_PN = "36";
"BVSEN":   PN = "35"  !CDS_PN = "35";
"IINSEN":   PN = "46"  !CDS_PN = "46";
"MP0":   PN = "15"  !CDS_PN = "15";
"MP1":   PN = "16"  !CDS_PN = "16";
"MP2":   PN = "20"  !CDS_PN = "20";
"MP3":   PN = "39"  !CDS_PN = "39";
"MP4":   PN = "40"  !CDS_PN = "40";
"PINALRT_N":   PN = "14"  !CDS_PN = "14";
"RESET_N":   PN = "10"  !CDS_PN = "10";
"SCL":   PN = "9"  !CDS_PN = "9";
"SDA":   PN = "8"  !CDS_PN = "8";
"THPAD":   PN = "49"  !CDS_PN = "49";
"VALRT_N":   PN = "19"  !CDS_PN = "19";
"VCLK":   PN = "17"  !CDS_PN = "17";
"VD12":   PN = "48"  !CDS_PN = "48";
"VDD":   PN = "47"  !CDS_PN = "47";
"VDIO":   PN = "18"  !CDS_PN = "18";
"VINSEN":   PN = "45"  !CDS_PN = "45";
"VRHOT_N":   PN = "13"  !CDS_PN = "13";
"XADDR1":   PN = "44"  !CDS_PN = "44";
"XADDR2":   PN = "41"  !CDS_PN = "41";
BODY = "SC22P50V2JN-4GP","I137": #LOCATION = "CF7" !CDS_LOCATION = "CF7" &SEC = "1" #&CDS_SEC = "1";
"1":   PN = "1"  !CDS_PN = "1";
"2":   PN = "2"  !CDS_PN = "2";
BODY = "SC22P50V2JN-4GP","I138": #LOCATION = "CF8" !CDS_LOCATION = "CF8" #SEC = "1" !CDS_SEC = "1";
"1":   PN = "1"  !CDS_PN = "1";
"2":   PN = "2"  !CDS_PN = "2";
BODY = "SC22P50V2JN-4GP","I139": #LOCATION = "CF9" !CDS_LOCATION = "CF9" &SEC = "1" #&CDS_SEC = "1";
"1":   PN = "1"  !CDS_PN = "1";
"2":   PN = "2"  !CDS_PN = "2";
BODY = "SC22P50V2JN-4GP","I140": #LOCATION = "CF10" !CDS_LOCATION = "CF10" &SEC = "1" #&CDS_SEC = "1";
"1":   PN = "1"  !CDS_PN = "1";
"2":   PN = "2"  !CDS_PN = "2";
BODY = "SC22P50V2JN-4GP","I141": #LOCATION = "CF11" !CDS_LOCATION = "CF11" &SEC = "1" #&CDS_SEC = "1";
"1":   PN = "1"  !CDS_PN = "1";
"2":   PN = "2"  !CDS_PN = "2";
BODY = "SC22P50V2JN-4GP","I142": #LOCATION = "CF12" !CDS_LOCATION = "CF12" &SEC = "1" #&CDS_SEC = "1";
"1":   PN = "1"  !CDS_PN = "1";
"2":   PN = "2"  !CDS_PN = "2";
BODY = "RES","I149": #LOCATION = "RF12" !CDS_LOCATION = "RF12" #SEC = "1" !CDS_SEC = "1";
"A":   PN = "1"  !CDS_PN = "1";
"B":   PN = "2"  !CDS_PN = "2";
BODY = "RES","I150": #LOCATION = "RF7" !CDS_LOCATION = "RF7" #SEC = "1" !CDS_SEC = "1";
"A":   PN = "1"  !CDS_PN = "1";
"B":   PN = "2"  !CDS_PN = "2";
BODY = "RES","I151": #LOCATION = "RF8" !CDS_LOCATION = "RF8" #SEC = "1" !CDS_SEC = "1";
"A":   PN = "1"  !CDS_PN = "1";
"B":   PN = "2"  !CDS_PN = "2";
BODY = "RES","I152": #LOCATION = "RF9" !CDS_LOCATION = "RF9" #SEC = "1" !CDS_SEC = "1";
"A":   PN = "1"  !CDS_PN = "1";
"B":   PN = "2"  !CDS_PN = "2";
BODY = "RES","I153": #LOCATION = "RF10" !CDS_LOCATION = "RF10" #SEC = "1" !CDS_SEC = "1";
"A":   PN = "1"  !CDS_PN = "1";
"B":   PN = "2"  !CDS_PN = "2";
BODY = "RES","I154": #LOCATION = "RF11" !CDS_LOCATION = "RF11" #SEC = "1" !CDS_SEC = "1";
"A":   PN = "1"  !CDS_PN = "1";
"B":   PN = "2"  !CDS_PN = "2";
BODY = "RES","I155": #LOCATION = "R1D7" !CDS_LOCATION = "R1D7" #SEC = "1" !CDS_SEC = "1";
"A":   PN = "1"  !CDS_PN = "1";
"B":   PN = "2"  !CDS_PN = "2";
BODY = "CAP_A","I156": #LOCATION = "C1C8" !CDS_LOCATION = "C1C8" #SEC = "1" !CDS_SEC = "1";
"A":   PN = "1"  !CDS_PN = "1";
"B":   PN = "2"  !CDS_PN = "2";
DRAWING = "@baseboard_fab2_lib.baseboard_fab2(sch_1):page207";
BODY = "CAP_A","I8": #LOCATION = "C9R8" !CDS_LOCATION = "C9R8" #SEC = "1" !CDS_SEC = "1";
"A":   PN = "1"  !CDS_PN = "1";
"B":   PN = "2"  !CDS_PN = "2";
BODY = "CAP_A","I18": #LOCATION = "C1E3" !CDS_LOCATION = "C1E3" #SEC = "1" !CDS_SEC = "1";
"A":   PN = "1"  !CDS_PN = "1";
"B":   PN = "2"  !CDS_PN = "2";
BODY = "IR354XX","I20": #LOCATION = "EU1E2" !CDS_LOCATION = "EU1E2" #SEC = "1" !CDS_SEC = "1";
"BOOST":   PN = "33"  !CDS_PN = "33";
"EN":   PN = "35"  !CDS_PN = "35";
"GL<0>":   PN = "6"  !CDS_PN = "6";
"GL<1>":   PN = "41"  !CDS_PN = "41";
"IOUT":   PN = "38"  !CDS_PN = "38";
"LGND":   PN = "2"  !CDS_PN = "2";
"NC":   PN = "31"  !CDS_PN = "31";
"OCSET":   PN = "37"  !CDS_PN = "37";
"PGND<0>":   PN = "5"  !CDS_PN = "5";
"PGND<1>":   PN = "7"  !CDS_PN = "7";
"PGND<2>":   PN = "40"  !CDS_PN = "40";
"PHASE":   PN = "32"  !CDS_PN = "32";
"PWM":   PN = "34"  !CDS_PN = "34";
"REFIN":   PN = "39"  !CDS_PN = "39";
"SW":   PN = "10"  !CDS_PN = "10";
"TOUT_FLT":   PN = "36"  !CDS_PN = "36";
"VCC":   PN = "3"  !CDS_PN = "3";
"VDRV":   PN = "4"  !CDS_PN = "4";
"VIN<0>":   PN = "25"  !CDS_PN = "25";
"VIN<1>":   PN = "30"  !CDS_PN = "30";
"VOS":   PN = "1"  !CDS_PN = "1";
BODY = "CAP","I28": #LOCATION = "C1E7" !CDS_LOCATION = "C1E7" #SEC = "1" !CDS_SEC = "1";
"A":   PN = "1"  !CDS_PN = "1";
"B":   PN = "2"  !CDS_PN = "2";
BODY = "CAP","I30": #LOCATION = "C1E11" !CDS_LOCATION = "C1E11" #SEC = "1" !CDS_SEC = "1";
"A":   PN = "1"  !CDS_PN = "1";
"B":   PN = "2"  !CDS_PN = "2";
BODY = "CAP","I32": #LOCATION = "C1E8" !CDS_LOCATION = "C1E8" #SEC = "1" !CDS_SEC = "1";
"A":   PN = "1"  !CDS_PN = "1";
"B":   PN = "2"  !CDS_PN = "2";
BODY = "CAP_A","I33": #LOCATION = "C1E14" !CDS_LOCATION = "C1E14" #SEC = "1" !CDS_SEC = "1";
"A":   PN = "1"  !CDS_PN = "1";
"B":   PN = "2"  !CDS_PN = "2";
BODY = "CAP","I34": #LOCATION = "C1E13" !CDS_LOCATION = "C1E13" #SEC = "1" !CDS_SEC = "1";
"A":   PN = "1"  !CDS_PN = "1";
"B":   PN = "2"  !CDS_PN = "2";
BODY = "CAP","I36": #LOCATION = "C1E25" !CDS_LOCATION = "C1E25" #SEC = "1" !CDS_SEC = "1";
"A":   PN = "1"  !CDS_PN = "1";
"B":   PN = "2"  !CDS_PN = "2";
BODY = "CAP","I38": #LOCATION = "C1D36" !CDS_LOCATION = "C1D36" #SEC = "1" !CDS_SEC = "1";
"A":   PN = "1"  !CDS_PN = "1";
"B":   PN = "2"  !CDS_PN = "2";
BODY = "CAP","I40": #LOCATION = "C1E24" !CDS_LOCATION = "C1E24" #SEC = "1" !CDS_SEC = "1";
"A":   PN = "1"  !CDS_PN = "1";
"B":   PN = "2"  !CDS_PN = "2";
BODY = "CAP_A","I41": #LOCATION = "C1D34" !CDS_LOCATION = "C1D34" #SEC = "1" !CDS_SEC = "1";
"A":   PN = "1"  !CDS_PN = "1";
"B":   PN = "2"  !CDS_PN = "2";
BODY = "CAP","I42": #LOCATION = "C1D35" !CDS_LOCATION = "C1D35" #SEC = "1" !CDS_SEC = "1";
"A":   PN = "1"  !CDS_PN = "1";
"B":   PN = "2"  !CDS_PN = "2";
BODY = "CAP","I43": #LOCATION = "C9R7" !CDS_LOCATION = "C9R7" #SEC = "1" !CDS_SEC = "1";
"A":   PN = "1"  !CDS_PN = "1";
"B":   PN = "2"  !CDS_PN = "2";
BODY = "CAP","I44": #LOCATION = "C9R10" !CDS_LOCATION = "C9R10" #SEC = "1" !CDS_SEC = "1";
"A":   PN = "1"  !CDS_PN = "1";
"B":   PN = "2"  !CDS_PN = "2";
BODY = "CAP","I48": #LOCATION = "C9R11" !CDS_LOCATION = "C9R11" #SEC = "1" !CDS_SEC = "1";
"A":   PN = "1"  !CDS_PN = "1";
"B":   PN = "2"  !CDS_PN = "2";
BODY = "CAP","I50": #LOCATION = "C9P22" !CDS_LOCATION = "C9P22" #SEC = "1" !CDS_SEC = "1";
"A":   PN = "1"  !CDS_PN = "1";
"B":   PN = "2"  !CDS_PN = "2";
BODY = "CAP","I51": #LOCATION = "C9P25" !CDS_LOCATION = "C9P25" #SEC = "1" !CDS_SEC = "1";
"A":   PN = "1"  !CDS_PN = "1";
"B":   PN = "2"  !CDS_PN = "2";
BODY = "CAP","I54": #LOCATION = "C9P26" !CDS_LOCATION = "C9P26" #SEC = "1" !CDS_SEC = "1";
"A":   PN = "1"  !CDS_PN = "1";
"B":   PN = "2"  !CDS_PN = "2";
BODY = "CAP_A","I58": #LOCATION = "C1E9" !CDS_LOCATION = "C1E9" #SEC = "1" !CDS_SEC = "1";
"A":   PN = "1"  !CDS_PN = "1";
"B":   PN = "2"  !CDS_PN = "2";
BODY = "CAP_A","I59": #LOCATION = "C9P3" !CDS_LOCATION = "C9P3" #SEC = "1" !CDS_SEC = "1";
"A":   PN = "1"  !CDS_PN = "1";
"B":   PN = "2"  !CDS_PN = "2";
BODY = "RES","I67": #LOCATION = "R1E13" !CDS_LOCATION = "R1E13" &SEC = "1" #&CDS_SEC = "1";
"A":   PN = "1"  !CDS_PN = "1";
"B":   PN = "2"  !CDS_PN = "2";
BODY = "RES","I68": #LOCATION = "R1E14" !CDS_LOCATION = "R1E14" &SEC = "1" #&CDS_SEC = "1";
"A":   PN = "1"  !CDS_PN = "1";
"B":   PN = "2"  !CDS_PN = "2";
BODY = "CAP_A","I71": #LOCATION = "CT24" !CDS_LOCATION = "CT24" #SEC = "1" !CDS_SEC = "1";
"A":   PN = "1"  !CDS_PN = "1";
"B":   PN = "2"  !CDS_PN = "2";
BODY = "CAP","I74": #LOCATION = "CT22" !CDS_LOCATION = "CT22" #SEC = "1" !CDS_SEC = "1";
"A":   PN = "1"  !CDS_PN = "1";
"B":   PN = "2"  !CDS_PN = "2";
BODY = "CAP_A","I81": #LOCATION = "CT25" !CDS_LOCATION = "CT25" #SEC = "1" !CDS_SEC = "1";
"A":   PN = "1"  !CDS_PN = "1";
"B":   PN = "2"  !CDS_PN = "2";
BODY = "CAP","I82": #LOCATION = "CT26" !CDS_LOCATION = "CT26" #SEC = "1" !CDS_SEC = "1";
"A":   PN = "1"  !CDS_PN = "1";
"B":   PN = "2"  !CDS_PN = "2";
BODY = "CAP","I95": #LOCATION = "CT23" !CDS_LOCATION = "CT23" #SEC = "1" !CDS_SEC = "1";
"A":   PN = "1"  !CDS_PN = "1";
"B":   PN = "2"  !CDS_PN = "2";
BODY = "CAP","I96": #LOCATION = "CT27" !CDS_LOCATION = "CT27" #SEC = "1" !CDS_SEC = "1";
"A":   PN = "1"  !CDS_PN = "1";
"B":   PN = "2"  !CDS_PN = "2";
BODY = "RES","I99": #LOCATION = "RT15" !CDS_LOCATION = "RT15" #SEC = "1" !CDS_SEC = "1";
"A":   PN = "1"  !CDS_PN = "1";
"B":   PN = "2"  !CDS_PN = "2";
BODY = "RES","I100": #LOCATION = "RT17" !CDS_LOCATION = "RT17" #SEC = "1" !CDS_SEC = "1";
"A":   PN = "1"  !CDS_PN = "1";
"B":   PN = "2"  !CDS_PN = "2";
BODY = "RES","I105": #LOCATION = "R9R11" !CDS_LOCATION = "R9R11" #SEC = "1" !CDS_SEC = "1";
"A":   PN = "1"  !CDS_PN = "1";
"B":   PN = "2"  !CDS_PN = "2";
BODY = "RES","I106": #LOCATION = "R9R2" !CDS_LOCATION = "R9R2" #SEC = "1" !CDS_SEC = "1";
"A":   PN = "1"  !CDS_PN = "1";
"B":   PN = "2"  !CDS_PN = "2";
BODY = "IND-120NH-30-GP","I107": #LOCATION = "L1E1" !CDS_LOCATION = "L1E1" #SEC = "1" !CDS_SEC = "1";
"F":   PN = "2"  !CDS_PN = "2";
"S":   PN = "1"  !CDS_PN = "1";
BODY = "IND-120NH-30-GP","I108": #LOCATION = "L1D3" !CDS_LOCATION = "L1D3" #SEC = "1" !CDS_SEC = "1";
"F":   PN = "2"  !CDS_PN = "2";
"S":   PN = "1"  !CDS_PN = "1";
BODY = "SC1U10V2KX-4-GP","I109": #LOCATION = "C1E23" !CDS_LOCATION = "C1E23" #SEC = "1" !CDS_SEC = "1";
"1":   PN = "1"  !CDS_PN = "1";
"2":   PN = "2"  !CDS_PN = "2";
BODY = "SC1U10V2KX-4-GP","I110": #LOCATION = "C1E6" !CDS_LOCATION = "C1E6" #SEC = "1" !CDS_SEC = "1";
"1":   PN = "1"  !CDS_PN = "1";
"2":   PN = "2"  !CDS_PN = "2";
BODY = "1R3F-GP","I111": #LOCATION = "RT16" !CDS_LOCATION = "RT16" #SEC = "1" !CDS_SEC = "1";
"1":   PN = "1"  !CDS_PN = "1";
"2":   PN = "2"  !CDS_PN = "2";
BODY = "1R3F-GP","I112": #LOCATION = "RT18" !CDS_LOCATION = "RT18" #SEC = "1" !CDS_SEC = "1";
"1":   PN = "1"  !CDS_PN = "1";
"2":   PN = "2"  !CDS_PN = "2";
BODY = "IR354XX","I113": #LOCATION = "EU1D4" !CDS_LOCATION = "EU1D4" #SEC = "1" !CDS_SEC = "1";
"BOOST":   PN = "33"  !CDS_PN = "33";
"EN":   PN = "35"  !CDS_PN = "35";
"GL<0>":   PN = "6"  !CDS_PN = "6";
"GL<1>":   PN = "41"  !CDS_PN = "41";
"IOUT":   PN = "38"  !CDS_PN = "38";
"LGND":   PN = "2"  !CDS_PN = "2";
"NC":   PN = "31"  !CDS_PN = "31";
"OCSET":   PN = "37"  !CDS_PN = "37";
"PGND<0>":   PN = "5"  !CDS_PN = "5";
"PGND<1>":   PN = "7"  !CDS_PN = "7";
"PGND<2>":   PN = "40"  !CDS_PN = "40";
"PHASE":   PN = "32"  !CDS_PN = "32";
"PWM":   PN = "34"  !CDS_PN = "34";
"REFIN":   PN = "39"  !CDS_PN = "39";
"SW":   PN = "10"  !CDS_PN = "10";
"TOUT_FLT":   PN = "36"  !CDS_PN = "36";
"VCC":   PN = "3"  !CDS_PN = "3";
"VDRV":   PN = "4"  !CDS_PN = "4";
"VIN<0>":   PN = "25"  !CDS_PN = "25";
"VIN<1>":   PN = "30"  !CDS_PN = "30";
"VOS":   PN = "1"  !CDS_PN = "1";
DRAWING = "@baseboard_fab2_lib.baseboard_fab2(sch_1):page208";
BODY = "RES","I7": #LOCATION = "R1E3" !CDS_LOCATION = "R1E3" #SEC = "1" !CDS_SEC = "1";
"A":   PN = "1"  !CDS_PN = "1";
"B":   PN = "2"  !CDS_PN = "2";
BODY = "CAP_A","I9": #LOCATION = "C1D14" !CDS_LOCATION = "C1D14" #SEC = "1" !CDS_SEC = "1";
"A":   PN = "1"  !CDS_PN = "1";
"B":   PN = "2"  !CDS_PN = "2";
BODY = "CAPP","I12": #LOCATION = "C9P8" !CDS_LOCATION = "C9P8" #SEC = "1" !CDS_SEC = "1";
"A":   PN = "1"  !CDS_PN = "1";
"B":   PN = "2"  !CDS_PN = "2";
BODY = "CAPP","I14": #LOCATION = "C9P5" !CDS_LOCATION = "C9P5" #SEC = "1" !CDS_SEC = "1";
"A":   PN = "1"  !CDS_PN = "1";
"B":   PN = "2"  !CDS_PN = "2";
BODY = "CAP_A","I22": #LOCATION = "C1D3" !CDS_LOCATION = "C1D3" #SEC = "1" !CDS_SEC = "1";
"A":   PN = "1"  !CDS_PN = "1";
"B":   PN = "2"  !CDS_PN = "2";
BODY = "CAPP","I24": #LOCATION = "C9N24" !CDS_LOCATION = "C9N24" #SEC = "1" !CDS_SEC = "1";
"A":   PN = "1"  !CDS_PN = "1";
"B":   PN = "2"  !CDS_PN = "2";
BODY = "CAPP","I25": #LOCATION = "C9R9" !CDS_LOCATION = "C9R9" #SEC = "1" !CDS_SEC = "1";
"A":   PN = "1"  !CDS_PN = "1";
"B":   PN = "2"  !CDS_PN = "2";
BODY = "CAPP","I26": #LOCATION = "C9R3" !CDS_LOCATION = "C9R3" #SEC = "1" !CDS_SEC = "1";
"A":   PN = "1"  !CDS_PN = "1";
"B":   PN = "2"  !CDS_PN = "2";
BODY = "IR354XX","I27": #LOCATION = "EU1D3" !CDS_LOCATION = "EU1D3" #SEC = "1" !CDS_SEC = "1";
"BOOST":   PN = "33"  !CDS_PN = "33";
"EN":   PN = "35"  !CDS_PN = "35";
"GL<0>":   PN = "6"  !CDS_PN = "6";
"GL<1>":   PN = "41"  !CDS_PN = "41";
"IOUT":   PN = "38"  !CDS_PN = "38";
"LGND":   PN = "2"  !CDS_PN = "2";
"NC":   PN = "31"  !CDS_PN = "31";
"OCSET":   PN = "37"  !CDS_PN = "37";
"PGND<0>":   PN = "5"  !CDS_PN = "5";
"PGND<1>":   PN = "7"  !CDS_PN = "7";
"PGND<2>":   PN = "40"  !CDS_PN = "40";
"PHASE":   PN = "32"  !CDS_PN = "32";
"PWM":   PN = "34"  !CDS_PN = "34";
"REFIN":   PN = "39"  !CDS_PN = "39";
"SW":   PN = "10"  !CDS_PN = "10";
"TOUT_FLT":   PN = "36"  !CDS_PN = "36";
"VCC":   PN = "3"  !CDS_PN = "3";
"VDRV":   PN = "4"  !CDS_PN = "4";
"VIN<0>":   PN = "25"  !CDS_PN = "25";
"VIN<1>":   PN = "30"  !CDS_PN = "30";
"VOS":   PN = "1"  !CDS_PN = "1";
BODY = "CAPP","I28": #LOCATION = "C9P23" !CDS_LOCATION = "C9P23" #SEC = "1" !CDS_SEC = "1";
"A":   PN = "1"  !CDS_PN = "1";
"B":   PN = "2"  !CDS_PN = "2";
BODY = "CAPP","I30": #LOCATION = "C9P18" !CDS_LOCATION = "C9P18" #SEC = "1" !CDS_SEC = "1";
"A":   PN = "1"  !CDS_PN = "1";
"B":   PN = "2"  !CDS_PN = "2";
BODY = "CAP","I38": #LOCATION = "C1D16" !CDS_LOCATION = "C1D16" #SEC = "1" !CDS_SEC = "1";
"A":   PN = "1"  !CDS_PN = "1";
"B":   PN = "2"  !CDS_PN = "2";
BODY = "CAP","I40": #LOCATION = "C1D20" !CDS_LOCATION = "C1D20" #SEC = "1" !CDS_SEC = "1";
"A":   PN = "1"  !CDS_PN = "1";
"B":   PN = "2"  !CDS_PN = "2";
BODY = "CAP","I43": #LOCATION = "C1D17" !CDS_LOCATION = "C1D17" #SEC = "1" !CDS_SEC = "1";
"A":   PN = "1"  !CDS_PN = "1";
"B":   PN = "2"  !CDS_PN = "2";
BODY = "CAP_A","I44": #LOCATION = "C1D28" !CDS_LOCATION = "C1D28" #SEC = "1" !CDS_SEC = "1";
"A":   PN = "1"  !CDS_PN = "1";
"B":   PN = "2"  !CDS_PN = "2";
BODY = "CAP","I45": #LOCATION = "C1D23" !CDS_LOCATION = "C1D23" #SEC = "1" !CDS_SEC = "1";
"A":   PN = "1"  !CDS_PN = "1";
"B":   PN = "2"  !CDS_PN = "2";
BODY = "CAP","I46": #LOCATION = "C1D6" !CDS_LOCATION = "C1D6" #SEC = "1" !CDS_SEC = "1";
"A":   PN = "1"  !CDS_PN = "1";
"B":   PN = "2"  !CDS_PN = "2";
BODY = "CAP","I48": #LOCATION = "C1D10" !CDS_LOCATION = "C1D10" #SEC = "1" !CDS_SEC = "1";
"A":   PN = "1"  !CDS_PN = "1";
"B":   PN = "2"  !CDS_PN = "2";
BODY = "CAP","I50": #LOCATION = "C1D7" !CDS_LOCATION = "C1D7" #SEC = "1" !CDS_SEC = "1";
"A":   PN = "1"  !CDS_PN = "1";
"B":   PN = "2"  !CDS_PN = "2";
BODY = "CAP_A","I51": #LOCATION = "C1D13" !CDS_LOCATION = "C1D13" #SEC = "1" !CDS_SEC = "1";
"A":   PN = "1"  !CDS_PN = "1";
"B":   PN = "2"  !CDS_PN = "2";
BODY = "CAP","I52": #LOCATION = "C1D12" !CDS_LOCATION = "C1D12" #SEC = "1" !CDS_SEC = "1";
"A":   PN = "1"  !CDS_PN = "1";
"B":   PN = "2"  !CDS_PN = "2";
BODY = "CAP","I53": #LOCATION = "C9P4" !CDS_LOCATION = "C9P4" #SEC = "1" !CDS_SEC = "1";
"A":   PN = "1"  !CDS_PN = "1";
"B":   PN = "2"  !CDS_PN = "2";
BODY = "CAP","I54": #LOCATION = "C9P7" !CDS_LOCATION = "C9P7" #SEC = "1" !CDS_SEC = "1";
"A":   PN = "1"  !CDS_PN = "1";
"B":   PN = "2"  !CDS_PN = "2";
BODY = "CAP","I55": #LOCATION = "C9P9" !CDS_LOCATION = "C9P9" #SEC = "1" !CDS_SEC = "1";
"A":   PN = "1"  !CDS_PN = "1";
"B":   PN = "2"  !CDS_PN = "2";
BODY = "CAP","I58": #LOCATION = "C9P24" !CDS_LOCATION = "C9P24" #SEC = "1" !CDS_SEC = "1";
"A":   PN = "1"  !CDS_PN = "1";
"B":   PN = "2"  !CDS_PN = "2";
BODY = "CAP","I59": #LOCATION = "C9P1" !CDS_LOCATION = "C9P1" #SEC = "1" !CDS_SEC = "1";
"A":   PN = "1"  !CDS_PN = "1";
"B":   PN = "2"  !CDS_PN = "2";
BODY = "CAP","I60": #LOCATION = "C9P2" !CDS_LOCATION = "C9P2" #SEC = "1" !CDS_SEC = "1";
"A":   PN = "1"  !CDS_PN = "1";
"B":   PN = "2"  !CDS_PN = "2";
BODY = "CAP_A","I66": #LOCATION = "C9P10" !CDS_LOCATION = "C9P10" #SEC = "1" !CDS_SEC = "1";
"A":   PN = "1"  !CDS_PN = "1";
"B":   PN = "2"  !CDS_PN = "2";
BODY = "CAP_A","I67": #LOCATION = "C9R2" !CDS_LOCATION = "C9R2" #SEC = "1" !CDS_SEC = "1";
"A":   PN = "1"  !CDS_PN = "1";
"B":   PN = "2"  !CDS_PN = "2";
BODY = "IR354XX","I71": #LOCATION = "EU1D1" !CDS_LOCATION = "EU1D1" #SEC = "1" !CDS_SEC = "1";
"BOOST":   PN = "33"  !CDS_PN = "33";
"EN":   PN = "35"  !CDS_PN = "35";
"GL<0>":   PN = "6"  !CDS_PN = "6";
"GL<1>":   PN = "41"  !CDS_PN = "41";
"IOUT":   PN = "38"  !CDS_PN = "38";
"LGND":   PN = "2"  !CDS_PN = "2";
"NC":   PN = "31"  !CDS_PN = "31";
"OCSET":   PN = "37"  !CDS_PN = "37";
"PGND<0>":   PN = "5"  !CDS_PN = "5";
"PGND<1>":   PN = "7"  !CDS_PN = "7";
"PGND<2>":   PN = "40"  !CDS_PN = "40";
"PHASE":   PN = "32"  !CDS_PN = "32";
"PWM":   PN = "34"  !CDS_PN = "34";
"REFIN":   PN = "39"  !CDS_PN = "39";
"SW":   PN = "10"  !CDS_PN = "10";
"TOUT_FLT":   PN = "36"  !CDS_PN = "36";
"VCC":   PN = "3"  !CDS_PN = "3";
"VDRV":   PN = "4"  !CDS_PN = "4";
"VIN<0>":   PN = "25"  !CDS_PN = "25";
"VIN<1>":   PN = "30"  !CDS_PN = "30";
"VOS":   PN = "1"  !CDS_PN = "1";
BODY = "RES","I75": #LOCATION = "R1D54" !CDS_LOCATION = "R1D54" &SEC = "1" #&CDS_SEC = "1";
"A":   PN = "1"  !CDS_PN = "1";
"B":   PN = "2"  !CDS_PN = "2";
BODY = "RES","I76": #LOCATION = "R1D55" !CDS_LOCATION = "R1D55" &SEC = "1" #&CDS_SEC = "1";
"A":   PN = "1"  !CDS_PN = "1";
"B":   PN = "2"  !CDS_PN = "2";
BODY = "CAP_A","I80": #LOCATION = "CT16" !CDS_LOCATION = "CT16" #SEC = "1" !CDS_SEC = "1";
"A":   PN = "1"  !CDS_PN = "1";
"B":   PN = "2"  !CDS_PN = "2";
BODY = "CAP","I82": #LOCATION = "CTI7" !CDS_LOCATION = "CTI7" #SEC = "1" !CDS_SEC = "1";
"A":   PN = "1"  !CDS_PN = "1";
"B":   PN = "2"  !CDS_PN = "2";
BODY = "CAP_A","I87": #LOCATION = "CT21" !CDS_LOCATION = "CT21" #SEC = "1" !CDS_SEC = "1";
"A":   PN = "1"  !CDS_PN = "1";
"B":   PN = "2"  !CDS_PN = "2";
BODY = "CAP","I90": #LOCATION = "CT19" !CDS_LOCATION = "CT19" #SEC = "1" !CDS_SEC = "1";
"A":   PN = "1"  !CDS_PN = "1";
"B":   PN = "2"  !CDS_PN = "2";
BODY = "CAP","I104": #LOCATION = "CT18" !CDS_LOCATION = "CT18" #SEC = "1" !CDS_SEC = "1";
"A":   PN = "1"  !CDS_PN = "1";
"B":   PN = "2"  !CDS_PN = "2";
BODY = "CAP","I105": #LOCATION = "CT20" !CDS_LOCATION = "CT20" #SEC = "1" !CDS_SEC = "1";
"A":   PN = "1"  !CDS_PN = "1";
"B":   PN = "2"  !CDS_PN = "2";
BODY = "RES","I108": #LOCATION = "RT11" !CDS_LOCATION = "RT11" #SEC = "1" !CDS_SEC = "1";
"A":   PN = "1"  !CDS_PN = "1";
"B":   PN = "2"  !CDS_PN = "2";
BODY = "RES","I109": #LOCATION = "RT14" !CDS_LOCATION = "RT14" #SEC = "1" !CDS_SEC = "1";
"A":   PN = "1"  !CDS_PN = "1";
"B":   PN = "2"  !CDS_PN = "2";
BODY = "RES","I114": #LOCATION = "R9P22" !CDS_LOCATION = "R9P22" #SEC = "1" !CDS_SEC = "1";
"A":   PN = "1"  !CDS_PN = "1";
"B":   PN = "2"  !CDS_PN = "2";
BODY = "RES","I115": #LOCATION = "R9P8" !CDS_LOCATION = "R9P8" #SEC = "1" !CDS_SEC = "1";
"A":   PN = "1"  !CDS_PN = "1";
"B":   PN = "2"  !CDS_PN = "2";
BODY = "IND-120NH-30-GP","I116": #LOCATION = "L1D2" !CDS_LOCATION = "L1D2" #SEC = "1" !CDS_SEC = "1";
"F":   PN = "2"  !CDS_PN = "2";
"S":   PN = "1"  !CDS_PN = "1";
BODY = "IND-120NH-30-GP","I117": #LOCATION = "L1D1" !CDS_LOCATION = "L1D1" #SEC = "1" !CDS_SEC = "1";
"F":   PN = "2"  !CDS_PN = "2";
"S":   PN = "1"  !CDS_PN = "1";
BODY = "SC1U10V2KX-4-GP","I118": #LOCATION = "C1D15" !CDS_LOCATION = "C1D15" #SEC = "1" !CDS_SEC = "1";
"1":   PN = "1"  !CDS_PN = "1";
"2":   PN = "2"  !CDS_PN = "2";
BODY = "SC1U10V2KX-4-GP","I119": #LOCATION = "C1D5" !CDS_LOCATION = "C1D5" #SEC = "1" !CDS_SEC = "1";
"1":   PN = "1"  !CDS_PN = "1";
"2":   PN = "2"  !CDS_PN = "2";
BODY = "1R3F-GP","I120": #LOCATION = "RT12" !CDS_LOCATION = "RT12" #SEC = "1" !CDS_SEC = "1";
"1":   PN = "1"  !CDS_PN = "1";
"2":   PN = "2"  !CDS_PN = "2";
BODY = "1R3F-GP","I121": #LOCATION = "RT13" !CDS_LOCATION = "RT13" #SEC = "1" !CDS_SEC = "1";
"1":   PN = "1"  !CDS_PN = "1";
"2":   PN = "2"  !CDS_PN = "2";
DRAWING = "@baseboard_fab2_lib.baseboard_fab2(sch_1):page209";
BODY = "RES","I3": #LOCATION = "R1E5" !CDS_LOCATION = "R1E5" &SEC = "1" #&CDS_SEC = "1";
"A":   PN = "1"  !CDS_PN = "1";
"B":   PN = "2"  !CDS_PN = "2";
BODY = "CAP","I5": #LOCATION = "C9N27" !CDS_LOCATION = "C9N27" #SEC = "1" !CDS_SEC = "1";
"A":   PN = "1"  !CDS_PN = "1";
"B":   PN = "2"  !CDS_PN = "2";
BODY = "CAP","I7": #LOCATION = "C9N26" !CDS_LOCATION = "C9N26" #SEC = "1" !CDS_SEC = "1";
"A":   PN = "1"  !CDS_PN = "1";
"B":   PN = "2"  !CDS_PN = "2";
BODY = "CAP","I8": #LOCATION = "C9N25" !CDS_LOCATION = "C9N25" #SEC = "1" !CDS_SEC = "1";
"A":   PN = "1"  !CDS_PN = "1";
"B":   PN = "2"  !CDS_PN = "2";
BODY = "RES","I9": #LOCATION = "R1E8" !CDS_LOCATION = "R1E8" &SEC = "1" #&CDS_SEC = "1";
"A":   PN = "1"  !CDS_PN = "1";
"B":   PN = "2"  !CDS_PN = "2";
BODY = "RES","I10": #LOCATION = "R1E7" !CDS_LOCATION = "R1E7" &SEC = "1" #&CDS_SEC = "1";
"A":   PN = "1"  !CDS_PN = "1";
"B":   PN = "2"  !CDS_PN = "2";
BODY = "RES","I11": #LOCATION = "R1E6" !CDS_LOCATION = "R1E6" &SEC = "1" #&CDS_SEC = "1";
"A":   PN = "1"  !CDS_PN = "1";
"B":   PN = "2"  !CDS_PN = "2";
BODY = "RES","I15": #LOCATION = "R1E4" !CDS_LOCATION = "R1E4" &SEC = "1" #&CDS_SEC = "1";
"A":   PN = "1"  !CDS_PN = "1";
"B":   PN = "2"  !CDS_PN = "2";
BODY = "CAP","I16": #LOCATION = "C1C26" !CDS_LOCATION = "C1C26" #SEC = "1" !CDS_SEC = "1";
"A":   PN = "1"  !CDS_PN = "1";
"B":   PN = "2"  !CDS_PN = "2";
BODY = "CAP_A","I17": #LOCATION = "C1C25" !CDS_LOCATION = "C1C25" #SEC = "1" !CDS_SEC = "1";
"A":   PN = "1"  !CDS_PN = "1";
"B":   PN = "2"  !CDS_PN = "2";
BODY = "CAP","I18": #LOCATION = "C1D32" !CDS_LOCATION = "C1D32" #SEC = "1" !CDS_SEC = "1";
"A":   PN = "1"  !CDS_PN = "1";
"B":   PN = "2"  !CDS_PN = "2";
BODY = "CAP","I20": #LOCATION = "C1C24" !CDS_LOCATION = "C1C24" #SEC = "1" !CDS_SEC = "1";
"A":   PN = "1"  !CDS_PN = "1";
"B":   PN = "2"  !CDS_PN = "2";
BODY = "CAP","I22": #LOCATION = "C1D33" !CDS_LOCATION = "C1D33" #SEC = "1" !CDS_SEC = "1";
"A":   PN = "1"  !CDS_PN = "1";
"B":   PN = "2"  !CDS_PN = "2";
BODY = "CAPP","I35": #LOCATION = "C1C1" !CDS_LOCATION = "C1C1" #SEC = "1" !CDS_SEC = "1";
"A":   PN = "1"  !CDS_PN = "1";
"B":   PN = "2"  !CDS_PN = "2";
BODY = "CAPP","I37": #LOCATION = "C1E18" !CDS_LOCATION = "C1E18" #SEC = "1" !CDS_SEC = "1";
"A":   PN = "1"  !CDS_PN = "1";
"B":   PN = "2"  !CDS_PN = "2";
BODY = "CAPP","I38": #LOCATION = "C1C2" !CDS_LOCATION = "C1C2" #SEC = "1" !CDS_SEC = "1";
"A":   PN = "1"  !CDS_PN = "1";
"B":   PN = "2"  !CDS_PN = "2";
BODY = "CAP_A","I42": #LOCATION = "C1D24" !CDS_LOCATION = "C1D24" #SEC = "1" !CDS_SEC = "1";
"A":   PN = "1"  !CDS_PN = "1";
"B":   PN = "2"  !CDS_PN = "2";
BODY = "CAP_A","I55": #LOCATION = "C9P20" !CDS_LOCATION = "C9P20" #SEC = "1" !CDS_SEC = "1";
"A":   PN = "1"  !CDS_PN = "1";
"B":   PN = "2"  !CDS_PN = "2";
BODY = "IR354XX","I56": #LOCATION = "EU1C3" !CDS_LOCATION = "EU1C3" #SEC = "1" !CDS_SEC = "1";
"BOOST":   PN = "33"  !CDS_PN = "33";
"EN":   PN = "35"  !CDS_PN = "35";
"GL<0>":   PN = "6"  !CDS_PN = "6";
"GL<1>":   PN = "41"  !CDS_PN = "41";
"IOUT":   PN = "38"  !CDS_PN = "38";
"LGND":   PN = "2"  !CDS_PN = "2";
"NC":   PN = "31"  !CDS_PN = "31";
"OCSET":   PN = "37"  !CDS_PN = "37";
"PGND<0>":   PN = "5"  !CDS_PN = "5";
"PGND<1>":   PN = "7"  !CDS_PN = "7";
"PGND<2>":   PN = "40"  !CDS_PN = "40";
"PHASE":   PN = "32"  !CDS_PN = "32";
"PWM":   PN = "34"  !CDS_PN = "34";
"REFIN":   PN = "39"  !CDS_PN = "39";
"SW":   PN = "10"  !CDS_PN = "10";
"TOUT_FLT":   PN = "36"  !CDS_PN = "36";
"VCC":   PN = "3"  !CDS_PN = "3";
"VDRV":   PN = "4"  !CDS_PN = "4";
"VIN<0>":   PN = "25"  !CDS_PN = "25";
"VIN<1>":   PN = "30"  !CDS_PN = "30";
"VOS":   PN = "1"  !CDS_PN = "1";
BODY = "RES","I59": #LOCATION = "R1D52" !CDS_LOCATION = "R1D52" &SEC = "1" #&CDS_SEC = "1";
"A":   PN = "1"  !CDS_PN = "1";
"B":   PN = "2"  !CDS_PN = "2";
BODY = "CAP_A","I62": #LOCATION = "CT13" !CDS_LOCATION = "CT13" #SEC = "1" !CDS_SEC = "1";
"A":   PN = "1"  !CDS_PN = "1";
"B":   PN = "2"  !CDS_PN = "2";
BODY = "CAP","I67": #LOCATION = "CT15" !CDS_LOCATION = "CT15" #SEC = "1" !CDS_SEC = "1";
"A":   PN = "1"  !CDS_PN = "1";
"B":   PN = "2"  !CDS_PN = "2";
BODY = "CAP","I73": #LOCATION = "CT14" !CDS_LOCATION = "CT14" #SEC = "1" !CDS_SEC = "1";
"A":   PN = "1"  !CDS_PN = "1";
"B":   PN = "2"  !CDS_PN = "2";
BODY = "RES","I75": #LOCATION = "RT9" !CDS_LOCATION = "RT9" #SEC = "1" !CDS_SEC = "1";
"A":   PN = "1"  !CDS_PN = "1";
"B":   PN = "2"  !CDS_PN = "2";
BODY = "RES","I79": #LOCATION = "R9P32" !CDS_LOCATION = "R9P32" #SEC = "1" !CDS_SEC = "1";
"A":   PN = "1"  !CDS_PN = "1";
"B":   PN = "2"  !CDS_PN = "2";
BODY = "IND-120NH-30-GP","I80": #LOCATION = "L1C2" !CDS_LOCATION = "L1C2" #SEC = "1" !CDS_SEC = "1";
"F":   PN = "2"  !CDS_PN = "2";
"S":   PN = "1"  !CDS_PN = "1";
BODY = "IND-80NH-1-GP","I81": #LOCATION = "L1B2" !CDS_LOCATION = "L1B2" #SEC = "1" !CDS_SEC = "1";
"F":   PN = "2"  !CDS_PN = "2";
"S":   PN = "1"  !CDS_PN = "1";
BODY = "SC1U10V2KX-4-GP","I89": #LOCATION = "C1C18" !CDS_LOCATION = "C1C18" #SEC = "1" !CDS_SEC = "1";
"1":   PN = "1"  !CDS_PN = "1";
"2":   PN = "2"  !CDS_PN = "2";
BODY = "1R3F-GP","I90": #LOCATION = "RT10" !CDS_LOCATION = "RT10" #SEC = "1" !CDS_SEC = "1";
"1":   PN = "1"  !CDS_PN = "1";
"2":   PN = "2"  !CDS_PN = "2";
DRAWING = "@baseboard_fab2_lib.baseboard_fab2(sch_1):page210";
BODY = "CAP_A","I8": #LOCATION = "C1C19" !CDS_LOCATION = "C1C19" #SEC = "1" !CDS_SEC = "1";
"A":   PN = "1"  !CDS_PN = "1";
"B":   PN = "2"  !CDS_PN = "2";
BODY = "CAPP","I12": #LOCATION = "C9N11" !CDS_LOCATION = "C9N11" #SEC = "1" !CDS_SEC = "1";
"A":   PN = "1"  !CDS_PN = "1";
"B":   PN = "2"  !CDS_PN = "2";
BODY = "CAPP","I14": #LOCATION = "C9N20" !CDS_LOCATION = "C9N20" #SEC = "1" !CDS_SEC = "1";
"A":   PN = "1"  !CDS_PN = "1";
"B":   PN = "2"  !CDS_PN = "2";
BODY = "CAP","I22": #LOCATION = "C1C4" !CDS_LOCATION = "C1C4" #SEC = "1" !CDS_SEC = "1";
"A":   PN = "1"  !CDS_PN = "1";
"B":   PN = "2"  !CDS_PN = "2";
BODY = "CAP","I24": #LOCATION = "C1C12" !CDS_LOCATION = "C1C12" #SEC = "1" !CDS_SEC = "1";
"A":   PN = "1"  !CDS_PN = "1";
"B":   PN = "2"  !CDS_PN = "2";
BODY = "CAP","I26": #LOCATION = "C1C5" !CDS_LOCATION = "C1C5" #SEC = "1" !CDS_SEC = "1";
"A":   PN = "1"  !CDS_PN = "1";
"B":   PN = "2"  !CDS_PN = "2";
BODY = "CAP_A","I27": #LOCATION = "C1C17" !CDS_LOCATION = "C1C17" #SEC = "1" !CDS_SEC = "1";
"A":   PN = "1"  !CDS_PN = "1";
"B":   PN = "2"  !CDS_PN = "2";
BODY = "CAP","I28": #LOCATION = "C1C15" !CDS_LOCATION = "C1C15" #SEC = "1" !CDS_SEC = "1";
"A":   PN = "1"  !CDS_PN = "1";
"B":   PN = "2"  !CDS_PN = "2";
BODY = "RES","I29": #LOCATION = "R1C12" !CDS_LOCATION = "R1C12" #SEC = "1" !CDS_SEC = "1";
"A":   PN = "1"  !CDS_PN = "1";
"B":   PN = "2"  !CDS_PN = "2";
BODY = "RES","I31": #LOCATION = "R1C7" !CDS_LOCATION = "R1C7" #SEC = "1" !CDS_SEC = "1";
"A":   PN = "1"  !CDS_PN = "1";
"B":   PN = "2"  !CDS_PN = "2";
BODY = "RES","I32": #LOCATION = "R1C5" !CDS_LOCATION = "R1C5" #SEC = "1" !CDS_SEC = "1";
"A":   PN = "1"  !CDS_PN = "1";
"B":   PN = "2"  !CDS_PN = "2";
BODY = "RES","I33": #LOCATION = "R1C4" !CDS_LOCATION = "R1C4" #SEC = "1" !CDS_SEC = "1";
"A":   PN = "1"  !CDS_PN = "1";
"B":   PN = "2"  !CDS_PN = "2";
BODY = "RES","I34": #LOCATION = "R1C6" !CDS_LOCATION = "R1C6" #SEC = "1" !CDS_SEC = "1";
"A":   PN = "1"  !CDS_PN = "1";
"B":   PN = "2"  !CDS_PN = "2";
BODY = "CAP","I35": #LOCATION = "C9N13" !CDS_LOCATION = "C9N13" #SEC = "1" !CDS_SEC = "1";
"A":   PN = "1"  !CDS_PN = "1";
"B":   PN = "2"  !CDS_PN = "2";
BODY = "CAP","I36": #LOCATION = "C9N19" !CDS_LOCATION = "C9N19" #SEC = "1" !CDS_SEC = "1";
"A":   PN = "1"  !CDS_PN = "1";
"B":   PN = "2"  !CDS_PN = "2";
BODY = "CAP","I38": #LOCATION = "C9N21" !CDS_LOCATION = "C9N21" #SEC = "1" !CDS_SEC = "1";
"A":   PN = "1"  !CDS_PN = "1";
"B":   PN = "2"  !CDS_PN = "2";
BODY = "CAP_A","I44": #LOCATION = "C9N22" !CDS_LOCATION = "C9N22" #SEC = "1" !CDS_SEC = "1";
"A":   PN = "1"  !CDS_PN = "1";
"B":   PN = "2"  !CDS_PN = "2";
BODY = "RES","I45": #LOCATION = "R9N4" !CDS_LOCATION = "R9N4" #SEC = "1" !CDS_SEC = "1";
"A":   PN = "1"  !CDS_PN = "1";
"B":   PN = "2"  !CDS_PN = "2";
BODY = "IR354XX","I51": #LOCATION = "EU1C1" !CDS_LOCATION = "EU1C1" #SEC = "1" !CDS_SEC = "1";
"BOOST":   PN = "33"  !CDS_PN = "33";
"EN":   PN = "35"  !CDS_PN = "35";
"GL<0>":   PN = "6"  !CDS_PN = "6";
"GL<1>":   PN = "41"  !CDS_PN = "41";
"IOUT":   PN = "38"  !CDS_PN = "38";
"LGND":   PN = "2"  !CDS_PN = "2";
"NC":   PN = "31"  !CDS_PN = "31";
"OCSET":   PN = "37"  !CDS_PN = "37";
"PGND<0>":   PN = "5"  !CDS_PN = "5";
"PGND<1>":   PN = "7"  !CDS_PN = "7";
"PGND<2>":   PN = "40"  !CDS_PN = "40";
"PHASE":   PN = "32"  !CDS_PN = "32";
"PWM":   PN = "34"  !CDS_PN = "34";
"REFIN":   PN = "39"  !CDS_PN = "39";
"SW":   PN = "10"  !CDS_PN = "10";
"TOUT_FLT":   PN = "36"  !CDS_PN = "36";
"VCC":   PN = "3"  !CDS_PN = "3";
"VDRV":   PN = "4"  !CDS_PN = "4";
"VIN<0>":   PN = "25"  !CDS_PN = "25";
"VIN<1>":   PN = "30"  !CDS_PN = "30";
"VOS":   PN = "1"  !CDS_PN = "1";
BODY = "RES","I52": #LOCATION = "R1C37" !CDS_LOCATION = "R1C37" &SEC = "1" #&CDS_SEC = "1";
"A":   PN = "1"  !CDS_PN = "1";
"B":   PN = "2"  !CDS_PN = "2";
BODY = "CAP_A","I55": #LOCATION = "CT57" !CDS_LOCATION = "CT57" #SEC = "1" !CDS_SEC = "1";
"A":   PN = "1"  !CDS_PN = "1";
"B":   PN = "2"  !CDS_PN = "2";
BODY = "CAP","I60": #LOCATION = "CT55" !CDS_LOCATION = "CT55" #SEC = "1" !CDS_SEC = "1";
"A":   PN = "1"  !CDS_PN = "1";
"B":   PN = "2"  !CDS_PN = "2";
BODY = "CAP","I66": #LOCATION = "CT56" !CDS_LOCATION = "CT56" #SEC = "1" !CDS_SEC = "1";
"A":   PN = "1"  !CDS_PN = "1";
"B":   PN = "2"  !CDS_PN = "2";
BODY = "RES","I68": #LOCATION = "RT37" !CDS_LOCATION = "RT37" #SEC = "1" !CDS_SEC = "1";
"A":   PN = "1"  !CDS_PN = "1";
"B":   PN = "2"  !CDS_PN = "2";
BODY = "RES","I71": #LOCATION = "R9N3" !CDS_LOCATION = "R9N3" #SEC = "1" !CDS_SEC = "1";
"A":   PN = "1"  !CDS_PN = "1";
"B":   PN = "2"  !CDS_PN = "2";
BODY = "IND-300NH-20-GP","I72": #LOCATION = "L1C1" !CDS_LOCATION = "L1C1" #SEC = "1" !CDS_SEC = "1";
"F":   PN = "2"  !CDS_PN = "2";
"S":   PN = "1"  !CDS_PN = "1";
BODY = "SC1U10V2KX-4-GP","I73": #LOCATION = "C1C3" !CDS_LOCATION = "C1C3" #SEC = "1" !CDS_SEC = "1";
"1":   PN = "1"  !CDS_PN = "1";
"2":   PN = "2"  !CDS_PN = "2";
BODY = "1R3F-GP","I74": #LOCATION = "RT38" !CDS_LOCATION = "RT38" #SEC = "1" !CDS_SEC = "1";
"1":   PN = "1"  !CDS_PN = "1";
"2":   PN = "2"  !CDS_PN = "2";
DRAWING = "@baseboard_fab2_lib.baseboard_fab2(sch_1):page211";
BODY = "CAP_A","I11": #LOCATION = "C3P4" !CDS_LOCATION = "C3P4" #SEC = "1" !CDS_SEC = "1";
"A":   PN = "1"  !CDS_PN = "1";
"B":   PN = "2"  !CDS_PN = "2";
BODY = "CAP_A","I13": #LOCATION = "C3P5" !CDS_LOCATION = "C3P5" #SEC = "1" !CDS_SEC = "1";
"A":   PN = "1"  !CDS_PN = "1";
"B":   PN = "2"  !CDS_PN = "2";
BODY = "RES","I16": #LOCATION = "R3P11" !CDS_LOCATION = "R3P11" #SEC = "1" !CDS_SEC = "1";
"A":   PN = "1"  !CDS_PN = "1";
"B":   PN = "2"  !CDS_PN = "2";
BODY = "CAP_A","I20": #LOCATION = "C3P3" !CDS_LOCATION = "C3P3" #SEC = "1" !CDS_SEC = "1";
"A":   PN = "1"  !CDS_PN = "1";
"B":   PN = "2"  !CDS_PN = "2";
BODY = "CAP_A","I22": #LOCATION = "C3P7" !CDS_LOCATION = "C3P7" #SEC = "1" !CDS_SEC = "1";
"A":   PN = "1"  !CDS_PN = "1";
"B":   PN = "2"  !CDS_PN = "2";
BODY = "RES","I24": #LOCATION = "R3P22" !CDS_LOCATION = "R3P22" #SEC = "1" !CDS_SEC = "1";
"A":   PN = "1"  !CDS_PN = "1";
"B":   PN = "2"  !CDS_PN = "2";
BODY = "RES","I29": #LOCATION = "R3P15" !CDS_LOCATION = "R3P15" #SEC = "1" !CDS_SEC = "1";
"A":   PN = "1"  !CDS_PN = "1";
"B":   PN = "2"  !CDS_PN = "2";
BODY = "RES","I31": #LOCATION = "R3P12" !CDS_LOCATION = "R3P12" #SEC = "1" !CDS_SEC = "1";
"A":   PN = "1"  !CDS_PN = "1";
"B":   PN = "2"  !CDS_PN = "2";
BODY = "RES","I32": #LOCATION = "R3P16" !CDS_LOCATION = "R3P16" #SEC = "1" !CDS_SEC = "1";
"A":   PN = "1"  !CDS_PN = "1";
"B":   PN = "2"  !CDS_PN = "2";
BODY = "RES","I52": #LOCATION = "R3N31" !CDS_LOCATION = "R3N31" #SEC = "1" !CDS_SEC = "1";
"A":   PN = "1"  !CDS_PN = "1";
"B":   PN = "2"  !CDS_PN = "2";
BODY = "RES","I56": #LOCATION = "R3P25" !CDS_LOCATION = "R3P25" #SEC = "1" !CDS_SEC = "1";
"A":   PN = "1"  !CDS_PN = "1";
"B":   PN = "2"  !CDS_PN = "2";
BODY = "RES","I58": #LOCATION = "R3P20" !CDS_LOCATION = "R3P20" #SEC = "1" !CDS_SEC = "1";
"A":   PN = "1"  !CDS_PN = "1";
"B":   PN = "2"  !CDS_PN = "2";
BODY = "RES","I60": #LOCATION = "R3N23" !CDS_LOCATION = "R3N23" #SEC = "1" !CDS_SEC = "1";
"A":   PN = "1"  !CDS_PN = "1";
"B":   PN = "2"  !CDS_PN = "2";
BODY = "RES","I61": #LOCATION = "R3P1" !CDS_LOCATION = "R3P1" #SEC = "1" !CDS_SEC = "1";
"A":   PN = "1"  !CDS_PN = "1";
"B":   PN = "2"  !CDS_PN = "2";
BODY = "RES","I64": #LOCATION = "R3P18" !CDS_LOCATION = "R3P18" #SEC = "1" !CDS_SEC = "1";
"A":   PN = "1"  !CDS_PN = "1";
"B":   PN = "2"  !CDS_PN = "2";
BODY = "CAP","I71": #LOCATION = "C3P6" !CDS_LOCATION = "C3P6" #SEC = "1" !CDS_SEC = "1";
"A":   PN = "1"  !CDS_PN = "1";
"B":   PN = "2"  !CDS_PN = "2";
BODY = "RES","I81": #LOCATION = "R3N19" !CDS_LOCATION = "R3N19" #SEC = "1" !CDS_SEC = "1";
"A":   PN = "1"  !CDS_PN = "1";
"B":   PN = "2"  !CDS_PN = "2";
BODY = "CAP","I83": #LOCATION = "C3N39" !CDS_LOCATION = "C3N39" #SEC = "1" !CDS_SEC = "1";
"A":   PN = "1"  !CDS_PN = "1";
"B":   PN = "2"  !CDS_PN = "2";
BODY = "RES","I87": #LOCATION = "R3P26" !CDS_LOCATION = "R3P26" #SEC = "1" !CDS_SEC = "1";
"A":   PN = "1"  !CDS_PN = "1";
"B":   PN = "2"  !CDS_PN = "2";
BODY = "RES","I88": #LOCATION = "R3P21" !CDS_LOCATION = "R3P21" &SEC = "1" #&CDS_SEC = "1";
"A":   PN = "1"  !CDS_PN = "1";
"B":   PN = "2"  !CDS_PN = "2";
BODY = "PXE1110B","I93": #LOCATION = "EU3P1" !CDS_LOCATION = "EU3P1" #SEC = "1" !CDS_SEC = "1";
"AIREF1":   PN = "21"  !CDS_PN = "21";
"AISEN1":   PN = "22"  !CDS_PN = "22";
"APWM1":   PN = "5"  !CDS_PN = "5";
"ATSEN":   PN = "35"  !CDS_PN = "35";
"AVREF":   PN = "20"  !CDS_PN = "20";
"AVREN":   PN = "10"  !CDS_PN = "10";
"AVRRDY":   PN = "9"  !CDS_PN = "9";
"AVSEN":   PN = "19"  !CDS_PN = "19";
"BIREF1":   PN = "25"  !CDS_PN = "25";
"BISEN1":   PN = "26"  !CDS_PN = "26";
"BPWM1":   PN = "3"  !CDS_PN = "3";
"BTSEN":   PN = "34"  !CDS_PN = "34";
"BVREF":   PN = "30"  !CDS_PN = "30";
"BVSEN":   PN = "29"  !CDS_PN = "29";
"DNC<0>":   PN = "1"  !CDS_PN = "1";
"DNC<1>":   PN = "2"  !CDS_PN = "2";
"DNC<2>":   PN = "4"  !CDS_PN = "4";
"DNC<3>":   PN = "24"  !CDS_PN = "24";
"DNC<4>":   PN = "28"  !CDS_PN = "28";
"GND<0>":   PN = "27"  !CDS_PN = "27";
"GND<1>":   PN = "23"  !CDS_PN = "23";
"IINSEN":   PN = "38"  !CDS_PN = "38";
"MP0":   PN = "13"  !CDS_PN = "13";
"MP1":   PN = "14"  !CDS_PN = "14";
"MP2":   PN = "18"  !CDS_PN = "18";
"MP3":   PN = "31"  !CDS_PN = "31";
"MP4":   PN = "32"  !CDS_PN = "32";
"PINALRT_N":   PN = "12"  !CDS_PN = "12";
"RESET_N":   PN = "8"  !CDS_PN = "8";
"SCL":   PN = "7"  !CDS_PN = "7";
"SDA":   PN = "6"  !CDS_PN = "6";
"THPAD":   PN = "41"  !CDS_PN = "41";
"VALRT_N":   PN = "17"  !CDS_PN = "17";
"VCLK":   PN = "15"  !CDS_PN = "15";
"VD12":   PN = "40"  !CDS_PN = "40";
"VDD":   PN = "39"  !CDS_PN = "39";
"VDIO":   PN = "16"  !CDS_PN = "16";
"VINSEN":   PN = "37"  !CDS_PN = "37";
"VRHOT_N":   PN = "11"  !CDS_PN = "11";
"XADDR1":   PN = "36"  !CDS_PN = "36";
"XADDR2":   PN = "33"  !CDS_PN = "33";
BODY = "SC22P50V2JN-4GP","I95": #LOCATION = "CF13" !CDS_LOCATION = "CF13" &SEC = "1" #&CDS_SEC = "1";
"1":   PN = "1"  !CDS_PN = "1";
"2":   PN = "2"  !CDS_PN = "2";
BODY = "RES","I96": #LOCATION = "RF13" !CDS_LOCATION = "RF13" #SEC = "1" !CDS_SEC = "1";
"A":   PN = "1"  !CDS_PN = "1";
"B":   PN = "2"  !CDS_PN = "2";
BODY = "CAP","I97": #LOCATION = "C4W1" !CDS_LOCATION = "C4W1" #SEC = "1" !CDS_SEC = "1";
"A":   PN = "1"  !CDS_PN = "1";
"B":   PN = "2"  !CDS_PN = "2";
BODY = "RES","I99": #LOCATION = "R3P17" !CDS_LOCATION = "R3P17" #SEC = "1" !CDS_SEC = "1";
"A":   PN = "1"  !CDS_PN = "1";
"B":   PN = "2"  !CDS_PN = "2";
BODY = "RES","I100": #LOCATION = "R3P13" !CDS_LOCATION = "R3P13" #SEC = "1" !CDS_SEC = "1";
"A":   PN = "1"  !CDS_PN = "1";
"B":   PN = "2"  !CDS_PN = "2";
BODY = "RES","I102": #LOCATION = "R3N22" !CDS_LOCATION = "R3N22" #SEC = "1" !CDS_SEC = "1";
"A":   PN = "1"  !CDS_PN = "1";
"B":   PN = "2"  !CDS_PN = "2";
BODY = "CAP_A","I103": #LOCATION = "C3P2" !CDS_LOCATION = "C3P2" #SEC = "1" !CDS_SEC = "1";
"A":   PN = "1"  !CDS_PN = "1";
"B":   PN = "2"  !CDS_PN = "2";
DRAWING = "@baseboard_fab2_lib.baseboard_fab2(sch_1):page212";
BODY = "CAPP","I18": #LOCATION = "C3N35" !CDS_LOCATION = "C3N35" &SEC = "1" #&CDS_SEC = "1";
"A":   PN = "1"  !CDS_PN = "1";
"B":   PN = "2"  !CDS_PN = "2";
BODY = "CAP_A","I23": #LOCATION = "C7C6" !CDS_LOCATION = "C7C6" #SEC = "1" !CDS_SEC = "1";
"A":   PN = "1"  !CDS_PN = "1";
"B":   PN = "2"  !CDS_PN = "2";
BODY = "CAP","I33": #LOCATION = "C7C18" !CDS_LOCATION = "C7C18" #SEC = "1" !CDS_SEC = "1";
"A":   PN = "1"  !CDS_PN = "1";
"B":   PN = "2"  !CDS_PN = "2";
BODY = "CAP","I36": #LOCATION = "C7C17" !CDS_LOCATION = "C7C17" #SEC = "1" !CDS_SEC = "1";
"A":   PN = "1"  !CDS_PN = "1";
"B":   PN = "2"  !CDS_PN = "2";
BODY = "CAP","I37": #LOCATION = "C7C14" !CDS_LOCATION = "C7C14" #SEC = "1" !CDS_SEC = "1";
"A":   PN = "1"  !CDS_PN = "1";
"B":   PN = "2"  !CDS_PN = "2";
BODY = "CAP_A","I38": #LOCATION = "C7C11" !CDS_LOCATION = "C7C11" #SEC = "1" !CDS_SEC = "1";
"A":   PN = "1"  !CDS_PN = "1";
"B":   PN = "2"  !CDS_PN = "2";
BODY = "CAP","I39": #LOCATION = "C7C12" !CDS_LOCATION = "C7C12" #SEC = "1" !CDS_SEC = "1";
"A":   PN = "1"  !CDS_PN = "1";
"B":   PN = "2"  !CDS_PN = "2";
BODY = "CAP","I40": #LOCATION = "C3N36" !CDS_LOCATION = "C3N36" #SEC = "1" !CDS_SEC = "1";
"A":   PN = "1"  !CDS_PN = "1";
"B":   PN = "2"  !CDS_PN = "2";
BODY = "CAP","I41": #LOCATION = "C3N33" !CDS_LOCATION = "C3N33" #SEC = "1" !CDS_SEC = "1";
"A":   PN = "1"  !CDS_PN = "1";
"B":   PN = "2"  !CDS_PN = "2";
BODY = "CAP","I43": #LOCATION = "C3N34" !CDS_LOCATION = "C3N34" #SEC = "1" !CDS_SEC = "1";
"A":   PN = "1"  !CDS_PN = "1";
"B":   PN = "2"  !CDS_PN = "2";
BODY = "CAP_A","I60": #LOCATION = "C3P1" !CDS_LOCATION = "C3P1" #SEC = "1" !CDS_SEC = "1";
"A":   PN = "1"  !CDS_PN = "1";
"B":   PN = "2"  !CDS_PN = "2";
BODY = "RES","I68": #LOCATION = "R3N20" !CDS_LOCATION = "R3N20" #SEC = "1" !CDS_SEC = "1";
"A":   PN = "1"  !CDS_PN = "1";
"B":   PN = "2"  !CDS_PN = "2";
BODY = "RES","I74": #LOCATION = "R3N21" !CDS_LOCATION = "R3N21" #SEC = "1" !CDS_SEC = "1";
"A":   PN = "1"  !CDS_PN = "1";
"B":   PN = "2"  !CDS_PN = "2";
BODY = "CAP_A","I77": #LOCATION = "C7C10" !CDS_LOCATION = "C7C10" #SEC = "1" !CDS_SEC = "1";
"A":   PN = "1"  !CDS_PN = "1";
"B":   PN = "2"  !CDS_PN = "2";
BODY = "RES","I78": #LOCATION = "R7C3" !CDS_LOCATION = "R7C3" #SEC = "1" !CDS_SEC = "1";
"A":   PN = "1"  !CDS_PN = "1";
"B":   PN = "2"  !CDS_PN = "2";
BODY = "IR354XX","I101": #LOCATION = "EU7C1" !CDS_LOCATION = "EU7C1" &SEC = "1" #&CDS_SEC = "1";
"BOOST":   PN = "33"  !CDS_PN = "33";
"EN":   PN = "35"  !CDS_PN = "35";
"GL<0>":   PN = "6"  !CDS_PN = "6";
"GL<1>":   PN = "41"  !CDS_PN = "41";
"IOUT":   PN = "38"  !CDS_PN = "38";
"LGND":   PN = "2"  !CDS_PN = "2";
"NC":   PN = "31"  !CDS_PN = "31";
"OCSET":   PN = "37"  !CDS_PN = "37";
"PGND<0>":   PN = "5"  !CDS_PN = "5";
"PGND<1>":   PN = "7"  !CDS_PN = "7";
"PGND<2>":   PN = "40"  !CDS_PN = "40";
"PHASE":   PN = "32"  !CDS_PN = "32";
"PWM":   PN = "34"  !CDS_PN = "34";
"REFIN":   PN = "39"  !CDS_PN = "39";
"SW":   PN = "10"  !CDS_PN = "10";
"TOUT_FLT":   PN = "36"  !CDS_PN = "36";
"VCC":   PN = "3"  !CDS_PN = "3";
"VDRV":   PN = "4"  !CDS_PN = "4";
"VIN<0>":   PN = "25"  !CDS_PN = "25";
"VIN<1>":   PN = "30"  !CDS_PN = "30";
"VOS":   PN = "1"  !CDS_PN = "1";
BODY = "RES","I103": #LOCATION = "R7C25" !CDS_LOCATION = "R7C25" &SEC = "1" #&CDS_SEC = "1";
"A":   PN = "1"  !CDS_PN = "1";
"B":   PN = "2"  !CDS_PN = "2";
BODY = "SHUNT","I104": #LOCATION = "SH3P1" !CDS_LOCATION = "SH3P1" #SEC = "1" !CDS_SEC = "1";
"A":   PN = "1"  !CDS_PN = "1";
"B":   PN = "2"  !CDS_PN = "2";
BODY = "SHUNT","I105": #LOCATION = "SH3P2" !CDS_LOCATION = "SH3P2" #SEC = "1" !CDS_SEC = "1";
"A":   PN = "1"  !CDS_PN = "1";
"B":   PN = "2"  !CDS_PN = "2";
BODY = "CAP_A","I106": #LOCATION = "CT70" !CDS_LOCATION = "CT70" &SEC = "1" #&CDS_SEC = "1";
"A":   PN = "1"  !CDS_PN = "1";
"B":   PN = "2"  !CDS_PN = "2";
BODY = "CAP","I109": #LOCATION = "CT71" !CDS_LOCATION = "CT71" &SEC = "1" #&CDS_SEC = "1";
"A":   PN = "1"  !CDS_PN = "1";
"B":   PN = "2"  !CDS_PN = "2";
BODY = "CAP","I118": #LOCATION = "CT72" !CDS_LOCATION = "CT72" #SEC = "1" !CDS_SEC = "1";
"A":   PN = "1"  !CDS_PN = "1";
"B":   PN = "2"  !CDS_PN = "2";
BODY = "RES","I120": #LOCATION = "RT47" !CDS_LOCATION = "RT47" #SEC = "1" !CDS_SEC = "1";
"A":   PN = "1"  !CDS_PN = "1";
"B":   PN = "2"  !CDS_PN = "2";
BODY = "SC22U16V5MX-4-GP","I124": #LOCATION = "C22W33" !CDS_LOCATION = "C22W33" #SEC = "1" !CDS_SEC = "1";
"1":   PN = "1"  !CDS_PN = "1";
"2":   PN = "2"  !CDS_PN = "2";
BODY = "SC22U16V5MX-4-GP","I126": #LOCATION = "C22W32" !CDS_LOCATION = "C22W32" #SEC = "1" !CDS_SEC = "1";
"1":   PN = "1"  !CDS_PN = "1";
"2":   PN = "2"  !CDS_PN = "2";
BODY = "SC22U16V5MX-4-GP","I129": #LOCATION = "C22W31" !CDS_LOCATION = "C22W31" #SEC = "1" !CDS_SEC = "1";
"1":   PN = "1"  !CDS_PN = "1";
"2":   PN = "2"  !CDS_PN = "2";
BODY = "SC22U16V5MX-4-GP","I130": #LOCATION = "C7C8" !CDS_LOCATION = "C7C8" #SEC = "1" !CDS_SEC = "1";
"1":   PN = "1"  !CDS_PN = "1";
"2":   PN = "2"  !CDS_PN = "2";
BODY = "SC22U16V5MX-4-GP","I132": #LOCATION = "C22W30" !CDS_LOCATION = "C22W30" #SEC = "1" !CDS_SEC = "1";
"1":   PN = "1"  !CDS_PN = "1";
"2":   PN = "2"  !CDS_PN = "2";
BODY = "SC22U16V5MX-4-GP","I134": #LOCATION = "C22W29" !CDS_LOCATION = "C22W29" #SEC = "1" !CDS_SEC = "1";
"1":   PN = "1"  !CDS_PN = "1";
"2":   PN = "2"  !CDS_PN = "2";
BODY = "SC22U16V5MX-4-GP","I136": #LOCATION = "C22W28" !CDS_LOCATION = "C22W28" #SEC = "1" !CDS_SEC = "1";
"1":   PN = "1"  !CDS_PN = "1";
"2":   PN = "2"  !CDS_PN = "2";
BODY = "SC22U16V5MX-4-GP","I138": #LOCATION = "C7C7" !CDS_LOCATION = "C7C7" #SEC = "1" !CDS_SEC = "1";
"1":   PN = "1"  !CDS_PN = "1";
"2":   PN = "2"  !CDS_PN = "2";
BODY = "RES","I140": #LOCATION = "R3N7" !CDS_LOCATION = "R3N7" #SEC = "1" !CDS_SEC = "1";
"A":   PN = "1"  !CDS_PN = "1";
"B":   PN = "2"  !CDS_PN = "2";
BODY = "IND-150NH-56-GP","I141": #LOCATION = "L7C2" !CDS_LOCATION = "L7C2" #SEC = "1" !CDS_SEC = "1";
"F":   PN = "2"  !CDS_PN = "2";
"S":   PN = "1"  !CDS_PN = "1";
BODY = "IND-100NH-35-GP","I142": #LOCATION = "L7C1" !CDS_LOCATION = "L7C1" #SEC = "1" !CDS_SEC = "1";
"F":   PN = "2"  !CDS_PN = "2";
"S":   PN = "1"  !CDS_PN = "1";
BODY = "SC1U10V2KX-4-GP","I143": #LOCATION = "C7C20" !CDS_LOCATION = "C7C20" #SEC = "1" !CDS_SEC = "1";
"1":   PN = "1"  !CDS_PN = "1";
"2":   PN = "2"  !CDS_PN = "2";
BODY = "1R3F-GP","I144": #LOCATION = "RT48" !CDS_LOCATION = "RT48" #SEC = "1" !CDS_SEC = "1";
"1":   PN = "1"  !CDS_PN = "1";
"2":   PN = "2"  !CDS_PN = "2";
BODY = "CAPP","I145": #LOCATION = "C3N26" !CDS_LOCATION = "C3N26" &SEC = "1" #&CDS_SEC = "1";
"A":   PN = "1"  !CDS_PN = "1";
"B":   PN = "2"  !CDS_PN = "2";
BODY = "CAPP","I146": #LOCATION = "C3N38" !CDS_LOCATION = "C3N38" &SEC = "1" #&CDS_SEC = "1";
"A":   PN = "1"  !CDS_PN = "1";
"B":   PN = "2"  !CDS_PN = "2";
DRAWING = "@baseboard_fab2_lib.baseboard_fab2(sch_1):page213";
BODY = "CAP_A","I9": #LOCATION = "C4D31" !CDS_LOCATION = "C4D31" #SEC = "1" !CDS_SEC = "1";
"A":   PN = "1"  !CDS_PN = "1";
"B":   PN = "2"  !CDS_PN = "2";
BODY = "CAP_A","I11": #LOCATION = "C4D32" !CDS_LOCATION = "C4D32" #SEC = "1" !CDS_SEC = "1";
"A":   PN = "1"  !CDS_PN = "1";
"B":   PN = "2"  !CDS_PN = "2";
BODY = "RES","I13": #LOCATION = "R4D46" !CDS_LOCATION = "R4D46" #SEC = "1" !CDS_SEC = "1";
"A":   PN = "1"  !CDS_PN = "1";
"B":   PN = "2"  !CDS_PN = "2";
BODY = "RES","I14": #LOCATION = "R6P49" !CDS_LOCATION = "R6P49" #SEC = "1" !CDS_SEC = "1";
"A":   PN = "1"  !CDS_PN = "1";
"B":   PN = "2"  !CDS_PN = "2";
BODY = "RES","I15": #LOCATION = "R4D42" !CDS_LOCATION = "R4D42" #SEC = "1" !CDS_SEC = "1";
"A":   PN = "1"  !CDS_PN = "1";
"B":   PN = "2"  !CDS_PN = "2";
BODY = "RES","I16": #LOCATION = "R4D56" !CDS_LOCATION = "R4D56" #SEC = "1" !CDS_SEC = "1";
"A":   PN = "1"  !CDS_PN = "1";
"B":   PN = "2"  !CDS_PN = "2";
BODY = "CAP_A","I17": #LOCATION = "C4D36" !CDS_LOCATION = "C4D36" #SEC = "1" !CDS_SEC = "1";
"A":   PN = "1"  !CDS_PN = "1";
"B":   PN = "2"  !CDS_PN = "2";
BODY = "RES","I25": #LOCATION = "R4D47" !CDS_LOCATION = "R4D47" #SEC = "1" !CDS_SEC = "1";
"A":   PN = "1"  !CDS_PN = "1";
"B":   PN = "2"  !CDS_PN = "2";
BODY = "RES","I27": #LOCATION = "R6P35" !CDS_LOCATION = "R6P35" #SEC = "1" !CDS_SEC = "1";
"A":   PN = "1"  !CDS_PN = "1";
"B":   PN = "2"  !CDS_PN = "2";
BODY = "RES","I30": #LOCATION = "R6P33" !CDS_LOCATION = "R6P33" #SEC = "1" !CDS_SEC = "1";
"A":   PN = "1"  !CDS_PN = "1";
"B":   PN = "2"  !CDS_PN = "2";
BODY = "RES","I31": #LOCATION = "R4D60" !CDS_LOCATION = "R4D60" #SEC = "1" !CDS_SEC = "1";
"A":   PN = "1"  !CDS_PN = "1";
"B":   PN = "2"  !CDS_PN = "2";
BODY = "RES","I32": #LOCATION = "R4D57" !CDS_LOCATION = "R4D57" #SEC = "1" !CDS_SEC = "1";
"A":   PN = "1"  !CDS_PN = "1";
"B":   PN = "2"  !CDS_PN = "2";
BODY = "CAP_A","I35": #LOCATION = "C4D38" !CDS_LOCATION = "C4D38" #SEC = "1" !CDS_SEC = "1";
"A":   PN = "1"  !CDS_PN = "1";
"B":   PN = "2"  !CDS_PN = "2";
BODY = "RES","I37": #LOCATION = "R4D54" !CDS_LOCATION = "R4D54" #SEC = "1" !CDS_SEC = "1";
"A":   PN = "1"  !CDS_PN = "1";
"B":   PN = "2"  !CDS_PN = "2";
BODY = "RES","I46": #LOCATION = "R4D51" !CDS_LOCATION = "R4D51" #SEC = "1" !CDS_SEC = "1";
"A":   PN = "1"  !CDS_PN = "1";
"B":   PN = "2"  !CDS_PN = "2";
BODY = "RES","I63": #LOCATION = "R4D49" !CDS_LOCATION = "R4D49" #SEC = "1" !CDS_SEC = "1";
"A":   PN = "1"  !CDS_PN = "1";
"B":   PN = "2"  !CDS_PN = "2";
BODY = "CAP","I73": #LOCATION = "C4D33" !CDS_LOCATION = "C4D33" #SEC = "1" !CDS_SEC = "1";
"A":   PN = "1"  !CDS_PN = "1";
"B":   PN = "2"  !CDS_PN = "2";
BODY = "CAP","I83": #LOCATION = "C4D44" !CDS_LOCATION = "C4D44" #SEC = "1" !CDS_SEC = "1";
"A":   PN = "1"  !CDS_PN = "1";
"B":   PN = "2"  !CDS_PN = "2";
BODY = "RES","I84": #LOCATION = "R4E7" !CDS_LOCATION = "R4E7" #SEC = "1" !CDS_SEC = "1";
"A":   PN = "1"  !CDS_PN = "1";
"B":   PN = "2"  !CDS_PN = "2";
BODY = "RES","I90": #LOCATION = "R6P41" !CDS_LOCATION = "R6P41" #SEC = "1" !CDS_SEC = "1";
"A":   PN = "1"  !CDS_PN = "1";
"B":   PN = "2"  !CDS_PN = "2";
BODY = "RES","I91": #LOCATION = "R6P40" !CDS_LOCATION = "R6P40" #SEC = "1" !CDS_SEC = "1";
"A":   PN = "1"  !CDS_PN = "1";
"B":   PN = "2"  !CDS_PN = "2";
BODY = "PXE1110B","I96": #LOCATION = "EU4D5" !CDS_LOCATION = "EU4D5" #SEC = "1" !CDS_SEC = "1";
"AIREF1":   PN = "21"  !CDS_PN = "21";
"AISEN1":   PN = "22"  !CDS_PN = "22";
"APWM1":   PN = "5"  !CDS_PN = "5";
"ATSEN":   PN = "35"  !CDS_PN = "35";
"AVREF":   PN = "20"  !CDS_PN = "20";
"AVREN":   PN = "10"  !CDS_PN = "10";
"AVRRDY":   PN = "9"  !CDS_PN = "9";
"AVSEN":   PN = "19"  !CDS_PN = "19";
"BIREF1":   PN = "25"  !CDS_PN = "25";
"BISEN1":   PN = "26"  !CDS_PN = "26";
"BPWM1":   PN = "3"  !CDS_PN = "3";
"BTSEN":   PN = "34"  !CDS_PN = "34";
"BVREF":   PN = "30"  !CDS_PN = "30";
"BVSEN":   PN = "29"  !CDS_PN = "29";
"DNC<0>":   PN = "1"  !CDS_PN = "1";
"DNC<1>":   PN = "2"  !CDS_PN = "2";
"DNC<2>":   PN = "4"  !CDS_PN = "4";
"DNC<3>":   PN = "24"  !CDS_PN = "24";
"DNC<4>":   PN = "28"  !CDS_PN = "28";
"GND<0>":   PN = "27"  !CDS_PN = "27";
"GND<1>":   PN = "23"  !CDS_PN = "23";
"IINSEN":   PN = "38"  !CDS_PN = "38";
"MP0":   PN = "13"  !CDS_PN = "13";
"MP1":   PN = "14"  !CDS_PN = "14";
"MP2":   PN = "18"  !CDS_PN = "18";
"MP3":   PN = "31"  !CDS_PN = "31";
"MP4":   PN = "32"  !CDS_PN = "32";
"PINALRT_N":   PN = "12"  !CDS_PN = "12";
"RESET_N":   PN = "8"  !CDS_PN = "8";
"SCL":   PN = "7"  !CDS_PN = "7";
"SDA":   PN = "6"  !CDS_PN = "6";
"THPAD":   PN = "41"  !CDS_PN = "41";
"VALRT_N":   PN = "17"  !CDS_PN = "17";
"VCLK":   PN = "15"  !CDS_PN = "15";
"VD12":   PN = "40"  !CDS_PN = "40";
"VDD":   PN = "39"  !CDS_PN = "39";
"VDIO":   PN = "16"  !CDS_PN = "16";
"VINSEN":   PN = "37"  !CDS_PN = "37";
"VRHOT_N":   PN = "11"  !CDS_PN = "11";
"XADDR1":   PN = "36"  !CDS_PN = "36";
"XADDR2":   PN = "33"  !CDS_PN = "33";
BODY = "SC22P50V2JN-4GP","I98": #LOCATION = "CF14" !CDS_LOCATION = "CF14" &SEC = "1" #&CDS_SEC = "1";
"1":   PN = "1"  !CDS_PN = "1";
"2":   PN = "2"  !CDS_PN = "2";
BODY = "RES","I99": #LOCATION = "RF14" !CDS_LOCATION = "RF14" #SEC = "1" !CDS_SEC = "1";
"A":   PN = "1"  !CDS_PN = "1";
"B":   PN = "2"  !CDS_PN = "2";
BODY = "CAP","I101": #LOCATION = "C4W2" !CDS_LOCATION = "C4W2" #SEC = "1" !CDS_SEC = "1";
"A":   PN = "1"  !CDS_PN = "1";
"B":   PN = "2"  !CDS_PN = "2";
BODY = "RES","I103": #LOCATION = "R4E2" !CDS_LOCATION = "R4E2" #SEC = "1" !CDS_SEC = "1";
"A":   PN = "1"  !CDS_PN = "1";
"B":   PN = "2"  !CDS_PN = "2";
BODY = "RES","I104": #LOCATION = "R4D64" !CDS_LOCATION = "R4D64" #SEC = "1" !CDS_SEC = "1";
"A":   PN = "1"  !CDS_PN = "1";
"B":   PN = "2"  !CDS_PN = "2";
BODY = "CAP_A","I105": #LOCATION = "C4D40" !CDS_LOCATION = "C4D40" #SEC = "1" !CDS_SEC = "1";
"A":   PN = "1"  !CDS_PN = "1";
"B":   PN = "2"  !CDS_PN = "2";
DRAWING = "@baseboard_fab2_lib.baseboard_fab2(sch_1):page214";
BODY = "CAPP","I24": #LOCATION = "C6R5" !CDS_LOCATION = "C6R5" #SEC = "1" !CDS_SEC = "1";
"A":   PN = "1"  !CDS_PN = "1";
"B":   PN = "2"  !CDS_PN = "2";
BODY = "CAP_A","I65": #LOCATION = "C7R1" !CDS_LOCATION = "C7R1" #SEC = "1" !CDS_SEC = "1";
"A":   PN = "1"  !CDS_PN = "1";
"B":   PN = "2"  !CDS_PN = "2";
BODY = "CAP","I73": #LOCATION = "C4E23" !CDS_LOCATION = "C4E23" #SEC = "1" !CDS_SEC = "1";
"A":   PN = "1"  !CDS_PN = "1";
"B":   PN = "2"  !CDS_PN = "2";
BODY = "CAP","I76": #LOCATION = "C4E22" !CDS_LOCATION = "C4E22" #SEC = "1" !CDS_SEC = "1";
"A":   PN = "1"  !CDS_PN = "1";
"B":   PN = "2"  !CDS_PN = "2";
BODY = "CAP_A","I77": #LOCATION = "C4E13" !CDS_LOCATION = "C4E13" #SEC = "1" !CDS_SEC = "1";
"A":   PN = "1"  !CDS_PN = "1";
"B":   PN = "2"  !CDS_PN = "2";
BODY = "CAP","I78": #LOCATION = "C4E18" !CDS_LOCATION = "C4E18" #SEC = "1" !CDS_SEC = "1";
"A":   PN = "1"  !CDS_PN = "1";
"B":   PN = "2"  !CDS_PN = "2";
BODY = "CAP","I79": #LOCATION = "C4E15" !CDS_LOCATION = "C4E15" #SEC = "1" !CDS_SEC = "1";
"A":   PN = "1"  !CDS_PN = "1";
"B":   PN = "2"  !CDS_PN = "2";
BODY = "CAP","I80": #LOCATION = "C6R14" !CDS_LOCATION = "C6R14" #SEC = "1" !CDS_SEC = "1";
"A":   PN = "1"  !CDS_PN = "1";
"B":   PN = "2"  !CDS_PN = "2";
BODY = "CAP","I81": #LOCATION = "C6R10" !CDS_LOCATION = "C6R10" #SEC = "1" !CDS_SEC = "1";
"A":   PN = "1"  !CDS_PN = "1";
"B":   PN = "2"  !CDS_PN = "2";
BODY = "CAP","I83": #LOCATION = "C6R8" !CDS_LOCATION = "C6R8" #SEC = "1" !CDS_SEC = "1";
"A":   PN = "1"  !CDS_PN = "1";
"B":   PN = "2"  !CDS_PN = "2";
BODY = "CAP_A","I96": #LOCATION = "C3D27" !CDS_LOCATION = "C3D27" #SEC = "1" !CDS_SEC = "1";
"A":   PN = "1"  !CDS_PN = "1";
"B":   PN = "2"  !CDS_PN = "2";
BODY = "RES","I101": #LOCATION = "R3D28" !CDS_LOCATION = "R3D28" #SEC = "1" !CDS_SEC = "1";
"A":   PN = "1"  !CDS_PN = "1";
"B":   PN = "2"  !CDS_PN = "2";
BODY = "RES","I105": #LOCATION = "R3E1" !CDS_LOCATION = "R3E1" #SEC = "1" !CDS_SEC = "1";
"A":   PN = "1"  !CDS_PN = "1";
"B":   PN = "2"  !CDS_PN = "2";
BODY = "CAP_A","I108": #LOCATION = "C3E1" !CDS_LOCATION = "C3E1" #SEC = "1" !CDS_SEC = "1";
"A":   PN = "1"  !CDS_PN = "1";
"B":   PN = "2"  !CDS_PN = "2";
BODY = "RES","I109": #LOCATION = "R7R1" !CDS_LOCATION = "R7R1" #SEC = "1" !CDS_SEC = "1";
"A":   PN = "1"  !CDS_PN = "1";
"B":   PN = "2"  !CDS_PN = "2";
BODY = "IR354XX","I126": #LOCATION = "EU4E2" !CDS_LOCATION = "EU4E2" #SEC = "1" !CDS_SEC = "1";
"BOOST":   PN = "33"  !CDS_PN = "33";
"EN":   PN = "35"  !CDS_PN = "35";
"GL<0>":   PN = "6"  !CDS_PN = "6";
"GL<1>":   PN = "41"  !CDS_PN = "41";
"IOUT":   PN = "38"  !CDS_PN = "38";
"LGND":   PN = "2"  !CDS_PN = "2";
"NC":   PN = "31"  !CDS_PN = "31";
"OCSET":   PN = "37"  !CDS_PN = "37";
"PGND<0>":   PN = "5"  !CDS_PN = "5";
"PGND<1>":   PN = "7"  !CDS_PN = "7";
"PGND<2>":   PN = "40"  !CDS_PN = "40";
"PHASE":   PN = "32"  !CDS_PN = "32";
"PWM":   PN = "34"  !CDS_PN = "34";
"REFIN":   PN = "39"  !CDS_PN = "39";
"SW":   PN = "10"  !CDS_PN = "10";
"TOUT_FLT":   PN = "36"  !CDS_PN = "36";
"VCC":   PN = "3"  !CDS_PN = "3";
"VDRV":   PN = "4"  !CDS_PN = "4";
"VIN<0>":   PN = "25"  !CDS_PN = "25";
"VIN<1>":   PN = "30"  !CDS_PN = "30";
"VOS":   PN = "1"  !CDS_PN = "1";
BODY = "RES","I127": #LOCATION = "R4E21" !CDS_LOCATION = "R4E21" &SEC = "1" #&CDS_SEC = "1";
"A":   PN = "1"  !CDS_PN = "1";
"B":   PN = "2"  !CDS_PN = "2";
BODY = "SHUNT","I129": #LOCATION = "SH3D2" !CDS_LOCATION = "SH3D2" #SEC = "1" !CDS_SEC = "1";
"A":   PN = "1"  !CDS_PN = "1";
"B":   PN = "2"  !CDS_PN = "2";
BODY = "SHUNT","I130": #LOCATION = "SH3D1" !CDS_LOCATION = "SH3D1" #SEC = "1" !CDS_SEC = "1";
"A":   PN = "1"  !CDS_PN = "1";
"B":   PN = "2"  !CDS_PN = "2";
BODY = "CAP","I134": #LOCATION = "CT61" !CDS_LOCATION = "CT61" #SEC = "1" !CDS_SEC = "1";
"A":   PN = "1"  !CDS_PN = "1";
"B":   PN = "2"  !CDS_PN = "2";
BODY = "CAP_A","I137": #LOCATION = "CT63" !CDS_LOCATION = "CT63" #SEC = "1" !CDS_SEC = "1";
"A":   PN = "1"  !CDS_PN = "1";
"B":   PN = "2"  !CDS_PN = "2";
BODY = "CAP","I143": #LOCATION = "CT62" !CDS_LOCATION = "CT62" #SEC = "1" !CDS_SEC = "1";
"A":   PN = "1"  !CDS_PN = "1";
"B":   PN = "2"  !CDS_PN = "2";
BODY = "RES","I145": #LOCATION = "RT41" !CDS_LOCATION = "RT41" #SEC = "1" !CDS_SEC = "1";
"A":   PN = "1"  !CDS_PN = "1";
"B":   PN = "2"  !CDS_PN = "2";
BODY = "SC22U16V5MX-4-GP","I148": #LOCATION = "C4E14" !CDS_LOCATION = "C4E14" #SEC = "1" !CDS_SEC = "1";
"1":   PN = "1"  !CDS_PN = "1";
"2":   PN = "2"  !CDS_PN = "2";
BODY = "SC22U16V5MX-4-GP","I149": #LOCATION = "C22W13" !CDS_LOCATION = "C22W13" #SEC = "1" !CDS_SEC = "1";
"1":   PN = "1"  !CDS_PN = "1";
"2":   PN = "2"  !CDS_PN = "2";
BODY = "SC22U16V5MX-4-GP","I152": #LOCATION = "C22W14" !CDS_LOCATION = "C22W14" #SEC = "1" !CDS_SEC = "1";
"1":   PN = "1"  !CDS_PN = "1";
"2":   PN = "2"  !CDS_PN = "2";
BODY = "SC22U16V5MX-4-GP","I154": #LOCATION = "C22W15" !CDS_LOCATION = "C22W15" #SEC = "1" !CDS_SEC = "1";
"1":   PN = "1"  !CDS_PN = "1";
"2":   PN = "2"  !CDS_PN = "2";
BODY = "SC22U16V5MX-4-GP","I156": #LOCATION = "C22W18" !CDS_LOCATION = "C22W18" #SEC = "1" !CDS_SEC = "1";
"1":   PN = "1"  !CDS_PN = "1";
"2":   PN = "2"  !CDS_PN = "2";
BODY = "SC22U16V5MX-4-GP","I158": #LOCATION = "C22W17" !CDS_LOCATION = "C22W17" #SEC = "1" !CDS_SEC = "1";
"1":   PN = "1"  !CDS_PN = "1";
"2":   PN = "2"  !CDS_PN = "2";
BODY = "SC22U16V5MX-4-GP","I160": #LOCATION = "C22W16" !CDS_LOCATION = "C22W16" #SEC = "1" !CDS_SEC = "1";
"1":   PN = "1"  !CDS_PN = "1";
"2":   PN = "2"  !CDS_PN = "2";
BODY = "SC22U16V5MX-4-GP","I161": #LOCATION = "C4E8" !CDS_LOCATION = "C4E8" #SEC = "1" !CDS_SEC = "1";
"1":   PN = "1"  !CDS_PN = "1";
"2":   PN = "2"  !CDS_PN = "2";
BODY = "SC22U16V5MX-4-GP","I164": #LOCATION = "C4E9" !CDS_LOCATION = "C4E9" #SEC = "1" !CDS_SEC = "1";
"1":   PN = "1"  !CDS_PN = "1";
"2":   PN = "2"  !CDS_PN = "2";
BODY = "SC22U16V5MX-4-GP","I166": #LOCATION = "C22W21" !CDS_LOCATION = "C22W21" #SEC = "1" !CDS_SEC = "1";
"1":   PN = "1"  !CDS_PN = "1";
"2":   PN = "2"  !CDS_PN = "2";
BODY = "SC22U16V5MX-4-GP","I168": #LOCATION = "C22W20" !CDS_LOCATION = "C22W20" #SEC = "1" !CDS_SEC = "1";
"1":   PN = "1"  !CDS_PN = "1";
"2":   PN = "2"  !CDS_PN = "2";
BODY = "SC22U16V5MX-4-GP","I169": #LOCATION = "C22W19" !CDS_LOCATION = "C22W19" #SEC = "1" !CDS_SEC = "1";
"1":   PN = "1"  !CDS_PN = "1";
"2":   PN = "2"  !CDS_PN = "2";
BODY = "RES","I173": #LOCATION = "R6R5" !CDS_LOCATION = "R6R5" #SEC = "1" !CDS_SEC = "1";
"A":   PN = "1"  !CDS_PN = "1";
"B":   PN = "2"  !CDS_PN = "2";
BODY = "IND-150NH-56-GP","I174": #LOCATION = "L4E2" !CDS_LOCATION = "L4E2" #SEC = "1" !CDS_SEC = "1";
"F":   PN = "2"  !CDS_PN = "2";
"S":   PN = "1"  !CDS_PN = "1";
BODY = "SC1U10V2KX-4-GP","I175": #LOCATION = "C4E28" !CDS_LOCATION = "C4E28" #SEC = "1" !CDS_SEC = "1";
"1":   PN = "1"  !CDS_PN = "1";
"2":   PN = "2"  !CDS_PN = "2";
BODY = "1R3F-GP","I176": #LOCATION = "RT42" !CDS_LOCATION = "RT42" #SEC = "1" !CDS_SEC = "1";
"1":   PN = "1"  !CDS_PN = "1";
"2":   PN = "2"  !CDS_PN = "2";
BODY = "CAPP","I177": #LOCATION = "C6R12" !CDS_LOCATION = "C6R12" #SEC = "1" !CDS_SEC = "1";
"A":   PN = "1"  !CDS_PN = "1";
"B":   PN = "2"  !CDS_PN = "2";
BODY = "CAPP","I178": #LOCATION = "C4E7" !CDS_LOCATION = "C4E7" #SEC = "1" !CDS_SEC = "1";
"A":   PN = "1"  !CDS_PN = "1";
"B":   PN = "2"  !CDS_PN = "2";
DRAWING = "@baseboard_fab2_lib.baseboard_fab2(sch_1):page216";
BODY = "CAP","I6": #LOCATION = "C6G3" !CDS_LOCATION = "C6G3" #SEC = "1" !CDS_SEC = "1";
"A":   PN = "1"  !CDS_PN = "1";
"B":   PN = "2"  !CDS_PN = "2";
BODY = "CAP","I44": #LOCATION = "C7G31" !CDS_LOCATION = "C7G31" #SEC = "1" !CDS_SEC = "1";
"A":   PN = "1"  !CDS_PN = "1";
"B":   PN = "2"  !CDS_PN = "2";
BODY = "CAP","I45": #LOCATION = "C3U2" !CDS_LOCATION = "C3U2" #SEC = "1" !CDS_SEC = "1";
"A":   PN = "1"  !CDS_PN = "1";
"B":   PN = "2"  !CDS_PN = "2";
BODY = "CAP","I46": #LOCATION = "C3U3" !CDS_LOCATION = "C3U3" #SEC = "1" !CDS_SEC = "1";
"A":   PN = "1"  !CDS_PN = "1";
"B":   PN = "2"  !CDS_PN = "2";
BODY = "CAP","I47": #LOCATION = "C3U4" !CDS_LOCATION = "C3U4" #SEC = "1" !CDS_SEC = "1";
"A":   PN = "1"  !CDS_PN = "1";
"B":   PN = "2"  !CDS_PN = "2";
BODY = "CAP","I48": #LOCATION = "C7G37" !CDS_LOCATION = "C7G37" #SEC = "1" !CDS_SEC = "1";
"A":   PN = "1"  !CDS_PN = "1";
"B":   PN = "2"  !CDS_PN = "2";
BODY = "CAP","I50": #LOCATION = "C7G33" !CDS_LOCATION = "C7G33" #SEC = "1" !CDS_SEC = "1";
"A":   PN = "1"  !CDS_PN = "1";
"B":   PN = "2"  !CDS_PN = "2";
BODY = "CAP_A","I51": #LOCATION = "C7G29" !CDS_LOCATION = "C7G29" #SEC = "1" !CDS_SEC = "1";
"A":   PN = "1"  !CDS_PN = "1";
"B":   PN = "2"  !CDS_PN = "2";
BODY = "CAP","I54": #LOCATION = "C7G34" !CDS_LOCATION = "C7G34" #SEC = "1" !CDS_SEC = "1";
"A":   PN = "1"  !CDS_PN = "1";
"B":   PN = "2"  !CDS_PN = "2";
BODY = "CAP","I68": #LOCATION = "C7G27" !CDS_LOCATION = "C7G27" #SEC = "1" !CDS_SEC = "1";
"A":   PN = "1"  !CDS_PN = "1";
"B":   PN = "2"  !CDS_PN = "2";
BODY = "CAP","I72": #LOCATION = "C7G41" !CDS_LOCATION = "C7G41" #SEC = "1" !CDS_SEC = "1";
"A":   PN = "1"  !CDS_PN = "1";
"B":   PN = "2"  !CDS_PN = "2";
BODY = "CAP","I77": #LOCATION = "C7G40" !CDS_LOCATION = "C7G40" #SEC = "1" !CDS_SEC = "1";
"A":   PN = "1"  !CDS_PN = "1";
"B":   PN = "2"  !CDS_PN = "2";
BODY = "CAP_A","I78": #LOCATION = "C7G36" !CDS_LOCATION = "C7G36" #SEC = "1" !CDS_SEC = "1";
"A":   PN = "1"  !CDS_PN = "1";
"B":   PN = "2"  !CDS_PN = "2";
BODY = "CAP","I79": #LOCATION = "C7G30" !CDS_LOCATION = "C7G30" #SEC = "1" !CDS_SEC = "1";
"A":   PN = "1"  !CDS_PN = "1";
"B":   PN = "2"  !CDS_PN = "2";
BODY = "CAP","I80": #LOCATION = "C3U9" !CDS_LOCATION = "C3U9" #SEC = "1" !CDS_SEC = "1";
"A":   PN = "1"  !CDS_PN = "1";
"B":   PN = "2"  !CDS_PN = "2";
BODY = "CAP","I81": #LOCATION = "C3U7" !CDS_LOCATION = "C3U7" #SEC = "1" !CDS_SEC = "1";
"A":   PN = "1"  !CDS_PN = "1";
"B":   PN = "2"  !CDS_PN = "2";
BODY = "CAP","I84": #LOCATION = "C3U6" !CDS_LOCATION = "C3U6" #SEC = "1" !CDS_SEC = "1";
"A":   PN = "1"  !CDS_PN = "1";
"B":   PN = "2"  !CDS_PN = "2";
BODY = "IR354XX","I102": #LOCATION = "EU7G2" !CDS_LOCATION = "EU7G2" #SEC = "1" !CDS_SEC = "1";
"BOOST":   PN = "33"  !CDS_PN = "33";
"EN":   PN = "35"  !CDS_PN = "35";
"GL<0>":   PN = "6"  !CDS_PN = "6";
"GL<1>":   PN = "41"  !CDS_PN = "41";
"IOUT":   PN = "38"  !CDS_PN = "38";
"LGND":   PN = "2"  !CDS_PN = "2";
"NC":   PN = "31"  !CDS_PN = "31";
"OCSET":   PN = "37"  !CDS_PN = "37";
"PGND<0>":   PN = "5"  !CDS_PN = "5";
"PGND<1>":   PN = "7"  !CDS_PN = "7";
"PGND<2>":   PN = "40"  !CDS_PN = "40";
"PHASE":   PN = "32"  !CDS_PN = "32";
"PWM":   PN = "34"  !CDS_PN = "34";
"REFIN":   PN = "39"  !CDS_PN = "39";
"SW":   PN = "10"  !CDS_PN = "10";
"TOUT_FLT":   PN = "36"  !CDS_PN = "36";
"VCC":   PN = "3"  !CDS_PN = "3";
"VDRV":   PN = "4"  !CDS_PN = "4";
"VIN<0>":   PN = "25"  !CDS_PN = "25";
"VIN<1>":   PN = "30"  !CDS_PN = "30";
"VOS":   PN = "1"  !CDS_PN = "1";
BODY = "IR354XX","I103": #LOCATION = "EU7G3" !CDS_LOCATION = "EU7G3" #SEC = "1" !CDS_SEC = "1";
"BOOST":   PN = "33"  !CDS_PN = "33";
"EN":   PN = "35"  !CDS_PN = "35";
"GL<0>":   PN = "6"  !CDS_PN = "6";
"GL<1>":   PN = "41"  !CDS_PN = "41";
"IOUT":   PN = "38"  !CDS_PN = "38";
"LGND":   PN = "2"  !CDS_PN = "2";
"NC":   PN = "31"  !CDS_PN = "31";
"OCSET":   PN = "37"  !CDS_PN = "37";
"PGND<0>":   PN = "5"  !CDS_PN = "5";
"PGND<1>":   PN = "7"  !CDS_PN = "7";
"PGND<2>":   PN = "40"  !CDS_PN = "40";
"PHASE":   PN = "32"  !CDS_PN = "32";
"PWM":   PN = "34"  !CDS_PN = "34";
"REFIN":   PN = "39"  !CDS_PN = "39";
"SW":   PN = "10"  !CDS_PN = "10";
"TOUT_FLT":   PN = "36"  !CDS_PN = "36";
"VCC":   PN = "3"  !CDS_PN = "3";
"VDRV":   PN = "4"  !CDS_PN = "4";
"VIN<0>":   PN = "25"  !CDS_PN = "25";
"VIN<1>":   PN = "30"  !CDS_PN = "30";
"VOS":   PN = "1"  !CDS_PN = "1";
BODY = "RES","I104": #LOCATION = "R7G25" !CDS_LOCATION = "R7G25" #SEC = "1" !CDS_SEC = "1";
"A":   PN = "1"  !CDS_PN = "1";
"B":   PN = "2"  !CDS_PN = "2";
BODY = "RES","I106": #LOCATION = "R7G30" !CDS_LOCATION = "R7G30" #SEC = "1" !CDS_SEC = "1";
"A":   PN = "1"  !CDS_PN = "1";
"B":   PN = "2"  !CDS_PN = "2";
BODY = "CAP_A","I108": #LOCATION = "CT51" !CDS_LOCATION = "CT51" #SEC = "1" !CDS_SEC = "1";
"A":   PN = "1"  !CDS_PN = "1";
"B":   PN = "2"  !CDS_PN = "2";
BODY = "CAP_A","I111": #LOCATION = "CT52" !CDS_LOCATION = "CT52" #SEC = "1" !CDS_SEC = "1";
"A":   PN = "1"  !CDS_PN = "1";
"B":   PN = "2"  !CDS_PN = "2";
BODY = "CAP","I118": #LOCATION = "CT49" !CDS_LOCATION = "CT49" #SEC = "1" !CDS_SEC = "1";
"A":   PN = "1"  !CDS_PN = "1";
"B":   PN = "2"  !CDS_PN = "2";
BODY = "CAP","I121": #LOCATION = "CT54" !CDS_LOCATION = "CT54" #SEC = "1" !CDS_SEC = "1";
"A":   PN = "1"  !CDS_PN = "1";
"B":   PN = "2"  !CDS_PN = "2";
BODY = "CAP","I128": #LOCATION = "C7G38" !CDS_LOCATION = "C7G38" #SEC = "1" !CDS_SEC = "1";
"A":   PN = "1"  !CDS_PN = "1";
"B":   PN = "2"  !CDS_PN = "2";
BODY = "CAP","I135": #LOCATION = "CT50" !CDS_LOCATION = "CT50" #SEC = "1" !CDS_SEC = "1";
"A":   PN = "1"  !CDS_PN = "1";
"B":   PN = "2"  !CDS_PN = "2";
BODY = "CAP","I136": #LOCATION = "CT53" !CDS_LOCATION = "CT53" #SEC = "1" !CDS_SEC = "1";
"A":   PN = "1"  !CDS_PN = "1";
"B":   PN = "2"  !CDS_PN = "2";
BODY = "RES","I139": #LOCATION = "RT33" !CDS_LOCATION = "RT33" #SEC = "1" !CDS_SEC = "1";
"A":   PN = "1"  !CDS_PN = "1";
"B":   PN = "2"  !CDS_PN = "2";
BODY = "RES","I140": #LOCATION = "RT36" !CDS_LOCATION = "RT36" #SEC = "1" !CDS_SEC = "1";
"A":   PN = "1"  !CDS_PN = "1";
"B":   PN = "2"  !CDS_PN = "2";
BODY = "RES","I145": #LOCATION = "R3U6" !CDS_LOCATION = "R3U6" #SEC = "1" !CDS_SEC = "1";
"A":   PN = "1"  !CDS_PN = "1";
"B":   PN = "2"  !CDS_PN = "2";
BODY = "RES","I146": #LOCATION = "R3U9" !CDS_LOCATION = "R3U9" #SEC = "1" !CDS_SEC = "1";
"A":   PN = "1"  !CDS_PN = "1";
"B":   PN = "2"  !CDS_PN = "2";
BODY = "SC1U10V2KX-4-GP","I149": #LOCATION = "C7G35" !CDS_LOCATION = "C7G35" #SEC = "1" !CDS_SEC = "1";
"1":   PN = "1"  !CDS_PN = "1";
"2":   PN = "2"  !CDS_PN = "2";
BODY = "SC1U10V2KX-4-GP","I150": #LOCATION = "C7G42" !CDS_LOCATION = "C7G42" #SEC = "1" !CDS_SEC = "1";
"1":   PN = "1"  !CDS_PN = "1";
"2":   PN = "2"  !CDS_PN = "2";
BODY = "1R3F-GP","I151": #LOCATION = "RT34" !CDS_LOCATION = "RT34" #SEC = "1" !CDS_SEC = "1";
"1":   PN = "1"  !CDS_PN = "1";
"2":   PN = "2"  !CDS_PN = "2";
BODY = "1R3F-GP","I152": #LOCATION = "RT35" !CDS_LOCATION = "RT35" #SEC = "1" !CDS_SEC = "1";
"1":   PN = "1"  !CDS_PN = "1";
"2":   PN = "2"  !CDS_PN = "2";
BODY = "IND-120NH-30-GP","I153": #LOCATION = "L7G1" !CDS_LOCATION = "L7G1" #SEC = "1" !CDS_SEC = "1";
"F":   PN = "2"  !CDS_PN = "2";
"S":   PN = "1"  !CDS_PN = "1";
BODY = "IND-120NH-30-GP","I155": #LOCATION = "L7G2" !CDS_LOCATION = "L7G2" #SEC = "1" !CDS_SEC = "1";
"F":   PN = "2"  !CDS_PN = "2";
"S":   PN = "1"  !CDS_PN = "1";
DRAWING = "@baseboard_fab2_lib.baseboard_fab2(sch_1):page217";
BODY = "RES","I58": #LOCATION = "R3U4" !CDS_LOCATION = "R3U4" &SEC = "1" #&CDS_SEC = "1";
"A":   PN = "1"  !CDS_PN = "1";
"B":   PN = "2"  !CDS_PN = "2";
BODY = "RES","I74": #LOCATION = "R4U6" !CDS_LOCATION = "R4U6" #SEC = "1" !CDS_SEC = "1";
"A":   PN = "1"  !CDS_PN = "1";
"B":   PN = "2"  !CDS_PN = "2";
BODY = "CAPP","I75": #LOCATION = "C7G28" !CDS_LOCATION = "C7G28" #SEC = "1" !CDS_SEC = "1";
"A":   PN = "1"  !CDS_PN = "1";
"B":   PN = "2"  !CDS_PN = "2";
BODY = "CAPP","I76": #LOCATION = "C3U1" !CDS_LOCATION = "C3U1" #SEC = "1" !CDS_SEC = "1";
"A":   PN = "1"  !CDS_PN = "1";
"B":   PN = "2"  !CDS_PN = "2";
BODY = "CAPP","I77": #LOCATION = "C3U5" !CDS_LOCATION = "C3U5" #SEC = "1" !CDS_SEC = "1";
"A":   PN = "1"  !CDS_PN = "1";
"B":   PN = "2"  !CDS_PN = "2";
BODY = "CAPP","I78": #LOCATION = "C3U8" !CDS_LOCATION = "C3U8" #SEC = "1" !CDS_SEC = "1";
"A":   PN = "1"  !CDS_PN = "1";
"B":   PN = "2"  !CDS_PN = "2";
BODY = "CAPP","I175": #LOCATION = "C7G2" !CDS_LOCATION = "C7G2" #SEC = "1" !CDS_SEC = "1";
"A":   PN = "1"  !CDS_PN = "1";
"B":   PN = "2"  !CDS_PN = "2";
BODY = "CAP_A","I205": #LOCATION = "C5F2" !CDS_LOCATION = "C5F2" #SEC = "1" !CDS_SEC = "1";
"A":   PN = "1"  !CDS_PN = "1";
"B":   PN = "2"  !CDS_PN = "2";
BODY = "CAP_A","I206": #LOCATION = "C5F1" !CDS_LOCATION = "C5F1" #SEC = "1" !CDS_SEC = "1";
"A":   PN = "1"  !CDS_PN = "1";
"B":   PN = "2"  !CDS_PN = "2";
BODY = "CAP_A","I207": #LOCATION = "C5G10" !CDS_LOCATION = "C5G10" #SEC = "1" !CDS_SEC = "1";
"A":   PN = "1"  !CDS_PN = "1";
"B":   PN = "2"  !CDS_PN = "2";
BODY = "CAP_A","I208": #LOCATION = "C5T2" !CDS_LOCATION = "C5T2" #SEC = "1" !CDS_SEC = "1";
"A":   PN = "1"  !CDS_PN = "1";
"B":   PN = "2"  !CDS_PN = "2";
BODY = "CAP_A","I209": #LOCATION = "C5U11" !CDS_LOCATION = "C5U11" #SEC = "1" !CDS_SEC = "1";
"A":   PN = "1"  !CDS_PN = "1";
"B":   PN = "2"  !CDS_PN = "2";
BODY = "CAP_A","I210": #LOCATION = "C5T13" !CDS_LOCATION = "C5T13" #SEC = "1" !CDS_SEC = "1";
"A":   PN = "1"  !CDS_PN = "1";
"B":   PN = "2"  !CDS_PN = "2";
BODY = "CAP_A","I211": #LOCATION = "C5T4" !CDS_LOCATION = "C5T4" #SEC = "1" !CDS_SEC = "1";
"A":   PN = "1"  !CDS_PN = "1";
"B":   PN = "2"  !CDS_PN = "2";
BODY = "CAP_A","I212": #LOCATION = "C5T1" !CDS_LOCATION = "C5T1" #SEC = "1" !CDS_SEC = "1";
"A":   PN = "1"  !CDS_PN = "1";
"B":   PN = "2"  !CDS_PN = "2";
BODY = "CAP_A","I213": #LOCATION = "C5G19" !CDS_LOCATION = "C5G19" #SEC = "1" !CDS_SEC = "1";
"A":   PN = "1"  !CDS_PN = "1";
"B":   PN = "2"  !CDS_PN = "2";
BODY = "SHUNT","I259": #LOCATION = "SH4U1" !CDS_LOCATION = "SH4U1" #SEC = "1" !CDS_SEC = "1";
"A":   PN = "1"  !CDS_PN = "1";
"B":   PN = "2"  !CDS_PN = "2";
BODY = "SHUNT","I260": #LOCATION = "SH4U2" !CDS_LOCATION = "SH4U2" #SEC = "1" !CDS_SEC = "1";
"A":   PN = "1"  !CDS_PN = "1";
"B":   PN = "2"  !CDS_PN = "2";
BODY = "IND-100NH-35-GP","I261": #LOCATION = "L7F2" !CDS_LOCATION = "L7F2" #SEC = "1" !CDS_SEC = "1";
"F":   PN = "2"  !CDS_PN = "2";
"S":   PN = "1"  !CDS_PN = "1";
BODY = "CAP_A","I269": #LOCATION = "C5D58" !CDS_LOCATION = "C5D58" &SEC = "1" #&CDS_SEC = "1";
"A":   PN = "1"  !CDS_PN = "1";
"B":   PN = "2"  !CDS_PN = "2";
BODY = "CAP_A","I270": #LOCATION = "C5D61" !CDS_LOCATION = "C5D61" &SEC = "1" #&CDS_SEC = "1";
"A":   PN = "1"  !CDS_PN = "1";
"B":   PN = "2"  !CDS_PN = "2";
BODY = "CAP_A","I271": #LOCATION = "C5D59" !CDS_LOCATION = "C5D59" &SEC = "1" #&CDS_SEC = "1";
"A":   PN = "1"  !CDS_PN = "1";
"B":   PN = "2"  !CDS_PN = "2";
BODY = "CAP_A","I272": #LOCATION = "C5D60" !CDS_LOCATION = "C5D60" &SEC = "1" #&CDS_SEC = "1";
"A":   PN = "1"  !CDS_PN = "1";
"B":   PN = "2"  !CDS_PN = "2";
BODY = "CAP_A","I279": #LOCATION = "C5D54" !CDS_LOCATION = "C5D54" &SEC = "1" #&CDS_SEC = "1";
"A":   PN = "1"  !CDS_PN = "1";
"B":   PN = "2"  !CDS_PN = "2";
BODY = "CAP_A","I280": #LOCATION = "C5D55" !CDS_LOCATION = "C5D55" &SEC = "1" #&CDS_SEC = "1";
"A":   PN = "1"  !CDS_PN = "1";
"B":   PN = "2"  !CDS_PN = "2";
BODY = "CAP_A","I281": #LOCATION = "C5D56" !CDS_LOCATION = "C5D56" &SEC = "1" #&CDS_SEC = "1";
"A":   PN = "1"  !CDS_PN = "1";
"B":   PN = "2"  !CDS_PN = "2";
BODY = "CAP_A","I282": #LOCATION = "C5D57" !CDS_LOCATION = "C5D57" &SEC = "1" #&CDS_SEC = "1";
"A":   PN = "1"  !CDS_PN = "1";
"B":   PN = "2"  !CDS_PN = "2";
BODY = "CAP_A","I283": #LOCATION = "C5U2" !CDS_LOCATION = "C5U2" #SEC = "1" !CDS_SEC = "1";
"A":   PN = "1"  !CDS_PN = "1";
"B":   PN = "2"  !CDS_PN = "2";
BODY = "CAP_A","I284": #LOCATION = "C5U3" !CDS_LOCATION = "C5U3" #SEC = "1" !CDS_SEC = "1";
"A":   PN = "1"  !CDS_PN = "1";
"B":   PN = "2"  !CDS_PN = "2";
BODY = "CAP_A","I285": #LOCATION = "C5U4" !CDS_LOCATION = "C5U4" #SEC = "1" !CDS_SEC = "1";
"A":   PN = "1"  !CDS_PN = "1";
"B":   PN = "2"  !CDS_PN = "2";
BODY = "CAP_A","I286": #LOCATION = "C5U5" !CDS_LOCATION = "C5U5" #SEC = "1" !CDS_SEC = "1";
"A":   PN = "1"  !CDS_PN = "1";
"B":   PN = "2"  !CDS_PN = "2";
BODY = "CAP_A","I287": #LOCATION = "C5U6" !CDS_LOCATION = "C5U6" #SEC = "1" !CDS_SEC = "1";
"A":   PN = "1"  !CDS_PN = "1";
"B":   PN = "2"  !CDS_PN = "2";
BODY = "CAP_A","I288": #LOCATION = "C5U7" !CDS_LOCATION = "C5U7" #SEC = "1" !CDS_SEC = "1";
"A":   PN = "1"  !CDS_PN = "1";
"B":   PN = "2"  !CDS_PN = "2";
BODY = "CAP_A","I289": #LOCATION = "C5U8" !CDS_LOCATION = "C5U8" #SEC = "1" !CDS_SEC = "1";
"A":   PN = "1"  !CDS_PN = "1";
"B":   PN = "2"  !CDS_PN = "2";
BODY = "CAP_A","I290": #LOCATION = "C5U9" !CDS_LOCATION = "C5U9" #SEC = "1" !CDS_SEC = "1";
"A":   PN = "1"  !CDS_PN = "1";
"B":   PN = "2"  !CDS_PN = "2";
BODY = "CAP_A","I291": #LOCATION = "C5T12" !CDS_LOCATION = "C5T12" #SEC = "1" !CDS_SEC = "1";
"A":   PN = "1"  !CDS_PN = "1";
"B":   PN = "2"  !CDS_PN = "2";
BODY = "CAP_A","I292": #LOCATION = "C5T11" !CDS_LOCATION = "C5T11" #SEC = "1" !CDS_SEC = "1";
"A":   PN = "1"  !CDS_PN = "1";
"B":   PN = "2"  !CDS_PN = "2";
BODY = "CAP_A","I293": #LOCATION = "C5T10" !CDS_LOCATION = "C5T10" #SEC = "1" !CDS_SEC = "1";
"A":   PN = "1"  !CDS_PN = "1";
"B":   PN = "2"  !CDS_PN = "2";
BODY = "CAP_A","I294": #LOCATION = "C5T9" !CDS_LOCATION = "C5T9" #SEC = "1" !CDS_SEC = "1";
"A":   PN = "1"  !CDS_PN = "1";
"B":   PN = "2"  !CDS_PN = "2";
BODY = "CAP_A","I295": #LOCATION = "C5T8" !CDS_LOCATION = "C5T8" #SEC = "1" !CDS_SEC = "1";
"A":   PN = "1"  !CDS_PN = "1";
"B":   PN = "2"  !CDS_PN = "2";
BODY = "CAP_A","I296": #LOCATION = "C5T7" !CDS_LOCATION = "C5T7" #SEC = "1" !CDS_SEC = "1";
"A":   PN = "1"  !CDS_PN = "1";
"B":   PN = "2"  !CDS_PN = "2";
BODY = "CAP_A","I297": #LOCATION = "C5T6" !CDS_LOCATION = "C5T6" #SEC = "1" !CDS_SEC = "1";
"A":   PN = "1"  !CDS_PN = "1";
"B":   PN = "2"  !CDS_PN = "2";
BODY = "CAP_A","I298": #LOCATION = "C5T5" !CDS_LOCATION = "C5T5" #SEC = "1" !CDS_SEC = "1";
"A":   PN = "1"  !CDS_PN = "1";
"B":   PN = "2"  !CDS_PN = "2";
BODY = "CAP_A","I299": #LOCATION = "C5G11" !CDS_LOCATION = "C5G11" #SEC = "1" !CDS_SEC = "1";
"A":   PN = "1"  !CDS_PN = "1";
"B":   PN = "2"  !CDS_PN = "2";
BODY = "CAP_A","I300": #LOCATION = "C5G12" !CDS_LOCATION = "C5G12" #SEC = "1" !CDS_SEC = "1";
"A":   PN = "1"  !CDS_PN = "1";
"B":   PN = "2"  !CDS_PN = "2";
BODY = "CAP_A","I301": #LOCATION = "C5G2" !CDS_LOCATION = "C5G2" #SEC = "1" !CDS_SEC = "1";
"A":   PN = "1"  !CDS_PN = "1";
"B":   PN = "2"  !CDS_PN = "2";
BODY = "CAP_A","I302": #LOCATION = "C5G4" !CDS_LOCATION = "C5G4" #SEC = "1" !CDS_SEC = "1";
"A":   PN = "1"  !CDS_PN = "1";
"B":   PN = "2"  !CDS_PN = "2";
BODY = "CAP_A","I303": #LOCATION = "C5G13" !CDS_LOCATION = "C5G13" #SEC = "1" !CDS_SEC = "1";
"A":   PN = "1"  !CDS_PN = "1";
"B":   PN = "2"  !CDS_PN = "2";
BODY = "CAP_A","I304": #LOCATION = "C5G6" !CDS_LOCATION = "C5G6" #SEC = "1" !CDS_SEC = "1";
"A":   PN = "1"  !CDS_PN = "1";
"B":   PN = "2"  !CDS_PN = "2";
BODY = "CAP_A","I305": #LOCATION = "C5G5" !CDS_LOCATION = "C5G5" #SEC = "1" !CDS_SEC = "1";
"A":   PN = "1"  !CDS_PN = "1";
"B":   PN = "2"  !CDS_PN = "2";
BODY = "CAP_A","I306": #LOCATION = "C5G7" !CDS_LOCATION = "C5G7" #SEC = "1" !CDS_SEC = "1";
"A":   PN = "1"  !CDS_PN = "1";
"B":   PN = "2"  !CDS_PN = "2";
BODY = "CAP_A","I307": #LOCATION = "C5G1" !CDS_LOCATION = "C5G1" #SEC = "1" !CDS_SEC = "1";
"A":   PN = "1"  !CDS_PN = "1";
"B":   PN = "2"  !CDS_PN = "2";
BODY = "CAP_A","I308": #LOCATION = "C5G8" !CDS_LOCATION = "C5G8" #SEC = "1" !CDS_SEC = "1";
"A":   PN = "1"  !CDS_PN = "1";
"B":   PN = "2"  !CDS_PN = "2";
BODY = "CAP_A","I309": #LOCATION = "C5G18" !CDS_LOCATION = "C5G18" #SEC = "1" !CDS_SEC = "1";
"A":   PN = "1"  !CDS_PN = "1";
"B":   PN = "2"  !CDS_PN = "2";
BODY = "CAP_A","I310": #LOCATION = "C5G17" !CDS_LOCATION = "C5G17" #SEC = "1" !CDS_SEC = "1";
"A":   PN = "1"  !CDS_PN = "1";
"B":   PN = "2"  !CDS_PN = "2";
BODY = "CAP_A","I311": #LOCATION = "C5G14" !CDS_LOCATION = "C5G14" #SEC = "1" !CDS_SEC = "1";
"A":   PN = "1"  !CDS_PN = "1";
"B":   PN = "2"  !CDS_PN = "2";
BODY = "CAP_A","I312": #LOCATION = "C5G16" !CDS_LOCATION = "C5G16" #SEC = "1" !CDS_SEC = "1";
"A":   PN = "1"  !CDS_PN = "1";
"B":   PN = "2"  !CDS_PN = "2";
BODY = "CAP_A","I313": #LOCATION = "C5G15" !CDS_LOCATION = "C5G15" #SEC = "1" !CDS_SEC = "1";
"A":   PN = "1"  !CDS_PN = "1";
"B":   PN = "2"  !CDS_PN = "2";
BODY = "CAP_A","I314": #LOCATION = "C5G3" !CDS_LOCATION = "C5G3" #SEC = "1" !CDS_SEC = "1";
"A":   PN = "1"  !CDS_PN = "1";
"B":   PN = "2"  !CDS_PN = "2";
BODY = "CAP","I316": #LOCATION = "C5U1" !CDS_LOCATION = "C5U1" #SEC = "1" !CDS_SEC = "1";
"A":   PN = "1"  !CDS_PN = "1";
"B":   PN = "2"  !CDS_PN = "2";
BODY = "CAP","I317": #LOCATION = "C5U10" !CDS_LOCATION = "C5U10" #SEC = "1" !CDS_SEC = "1";
"A":   PN = "1"  !CDS_PN = "1";
"B":   PN = "2"  !CDS_PN = "2";
BODY = "CAP","I318": #LOCATION = "C5G9" !CDS_LOCATION = "C5G9" #SEC = "1" !CDS_SEC = "1";
"A":   PN = "1"  !CDS_PN = "1";
"B":   PN = "2"  !CDS_PN = "2";
BODY = "CAP","I319": #LOCATION = "C4T4" !CDS_LOCATION = "C4T4" #SEC = "1" !CDS_SEC = "1";
"A":   PN = "1"  !CDS_PN = "1";
"B":   PN = "2"  !CDS_PN = "2";
BODY = "CAP","I320": #LOCATION = "C5U15" !CDS_LOCATION = "C5U15" #SEC = "1" !CDS_SEC = "1";
"A":   PN = "1"  !CDS_PN = "1";
"B":   PN = "2"  !CDS_PN = "2";
BODY = "CAP","I321": #LOCATION = "C5U13" !CDS_LOCATION = "C5U13" #SEC = "1" !CDS_SEC = "1";
"A":   PN = "1"  !CDS_PN = "1";
"B":   PN = "2"  !CDS_PN = "2";
BODY = "CAP","I322": #LOCATION = "C5U14" !CDS_LOCATION = "C5U14" #SEC = "1" !CDS_SEC = "1";
"A":   PN = "1"  !CDS_PN = "1";
"B":   PN = "2"  !CDS_PN = "2";
BODY = "CAP","I323": #LOCATION = "C5P41" !CDS_LOCATION = "C5P41" #SEC = "1" !CDS_SEC = "1";
"A":   PN = "1"  !CDS_PN = "1";
"B":   PN = "2"  !CDS_PN = "2";
BODY = "CAP","I324": #LOCATION = "C5P44" !CDS_LOCATION = "C5P44" #SEC = "1" !CDS_SEC = "1";
"A":   PN = "1"  !CDS_PN = "1";
"B":   PN = "2"  !CDS_PN = "2";
BODY = "CAP","I325": #LOCATION = "C5P42" !CDS_LOCATION = "C5P42" &SEC = "1" #&CDS_SEC = "1";
"A":   PN = "1"  !CDS_PN = "1";
"B":   PN = "2"  !CDS_PN = "2";
BODY = "CAP","I326": #LOCATION = "C5P43" !CDS_LOCATION = "C5P43" &SEC = "1" #&CDS_SEC = "1";
"A":   PN = "1"  !CDS_PN = "1";
"B":   PN = "2"  !CDS_PN = "2";
BODY = "CAP","I327": #LOCATION = "C5P38" !CDS_LOCATION = "C5P38" #SEC = "1" !CDS_SEC = "1";
"A":   PN = "1"  !CDS_PN = "1";
"B":   PN = "2"  !CDS_PN = "2";
BODY = "CAP","I328": #LOCATION = "C5P39" !CDS_LOCATION = "C5P39" #SEC = "1" !CDS_SEC = "1";
"A":   PN = "1"  !CDS_PN = "1";
"B":   PN = "2"  !CDS_PN = "2";
BODY = "CAP","I329": #LOCATION = "C5G20" !CDS_LOCATION = "C5G20" #SEC = "1" !CDS_SEC = "1";
"A":   PN = "1"  !CDS_PN = "1";
"B":   PN = "2"  !CDS_PN = "2";
DRAWING = "@baseboard_fab2_lib.baseboard_fab2(sch_1):page218";
BODY = "RES","I15": #LOCATION = "R3M6" !CDS_LOCATION = "R3M6" #SEC = "1" !CDS_SEC = "1";
"A":   PN = "1"  !CDS_PN = "1";
"B":   PN = "2"  !CDS_PN = "2";
BODY = "RES","I21": #LOCATION = "R7A17" !CDS_LOCATION = "R7A17" #SEC = "1" !CDS_SEC = "1";
"A":   PN = "1"  !CDS_PN = "1";
"B":   PN = "2"  !CDS_PN = "2";
BODY = "RES","I34": #LOCATION = "R3M5" !CDS_LOCATION = "R3M5" #SEC = "1" !CDS_SEC = "1";
"A":   PN = "1"  !CDS_PN = "1";
"B":   PN = "2"  !CDS_PN = "2";
BODY = "RES","I35": #LOCATION = "R3M1" !CDS_LOCATION = "R3M1" #SEC = "1" !CDS_SEC = "1";
"A":   PN = "1"  !CDS_PN = "1";
"B":   PN = "2"  !CDS_PN = "2";
BODY = "RES","I59": #LOCATION = "R7B1" !CDS_LOCATION = "R7B1" #SEC = "1" !CDS_SEC = "1";
"A":   PN = "1"  !CDS_PN = "1";
"B":   PN = "2"  !CDS_PN = "2";
BODY = "RES","I60": #LOCATION = "R3M3" !CDS_LOCATION = "R3M3" #SEC = "1" !CDS_SEC = "1";
"A":   PN = "1"  !CDS_PN = "1";
"B":   PN = "2"  !CDS_PN = "2";
BODY = "RES","I13": #LOCATION = "R7A7" !CDS_LOCATION = "R7A7" #SEC = "1" !CDS_SEC = "1";
"A":   PN = "1"  !CDS_PN = "1";
"B":   PN = "2"  !CDS_PN = "2";
BODY = "RES","I18": #LOCATION = "RF17" !CDS_LOCATION = "RF17" #SEC = "1" !CDS_SEC = "1";
"A":   PN = "1"  !CDS_PN = "1";
"B":   PN = "2"  !CDS_PN = "2";
BODY = "RES","I19": #LOCATION = "RF18" !CDS_LOCATION = "RF18" #SEC = "1" !CDS_SEC = "1";
"A":   PN = "1"  !CDS_PN = "1";
"B":   PN = "2"  !CDS_PN = "2";
BODY = "SC22P50V2JN-4GP","I20": #LOCATION = "CF18" !CDS_LOCATION = "CF18" &SEC = "1" #&CDS_SEC = "1";
"1":   PN = "1"  !CDS_PN = "1";
"2":   PN = "2"  !CDS_PN = "2";
BODY = "CAP_A","I28": #LOCATION = "C7B2" !CDS_LOCATION = "C7B2" #SEC = "1" !CDS_SEC = "1";
"A":   PN = "1"  !CDS_PN = "1";
"B":   PN = "2"  !CDS_PN = "2";
BODY = "CAP_A","I30": #LOCATION = "C7B1" !CDS_LOCATION = "C7B1" #SEC = "1" !CDS_SEC = "1";
"A":   PN = "1"  !CDS_PN = "1";
"B":   PN = "2"  !CDS_PN = "2";
BODY = "CAP_A","I38": #LOCATION = "C7A38" !CDS_LOCATION = "C7A38" #SEC = "1" !CDS_SEC = "1";
"A":   PN = "1"  !CDS_PN = "1";
"B":   PN = "2"  !CDS_PN = "2";
BODY = "CAP","I41": #LOCATION = "C7B3" !CDS_LOCATION = "C7B3" #SEC = "1" !CDS_SEC = "1";
"A":   PN = "1"  !CDS_PN = "1";
"B":   PN = "2"  !CDS_PN = "2";
BODY = "RES","I45": #LOCATION = "R7A12" !CDS_LOCATION = "R7A12" #SEC = "1" !CDS_SEC = "1";
"A":   PN = "1"  !CDS_PN = "1";
"B":   PN = "2"  !CDS_PN = "2";
BODY = "RES","I46": #LOCATION = "R12W29" !CDS_LOCATION = "R12W29" #SEC = "1" !CDS_SEC = "1";
"A":   PN = "1"  !CDS_PN = "1";
"B":   PN = "2"  !CDS_PN = "2";
BODY = "RES","I55": #LOCATION = "R12W30" !CDS_LOCATION = "R12W30" #SEC = "1" !CDS_SEC = "1";
"A":   PN = "1"  !CDS_PN = "1";
"B":   PN = "2"  !CDS_PN = "2";
BODY = "RES","I56": #LOCATION = "R7A11" !CDS_LOCATION = "R7A11" #SEC = "1" !CDS_SEC = "1";
"A":   PN = "1"  !CDS_PN = "1";
"B":   PN = "2"  !CDS_PN = "2";
BODY = "RES","I57": #LOCATION = "R7B4" !CDS_LOCATION = "R7B4" #SEC = "1" !CDS_SEC = "1";
"A":   PN = "1"  !CDS_PN = "1";
"B":   PN = "2"  !CDS_PN = "2";
BODY = "RES","I58": #LOCATION = "R7B5" !CDS_LOCATION = "R7B5" #SEC = "1" !CDS_SEC = "1";
"A":   PN = "1"  !CDS_PN = "1";
"B":   PN = "2"  !CDS_PN = "2";
BODY = "RES","I67": #LOCATION = "R3L11" !CDS_LOCATION = "R3L11" #SEC = "1" !CDS_SEC = "1";
"A":   PN = "1"  !CDS_PN = "1";
"B":   PN = "2"  !CDS_PN = "2";
BODY = "PXM1310B","I69": #LOCATION = "EU7A5" !CDS_LOCATION = "EU7A5" #SEC = "1" !CDS_SEC = "1";
"AIREF1":   PN = "21"  !CDS_PN = "21";
"AIREF2":   PN = "23"  !CDS_PN = "23";
"AIREF3":   PN = "25"  !CDS_PN = "25";
"AISEN1":   PN = "22"  !CDS_PN = "22";
"AISEN2":   PN = "24"  !CDS_PN = "24";
"AISEN3":   PN = "26"  !CDS_PN = "26";
"APWM1":   PN = "5"  !CDS_PN = "5";
"APWM2":   PN = "4"  !CDS_PN = "4";
"APWM3":   PN = "3"  !CDS_PN = "3";
"ATSEN":   PN = "35"  !CDS_PN = "35";
"AVREF":   PN = "20"  !CDS_PN = "20";
"AVREN":   PN = "10"  !CDS_PN = "10";
"AVRRDY":   PN = "9"  !CDS_PN = "9";
"AVSEN":   PN = "19"  !CDS_PN = "19";
"BIREF1":   PN = "31"  !CDS_PN = "31";
"BISEN1":   PN = "32"  !CDS_PN = "32";
"BPWM1":   PN = "1"  !CDS_PN = "1";
"BTSEN":   PN = "34"  !CDS_PN = "34";
"BVREF":   PN = "30"  !CDS_PN = "30";
"BVSEN":   PN = "29"  !CDS_PN = "29";
"DNC<0>":   PN = "2"  !CDS_PN = "2";
"DNC<1>":   PN = "28"  !CDS_PN = "28";
"GND":   PN = "27"  !CDS_PN = "27";
"IINSEN":   PN = "38"  !CDS_PN = "38";
"MP0":   PN = "13"  !CDS_PN = "13";
"MP1":   PN = "14"  !CDS_PN = "14";
"MP2":   PN = "18"  !CDS_PN = "18";
"PINALRT_N":   PN = "12"  !CDS_PN = "12";
"RESET_N":   PN = "8"  !CDS_PN = "8";
"SCL":   PN = "7"  !CDS_PN = "7";
"SDA":   PN = "6"  !CDS_PN = "6";
"THPAD":   PN = "41"  !CDS_PN = "41";
"VALRT_N":   PN = "17"  !CDS_PN = "17";
"VCLK":   PN = "15"  !CDS_PN = "15";
"VD12":   PN = "40"  !CDS_PN = "40";
"VDD":   PN = "39"  !CDS_PN = "39";
"VDIO":   PN = "16"  !CDS_PN = "16";
"VINSEN":   PN = "37"  !CDS_PN = "37";
"VRHOT_N":   PN = "11"  !CDS_PN = "11";
"XADDR1":   PN = "36"  !CDS_PN = "36";
"XADDR2":   PN = "33"  !CDS_PN = "33";
BODY = "CAP","I14": #LOCATION = "C7A28" !CDS_LOCATION = "C7A28" #SEC = "1" !CDS_SEC = "1";
"A":   PN = "1"  !CDS_PN = "1";
"B":   PN = "2"  !CDS_PN = "2";
BODY = "CAP","I16": #LOCATION = "C7A29" !CDS_LOCATION = "C7A29" #SEC = "1" !CDS_SEC = "1";
"A":   PN = "1"  !CDS_PN = "1";
"B":   PN = "2"  !CDS_PN = "2";
BODY = "SC22P50V2JN-4GP","I17": #LOCATION = "CF17" !CDS_LOCATION = "CF17" &SEC = "1" #&CDS_SEC = "1";
"1":   PN = "1"  !CDS_PN = "1";
"2":   PN = "2"  !CDS_PN = "2";
BODY = "CAP_A","I40": #LOCATION = "C7A37" !CDS_LOCATION = "C7A37" #SEC = "1" !CDS_SEC = "1";
"A":   PN = "1"  !CDS_PN = "1";
"B":   PN = "2"  !CDS_PN = "2";
BODY = "RES","I70": #LOCATION = "R3L13" !CDS_LOCATION = "R3L13" #SEC = "1" !CDS_SEC = "1";
"A":   PN = "1"  !CDS_PN = "1";
"B":   PN = "2"  !CDS_PN = "2";
BODY = "RES","I73": #LOCATION = "R7A10" !CDS_LOCATION = "R7A10" #SEC = "1" !CDS_SEC = "1";
"A":   PN = "1"  !CDS_PN = "1";
"B":   PN = "2"  !CDS_PN = "2";
BODY = "RES","I74": #LOCATION = "R7A8" !CDS_LOCATION = "R7A8" #SEC = "1" !CDS_SEC = "1";
"A":   PN = "1"  !CDS_PN = "1";
"B":   PN = "2"  !CDS_PN = "2";
BODY = "RES","I75": #LOCATION = "R12W28" !CDS_LOCATION = "R12W28" #SEC = "1" !CDS_SEC = "1";
"A":   PN = "1"  !CDS_PN = "1";
"B":   PN = "2"  !CDS_PN = "2";
BODY = "RES","I76": #LOCATION = "R7A9" !CDS_LOCATION = "R7A9" #SEC = "1" !CDS_SEC = "1";
"A":   PN = "1"  !CDS_PN = "1";
"B":   PN = "2"  !CDS_PN = "2";
DRAWING = "@baseboard_fab2_lib.baseboard_fab2(sch_1):page219";
BODY = "CAP","I44": #LOCATION = "C7A12" !CDS_LOCATION = "C7A12" #SEC = "1" !CDS_SEC = "1";
"A":   PN = "1"  !CDS_PN = "1";
"B":   PN = "2"  !CDS_PN = "2";
BODY = "CAP","I45": #LOCATION = "C3L2" !CDS_LOCATION = "C3L2" #SEC = "1" !CDS_SEC = "1";
"A":   PN = "1"  !CDS_PN = "1";
"B":   PN = "2"  !CDS_PN = "2";
BODY = "CAP","I46": #LOCATION = "C3L4" !CDS_LOCATION = "C3L4" #SEC = "1" !CDS_SEC = "1";
"A":   PN = "1"  !CDS_PN = "1";
"B":   PN = "2"  !CDS_PN = "2";
BODY = "CAP","I47": #LOCATION = "C3L13" !CDS_LOCATION = "C3L13" #SEC = "1" !CDS_SEC = "1";
"A":   PN = "1"  !CDS_PN = "1";
"B":   PN = "2"  !CDS_PN = "2";
BODY = "CAP","I48": #LOCATION = "C7A11" !CDS_LOCATION = "C7A11" #SEC = "1" !CDS_SEC = "1";
"A":   PN = "1"  !CDS_PN = "1";
"B":   PN = "2"  !CDS_PN = "2";
BODY = "CAP","I50": #LOCATION = "C7A16" !CDS_LOCATION = "C7A16" #SEC = "1" !CDS_SEC = "1";
"A":   PN = "1"  !CDS_PN = "1";
"B":   PN = "2"  !CDS_PN = "2";
BODY = "CAP_A","I51": #LOCATION = "C7A5" !CDS_LOCATION = "C7A5" #SEC = "1" !CDS_SEC = "1";
"A":   PN = "1"  !CDS_PN = "1";
"B":   PN = "2"  !CDS_PN = "2";
BODY = "CAP","I54": #LOCATION = "C7A17" !CDS_LOCATION = "C7A17" #SEC = "1" !CDS_SEC = "1";
"A":   PN = "1"  !CDS_PN = "1";
"B":   PN = "2"  !CDS_PN = "2";
BODY = "CAP","I68": #LOCATION = "C6A4" !CDS_LOCATION = "C6A4" #SEC = "1" !CDS_SEC = "1";
"A":   PN = "1"  !CDS_PN = "1";
"B":   PN = "2"  !CDS_PN = "2";
BODY = "CAP","I72": #LOCATION = "C7A25" !CDS_LOCATION = "C7A25" #SEC = "1" !CDS_SEC = "1";
"A":   PN = "1"  !CDS_PN = "1";
"B":   PN = "2"  !CDS_PN = "2";
BODY = "CAP","I75": #LOCATION = "C7A22" !CDS_LOCATION = "C7A22" #SEC = "1" !CDS_SEC = "1";
"A":   PN = "1"  !CDS_PN = "1";
"B":   PN = "2"  !CDS_PN = "2";
BODY = "CAP","I77": #LOCATION = "C7A24" !CDS_LOCATION = "C7A24" #SEC = "1" !CDS_SEC = "1";
"A":   PN = "1"  !CDS_PN = "1";
"B":   PN = "2"  !CDS_PN = "2";
BODY = "CAP_A","I78": #LOCATION = "C7A20" !CDS_LOCATION = "C7A20" #SEC = "1" !CDS_SEC = "1";
"A":   PN = "1"  !CDS_PN = "1";
"B":   PN = "2"  !CDS_PN = "2";
BODY = "CAP","I79": #LOCATION = "C7A21" !CDS_LOCATION = "C7A21" #SEC = "1" !CDS_SEC = "1";
"A":   PN = "1"  !CDS_PN = "1";
"B":   PN = "2"  !CDS_PN = "2";
BODY = "CAP","I80": #LOCATION = "C3L17" !CDS_LOCATION = "C3L17" #SEC = "1" !CDS_SEC = "1";
"A":   PN = "1"  !CDS_PN = "1";
"B":   PN = "2"  !CDS_PN = "2";
BODY = "CAP","I81": #LOCATION = "C3L16" !CDS_LOCATION = "C3L16" #SEC = "1" !CDS_SEC = "1";
"A":   PN = "1"  !CDS_PN = "1";
"B":   PN = "2"  !CDS_PN = "2";
BODY = "CAP","I84": #LOCATION = "C3L15" !CDS_LOCATION = "C3L15" #SEC = "1" !CDS_SEC = "1";
"A":   PN = "1"  !CDS_PN = "1";
"B":   PN = "2"  !CDS_PN = "2";
BODY = "CAP","I87": #LOCATION = "C6A1" !CDS_LOCATION = "C6A1" #SEC = "1" !CDS_SEC = "1";
"A":   PN = "1"  !CDS_PN = "1";
"B":   PN = "2"  !CDS_PN = "2";
BODY = "IR354XX","I106": #LOCATION = "EU7A1" !CDS_LOCATION = "EU7A1" #SEC = "1" !CDS_SEC = "1";
"BOOST":   PN = "33"  !CDS_PN = "33";
"EN":   PN = "35"  !CDS_PN = "35";
"GL<0>":   PN = "6"  !CDS_PN = "6";
"GL<1>":   PN = "41"  !CDS_PN = "41";
"IOUT":   PN = "38"  !CDS_PN = "38";
"LGND":   PN = "2"  !CDS_PN = "2";
"NC":   PN = "31"  !CDS_PN = "31";
"OCSET":   PN = "37"  !CDS_PN = "37";
"PGND<0>":   PN = "5"  !CDS_PN = "5";
"PGND<1>":   PN = "7"  !CDS_PN = "7";
"PGND<2>":   PN = "40"  !CDS_PN = "40";
"PHASE":   PN = "32"  !CDS_PN = "32";
"PWM":   PN = "34"  !CDS_PN = "34";
"REFIN":   PN = "39"  !CDS_PN = "39";
"SW":   PN = "10"  !CDS_PN = "10";
"TOUT_FLT":   PN = "36"  !CDS_PN = "36";
"VCC":   PN = "3"  !CDS_PN = "3";
"VDRV":   PN = "4"  !CDS_PN = "4";
"VIN<0>":   PN = "25"  !CDS_PN = "25";
"VIN<1>":   PN = "30"  !CDS_PN = "30";
"VOS":   PN = "1"  !CDS_PN = "1";
BODY = "IR354XX","I107": #LOCATION = "EU7A4" !CDS_LOCATION = "EU7A4" #SEC = "1" !CDS_SEC = "1";
"BOOST":   PN = "33"  !CDS_PN = "33";
"EN":   PN = "35"  !CDS_PN = "35";
"GL<0>":   PN = "6"  !CDS_PN = "6";
"GL<1>":   PN = "41"  !CDS_PN = "41";
"IOUT":   PN = "38"  !CDS_PN = "38";
"LGND":   PN = "2"  !CDS_PN = "2";
"NC":   PN = "31"  !CDS_PN = "31";
"OCSET":   PN = "37"  !CDS_PN = "37";
"PGND<0>":   PN = "5"  !CDS_PN = "5";
"PGND<1>":   PN = "7"  !CDS_PN = "7";
"PGND<2>":   PN = "40"  !CDS_PN = "40";
"PHASE":   PN = "32"  !CDS_PN = "32";
"PWM":   PN = "34"  !CDS_PN = "34";
"REFIN":   PN = "39"  !CDS_PN = "39";
"SW":   PN = "10"  !CDS_PN = "10";
"TOUT_FLT":   PN = "36"  !CDS_PN = "36";
"VCC":   PN = "3"  !CDS_PN = "3";
"VDRV":   PN = "4"  !CDS_PN = "4";
"VIN<0>":   PN = "25"  !CDS_PN = "25";
"VIN<1>":   PN = "30"  !CDS_PN = "30";
"VOS":   PN = "1"  !CDS_PN = "1";
BODY = "RES","I108": #LOCATION = "R7A20" !CDS_LOCATION = "R7A20" &SEC = "1" #&CDS_SEC = "1";
"A":   PN = "1"  !CDS_PN = "1";
"B":   PN = "2"  !CDS_PN = "2";
BODY = "RES","I110": #LOCATION = "R7A21" !CDS_LOCATION = "R7A21" #SEC = "1" !CDS_SEC = "1";
"A":   PN = "1"  !CDS_PN = "1";
"B":   PN = "2"  !CDS_PN = "2";
BODY = "CAP_A","I113": #LOCATION = "CT46" !CDS_LOCATION = "CT46" #SEC = "1" !CDS_SEC = "1";
"A":   PN = "1"  !CDS_PN = "1";
"B":   PN = "2"  !CDS_PN = "2";
BODY = "CAP_A","I116": #LOCATION = "CT45" !CDS_LOCATION = "CT45" #SEC = "1" !CDS_SEC = "1";
"A":   PN = "1"  !CDS_PN = "1";
"B":   PN = "2"  !CDS_PN = "2";
BODY = "CAP","I119": #LOCATION = "CT48" !CDS_LOCATION = "CT48" #SEC = "1" !CDS_SEC = "1";
"A":   PN = "1"  !CDS_PN = "1";
"B":   PN = "2"  !CDS_PN = "2";
BODY = "CAP","I124": #LOCATION = "CT43" !CDS_LOCATION = "CT43" #SEC = "1" !CDS_SEC = "1";
"A":   PN = "1"  !CDS_PN = "1";
"B":   PN = "2"  !CDS_PN = "2";
BODY = "CAP","I137": #LOCATION = "CT44" !CDS_LOCATION = "CT44" #SEC = "1" !CDS_SEC = "1";
"A":   PN = "1"  !CDS_PN = "1";
"B":   PN = "2"  !CDS_PN = "2";
BODY = "CAP","I138": #LOCATION = "CT47" !CDS_LOCATION = "CT47" #SEC = "1" !CDS_SEC = "1";
"A":   PN = "1"  !CDS_PN = "1";
"B":   PN = "2"  !CDS_PN = "2";
BODY = "RES","I141": #LOCATION = "RT30" !CDS_LOCATION = "RT30" #SEC = "1" !CDS_SEC = "1";
"A":   PN = "1"  !CDS_PN = "1";
"B":   PN = "2"  !CDS_PN = "2";
BODY = "RES","I142": #LOCATION = "RT31" !CDS_LOCATION = "RT31" #SEC = "1" !CDS_SEC = "1";
"A":   PN = "1"  !CDS_PN = "1";
"B":   PN = "2"  !CDS_PN = "2";
BODY = "RES","I147": #LOCATION = "R3L6" !CDS_LOCATION = "R3L6" #SEC = "1" !CDS_SEC = "1";
"A":   PN = "1"  !CDS_PN = "1";
"B":   PN = "2"  !CDS_PN = "2";
BODY = "RES","I148": #LOCATION = "R3L8" !CDS_LOCATION = "R3L8" #SEC = "1" !CDS_SEC = "1";
"A":   PN = "1"  !CDS_PN = "1";
"B":   PN = "2"  !CDS_PN = "2";
BODY = "SC1U10V2KX-4-GP","I151": #LOCATION = "C7A18" !CDS_LOCATION = "C7A18" #SEC = "1" !CDS_SEC = "1";
"1":   PN = "1"  !CDS_PN = "1";
"2":   PN = "2"  !CDS_PN = "2";
BODY = "SC1U10V2KX-4-GP","I152": #LOCATION = "C7A26" !CDS_LOCATION = "C7A26" #SEC = "1" !CDS_SEC = "1";
"1":   PN = "1"  !CDS_PN = "1";
"2":   PN = "2"  !CDS_PN = "2";
BODY = "1R3F-GP","I153": #LOCATION = "RT29" !CDS_LOCATION = "RT29" #SEC = "1" !CDS_SEC = "1";
"1":   PN = "1"  !CDS_PN = "1";
"2":   PN = "2"  !CDS_PN = "2";
BODY = "1R3F-GP","I154": #LOCATION = "RT32" !CDS_LOCATION = "RT32" #SEC = "1" !CDS_SEC = "1";
"1":   PN = "1"  !CDS_PN = "1";
"2":   PN = "2"  !CDS_PN = "2";
BODY = "IND-120NH-30-GP","I157": #LOCATION = "L7A1" !CDS_LOCATION = "L7A1" #SEC = "1" !CDS_SEC = "1";
"F":   PN = "2"  !CDS_PN = "2";
"S":   PN = "1"  !CDS_PN = "1";
BODY = "IND-120NH-30-GP","I158": #LOCATION = "L7A3" !CDS_LOCATION = "L7A3" #SEC = "1" !CDS_SEC = "1";
"F":   PN = "2"  !CDS_PN = "2";
"S":   PN = "1"  !CDS_PN = "1";
DRAWING = "@baseboard_fab2_lib.baseboard_fab2(sch_1):page220";
BODY = "RES","I58": #LOCATION = "R4L4" !CDS_LOCATION = "R4L4" &SEC = "1" #&CDS_SEC = "1";
"A":   PN = "1"  !CDS_PN = "1";
"B":   PN = "2"  !CDS_PN = "2";
BODY = "RES","I74": #LOCATION = "R4L2" !CDS_LOCATION = "R4L2" #SEC = "1" !CDS_SEC = "1";
"A":   PN = "1"  !CDS_PN = "1";
"B":   PN = "2"  !CDS_PN = "2";
BODY = "CAPP","I75": #LOCATION = "C3L6" !CDS_LOCATION = "C3L6" #SEC = "1" !CDS_SEC = "1";
"A":   PN = "1"  !CDS_PN = "1";
"B":   PN = "2"  !CDS_PN = "2";
BODY = "CAPP","I76": #LOCATION = "C3L14" !CDS_LOCATION = "C3L14" #SEC = "1" !CDS_SEC = "1";
"A":   PN = "1"  !CDS_PN = "1";
"B":   PN = "2"  !CDS_PN = "2";
BODY = "CAPP","I77": #LOCATION = "C6A5" !CDS_LOCATION = "C6A5" #SEC = "1" !CDS_SEC = "1";
"A":   PN = "1"  !CDS_PN = "1";
"B":   PN = "2"  !CDS_PN = "2";
BODY = "CAPP","I78": #LOCATION = "C4L5" !CDS_LOCATION = "C4L5" #SEC = "1" !CDS_SEC = "1";
"A":   PN = "1"  !CDS_PN = "1";
"B":   PN = "2"  !CDS_PN = "2";
BODY = "CAP_A","I192": #LOCATION = "C5L15" !CDS_LOCATION = "C5L15" #SEC = "1" !CDS_SEC = "1";
"A":   PN = "1"  !CDS_PN = "1";
"B":   PN = "2"  !CDS_PN = "2";
BODY = "CAP_A","I193": #LOCATION = "C5A5" !CDS_LOCATION = "C5A5" #SEC = "1" !CDS_SEC = "1";
"A":   PN = "1"  !CDS_PN = "1";
"B":   PN = "2"  !CDS_PN = "2";
BODY = "CAP_A","I194": #LOCATION = "C5B1" !CDS_LOCATION = "C5B1" #SEC = "1" !CDS_SEC = "1";
"A":   PN = "1"  !CDS_PN = "1";
"B":   PN = "2"  !CDS_PN = "2";
BODY = "CAP_A","I195": #LOCATION = "C5M9" !CDS_LOCATION = "C5M9" #SEC = "1" !CDS_SEC = "1";
"A":   PN = "1"  !CDS_PN = "1";
"B":   PN = "2"  !CDS_PN = "2";
BODY = "CAP_A","I196": #LOCATION = "C4M5" !CDS_LOCATION = "C4M5" #SEC = "1" !CDS_SEC = "1";
"A":   PN = "1"  !CDS_PN = "1";
"B":   PN = "2"  !CDS_PN = "2";
BODY = "CAP_A","I197": #LOCATION = "C5B2" !CDS_LOCATION = "C5B2" #SEC = "1" !CDS_SEC = "1";
"A":   PN = "1"  !CDS_PN = "1";
"B":   PN = "2"  !CDS_PN = "2";
BODY = "CAP_A","I198": #LOCATION = "C5M10" !CDS_LOCATION = "C5M10" #SEC = "1" !CDS_SEC = "1";
"A":   PN = "1"  !CDS_PN = "1";
"B":   PN = "2"  !CDS_PN = "2";
BODY = "CAP_A","I199": #LOCATION = "C5M3" !CDS_LOCATION = "C5M3" #SEC = "1" !CDS_SEC = "1";
"A":   PN = "1"  !CDS_PN = "1";
"B":   PN = "2"  !CDS_PN = "2";
BODY = "CAP_A","I200": #LOCATION = "C5M11" !CDS_LOCATION = "C5M11" #SEC = "1" !CDS_SEC = "1";
"A":   PN = "1"  !CDS_PN = "1";
"B":   PN = "2"  !CDS_PN = "2";
BODY = "SHUNT","I239": #LOCATION = "SH4L2" !CDS_LOCATION = "SH4L2" #SEC = "1" !CDS_SEC = "1";
"A":   PN = "1"  !CDS_PN = "1";
"B":   PN = "2"  !CDS_PN = "2";
BODY = "SHUNT","I240": #LOCATION = "SH4L1" !CDS_LOCATION = "SH4L1" #SEC = "1" !CDS_SEC = "1";
"A":   PN = "1"  !CDS_PN = "1";
"B":   PN = "2"  !CDS_PN = "2";
BODY = "IND-100NH-35-GP","I241": #LOCATION = "L7A5" !CDS_LOCATION = "L7A5" #SEC = "1" !CDS_SEC = "1";
"F":   PN = "2"  !CDS_PN = "2";
"S":   PN = "1"  !CDS_PN = "1";
BODY = "CAP_A","I249": #LOCATION = "C5D4" !CDS_LOCATION = "C5D4" &SEC = "1" #&CDS_SEC = "1";
"A":   PN = "1"  !CDS_PN = "1";
"B":   PN = "2"  !CDS_PN = "2";
BODY = "CAP_A","I250": #LOCATION = "C5D3" !CDS_LOCATION = "C5D3" &SEC = "1" #&CDS_SEC = "1";
"A":   PN = "1"  !CDS_PN = "1";
"B":   PN = "2"  !CDS_PN = "2";
BODY = "CAP_A","I251": #LOCATION = "C5D2" !CDS_LOCATION = "C5D2" &SEC = "1" #&CDS_SEC = "1";
"A":   PN = "1"  !CDS_PN = "1";
"B":   PN = "2"  !CDS_PN = "2";
BODY = "CAP_A","I252": #LOCATION = "C5D1" !CDS_LOCATION = "C5D1" &SEC = "1" #&CDS_SEC = "1";
"A":   PN = "1"  !CDS_PN = "1";
"B":   PN = "2"  !CDS_PN = "2";
BODY = "CAP_A","I258": #LOCATION = "C5D9" !CDS_LOCATION = "C5D9" &SEC = "1" #&CDS_SEC = "1";
"A":   PN = "1"  !CDS_PN = "1";
"B":   PN = "2"  !CDS_PN = "2";
BODY = "CAP_A","I259": #LOCATION = "C5D6" !CDS_LOCATION = "C5D6" &SEC = "1" #&CDS_SEC = "1";
"A":   PN = "1"  !CDS_PN = "1";
"B":   PN = "2"  !CDS_PN = "2";
BODY = "CAP_A","I260": #LOCATION = "C5D7" !CDS_LOCATION = "C5D7" &SEC = "1" #&CDS_SEC = "1";
"A":   PN = "1"  !CDS_PN = "1";
"B":   PN = "2"  !CDS_PN = "2";
BODY = "CAP_A","I261": #LOCATION = "C5D8" !CDS_LOCATION = "C5D8" &SEC = "1" #&CDS_SEC = "1";
"A":   PN = "1"  !CDS_PN = "1";
"B":   PN = "2"  !CDS_PN = "2";
BODY = "CAP_A","I262": #LOCATION = "C5A1" !CDS_LOCATION = "C5A1" #SEC = "1" !CDS_SEC = "1";
"A":   PN = "1"  !CDS_PN = "1";
"B":   PN = "2"  !CDS_PN = "2";
BODY = "CAP_A","I263": #LOCATION = "C5A15" !CDS_LOCATION = "C5A15" #SEC = "1" !CDS_SEC = "1";
"A":   PN = "1"  !CDS_PN = "1";
"B":   PN = "2"  !CDS_PN = "2";
BODY = "CAP_A","I264": #LOCATION = "C5A12" !CDS_LOCATION = "C5A12" #SEC = "1" !CDS_SEC = "1";
"A":   PN = "1"  !CDS_PN = "1";
"B":   PN = "2"  !CDS_PN = "2";
BODY = "CAP_A","I265": #LOCATION = "C5A13" !CDS_LOCATION = "C5A13" #SEC = "1" !CDS_SEC = "1";
"A":   PN = "1"  !CDS_PN = "1";
"B":   PN = "2"  !CDS_PN = "2";
BODY = "CAP_A","I266": #LOCATION = "C5A2" !CDS_LOCATION = "C5A2" #SEC = "1" !CDS_SEC = "1";
"A":   PN = "1"  !CDS_PN = "1";
"B":   PN = "2"  !CDS_PN = "2";
BODY = "CAP_A","I267": #LOCATION = "C5A14" !CDS_LOCATION = "C5A14" #SEC = "1" !CDS_SEC = "1";
"A":   PN = "1"  !CDS_PN = "1";
"B":   PN = "2"  !CDS_PN = "2";
BODY = "CAP_A","I268": #LOCATION = "C5A6" !CDS_LOCATION = "C5A6" #SEC = "1" !CDS_SEC = "1";
"A":   PN = "1"  !CDS_PN = "1";
"B":   PN = "2"  !CDS_PN = "2";
BODY = "CAP_A","I269": #LOCATION = "C5A7" !CDS_LOCATION = "C5A7" #SEC = "1" !CDS_SEC = "1";
"A":   PN = "1"  !CDS_PN = "1";
"B":   PN = "2"  !CDS_PN = "2";
BODY = "CAP_A","I270": #LOCATION = "C5A3" !CDS_LOCATION = "C5A3" #SEC = "1" !CDS_SEC = "1";
"A":   PN = "1"  !CDS_PN = "1";
"B":   PN = "2"  !CDS_PN = "2";
BODY = "CAP_A","I271": #LOCATION = "C5A8" !CDS_LOCATION = "C5A8" #SEC = "1" !CDS_SEC = "1";
"A":   PN = "1"  !CDS_PN = "1";
"B":   PN = "2"  !CDS_PN = "2";
BODY = "CAP_A","I272": #LOCATION = "C5A9" !CDS_LOCATION = "C5A9" #SEC = "1" !CDS_SEC = "1";
"A":   PN = "1"  !CDS_PN = "1";
"B":   PN = "2"  !CDS_PN = "2";
BODY = "CAP_A","I273": #LOCATION = "C5A16" !CDS_LOCATION = "C5A16" #SEC = "1" !CDS_SEC = "1";
"A":   PN = "1"  !CDS_PN = "1";
"B":   PN = "2"  !CDS_PN = "2";
BODY = "CAP_A","I274": #LOCATION = "C5A4" !CDS_LOCATION = "C5A4" #SEC = "1" !CDS_SEC = "1";
"A":   PN = "1"  !CDS_PN = "1";
"B":   PN = "2"  !CDS_PN = "2";
BODY = "CAP_A","I275": #LOCATION = "C5A17" !CDS_LOCATION = "C5A17" #SEC = "1" !CDS_SEC = "1";
"A":   PN = "1"  !CDS_PN = "1";
"B":   PN = "2"  !CDS_PN = "2";
BODY = "CAP_A","I276": #LOCATION = "C5A18" !CDS_LOCATION = "C5A18" #SEC = "1" !CDS_SEC = "1";
"A":   PN = "1"  !CDS_PN = "1";
"B":   PN = "2"  !CDS_PN = "2";
BODY = "CAP_A","I277": #LOCATION = "C5A19" !CDS_LOCATION = "C5A19" #SEC = "1" !CDS_SEC = "1";
"A":   PN = "1"  !CDS_PN = "1";
"B":   PN = "2"  !CDS_PN = "2";
BODY = "CAP_A","I278": #LOCATION = "C5L6" !CDS_LOCATION = "C5L6" #SEC = "1" !CDS_SEC = "1";
"A":   PN = "1"  !CDS_PN = "1";
"B":   PN = "2"  !CDS_PN = "2";
BODY = "CAP_A","I279": #LOCATION = "C5L7" !CDS_LOCATION = "C5L7" #SEC = "1" !CDS_SEC = "1";
"A":   PN = "1"  !CDS_PN = "1";
"B":   PN = "2"  !CDS_PN = "2";
BODY = "CAP_A","I280": #LOCATION = "C5L8" !CDS_LOCATION = "C5L8" #SEC = "1" !CDS_SEC = "1";
"A":   PN = "1"  !CDS_PN = "1";
"B":   PN = "2"  !CDS_PN = "2";
BODY = "CAP_A","I281": #LOCATION = "C5L9" !CDS_LOCATION = "C5L9" #SEC = "1" !CDS_SEC = "1";
"A":   PN = "1"  !CDS_PN = "1";
"B":   PN = "2"  !CDS_PN = "2";
BODY = "CAP_A","I282": #LOCATION = "C5L10" !CDS_LOCATION = "C5L10" #SEC = "1" !CDS_SEC = "1";
"A":   PN = "1"  !CDS_PN = "1";
"B":   PN = "2"  !CDS_PN = "2";
BODY = "CAP_A","I283": #LOCATION = "C5L11" !CDS_LOCATION = "C5L11" #SEC = "1" !CDS_SEC = "1";
"A":   PN = "1"  !CDS_PN = "1";
"B":   PN = "2"  !CDS_PN = "2";
BODY = "CAP_A","I284": #LOCATION = "C5L12" !CDS_LOCATION = "C5L12" #SEC = "1" !CDS_SEC = "1";
"A":   PN = "1"  !CDS_PN = "1";
"B":   PN = "2"  !CDS_PN = "2";
BODY = "CAP_A","I285": #LOCATION = "C5L13" !CDS_LOCATION = "C5L13" #SEC = "1" !CDS_SEC = "1";
"A":   PN = "1"  !CDS_PN = "1";
"B":   PN = "2"  !CDS_PN = "2";
BODY = "CAP_A","I286": #LOCATION = "C5M7" !CDS_LOCATION = "C5M7" #SEC = "1" !CDS_SEC = "1";
"A":   PN = "1"  !CDS_PN = "1";
"B":   PN = "2"  !CDS_PN = "2";
BODY = "CAP_A","I287": #LOCATION = "C5M6" !CDS_LOCATION = "C5M6" #SEC = "1" !CDS_SEC = "1";
"A":   PN = "1"  !CDS_PN = "1";
"B":   PN = "2"  !CDS_PN = "2";
BODY = "CAP_A","I288": #LOCATION = "C5M5" !CDS_LOCATION = "C5M5" #SEC = "1" !CDS_SEC = "1";
"A":   PN = "1"  !CDS_PN = "1";
"B":   PN = "2"  !CDS_PN = "2";
BODY = "CAP_A","I289": #LOCATION = "C5M4" !CDS_LOCATION = "C5M4" #SEC = "1" !CDS_SEC = "1";
"A":   PN = "1"  !CDS_PN = "1";
"B":   PN = "2"  !CDS_PN = "2";
BODY = "CAP_A","I290": #LOCATION = "C5M2" !CDS_LOCATION = "C5M2" #SEC = "1" !CDS_SEC = "1";
"A":   PN = "1"  !CDS_PN = "1";
"B":   PN = "2"  !CDS_PN = "2";
BODY = "CAP_A","I291": #LOCATION = "C5M1" !CDS_LOCATION = "C5M1" #SEC = "1" !CDS_SEC = "1";
"A":   PN = "1"  !CDS_PN = "1";
"B":   PN = "2"  !CDS_PN = "2";
BODY = "CAP_A","I292": #LOCATION = "C4M2" !CDS_LOCATION = "C4M2" #SEC = "1" !CDS_SEC = "1";
"A":   PN = "1"  !CDS_PN = "1";
"B":   PN = "2"  !CDS_PN = "2";
BODY = "CAP_A","I293": #LOCATION = "C5A11" !CDS_LOCATION = "C5A11" #SEC = "1" !CDS_SEC = "1";
"A":   PN = "1"  !CDS_PN = "1";
"B":   PN = "2"  !CDS_PN = "2";
BODY = "SC22U16V5MX-4-GP","I298": #LOCATION = "C7W5" !CDS_LOCATION = "C7W5" #SEC = "1" !CDS_SEC = "1";
"1":   PN = "1"  !CDS_PN = "1";
"2":   PN = "2"  !CDS_PN = "2";
BODY = "SC22U16V5MX-4-GP","I299": #LOCATION = "C7W9" !CDS_LOCATION = "C7W9" #SEC = "1" !CDS_SEC = "1";
"1":   PN = "1"  !CDS_PN = "1";
"2":   PN = "2"  !CDS_PN = "2";
BODY = "SC22U16V5MX-4-GP","I300": #LOCATION = "C7W8" !CDS_LOCATION = "C7W8" #SEC = "1" !CDS_SEC = "1";
"1":   PN = "1"  !CDS_PN = "1";
"2":   PN = "2"  !CDS_PN = "2";
BODY = "SC22U16V5MX-4-GP","I301": #LOCATION = "C7W7" !CDS_LOCATION = "C7W7" #SEC = "1" !CDS_SEC = "1";
"1":   PN = "1"  !CDS_PN = "1";
"2":   PN = "2"  !CDS_PN = "2";
BODY = "SC22U16V5MX-4-GP","I302": #LOCATION = "C7W6" !CDS_LOCATION = "C7W6" #SEC = "1" !CDS_SEC = "1";
"1":   PN = "1"  !CDS_PN = "1";
"2":   PN = "2"  !CDS_PN = "2";
BODY = "SC22U16V5MX-4-GP","I303": #LOCATION = "C7W13" !CDS_LOCATION = "C7W13" #SEC = "1" !CDS_SEC = "1";
"1":   PN = "1"  !CDS_PN = "1";
"2":   PN = "2"  !CDS_PN = "2";
BODY = "SC22U16V5MX-4-GP","I304": #LOCATION = "C7W12" !CDS_LOCATION = "C7W12" #SEC = "1" !CDS_SEC = "1";
"1":   PN = "1"  !CDS_PN = "1";
"2":   PN = "2"  !CDS_PN = "2";
BODY = "SC22U16V5MX-4-GP","I305": #LOCATION = "C7W11" !CDS_LOCATION = "C7W11" #SEC = "1" !CDS_SEC = "1";
"1":   PN = "1"  !CDS_PN = "1";
"2":   PN = "2"  !CDS_PN = "2";
BODY = "SC22U16V5MX-4-GP","I306": #LOCATION = "C7W10" !CDS_LOCATION = "C7W10" #SEC = "1" !CDS_SEC = "1";
"1":   PN = "1"  !CDS_PN = "1";
"2":   PN = "2"  !CDS_PN = "2";
BODY = "CAP","I308": #LOCATION = "C5A20" !CDS_LOCATION = "C5A20" #SEC = "1" !CDS_SEC = "1";
"A":   PN = "1"  !CDS_PN = "1";
"B":   PN = "2"  !CDS_PN = "2";
BODY = "CAP","I309": #LOCATION = "C5L1" !CDS_LOCATION = "C5L1" #SEC = "1" !CDS_SEC = "1";
"A":   PN = "1"  !CDS_PN = "1";
"B":   PN = "2"  !CDS_PN = "2";
BODY = "CAP","I310": #LOCATION = "C5L3" !CDS_LOCATION = "C5L3" #SEC = "1" !CDS_SEC = "1";
"A":   PN = "1"  !CDS_PN = "1";
"B":   PN = "2"  !CDS_PN = "2";
BODY = "CAP","I311": #LOCATION = "C5L2" !CDS_LOCATION = "C5L2" &SEC = "1" #&CDS_SEC = "1";
"A":   PN = "1"  !CDS_PN = "1";
"B":   PN = "2"  !CDS_PN = "2";
BODY = "CAP","I312": #LOCATION = "C5M12" !CDS_LOCATION = "C5M12" #SEC = "1" !CDS_SEC = "1";
"A":   PN = "1"  !CDS_PN = "1";
"B":   PN = "2"  !CDS_PN = "2";
BODY = "CAP","I313": #LOCATION = "C5L14" !CDS_LOCATION = "C5L14" #SEC = "1" !CDS_SEC = "1";
"A":   PN = "1"  !CDS_PN = "1";
"B":   PN = "2"  !CDS_PN = "2";
BODY = "CAP","I314": #LOCATION = "C5M8" !CDS_LOCATION = "C5M8" #SEC = "1" !CDS_SEC = "1";
"A":   PN = "1"  !CDS_PN = "1";
"B":   PN = "2"  !CDS_PN = "2";
BODY = "CAP","I315": #LOCATION = "C5P3" !CDS_LOCATION = "C5P3" #SEC = "1" !CDS_SEC = "1";
"A":   PN = "1"  !CDS_PN = "1";
"B":   PN = "2"  !CDS_PN = "2";
BODY = "CAP","I316": #LOCATION = "C5P6" !CDS_LOCATION = "C5P6" #SEC = "1" !CDS_SEC = "1";
"A":   PN = "1"  !CDS_PN = "1";
"B":   PN = "2"  !CDS_PN = "2";
BODY = "CAP","I317": #LOCATION = "C5P5" !CDS_LOCATION = "C5P5" #SEC = "1" !CDS_SEC = "1";
"A":   PN = "1"  !CDS_PN = "1";
"B":   PN = "2"  !CDS_PN = "2";
BODY = "CAP","I318": #LOCATION = "C5P4" !CDS_LOCATION = "C5P4" #SEC = "1" !CDS_SEC = "1";
"A":   PN = "1"  !CDS_PN = "1";
"B":   PN = "2"  !CDS_PN = "2";
BODY = "CAP","I319": #LOCATION = "C5P2" !CDS_LOCATION = "C5P2" #SEC = "1" !CDS_SEC = "1";
"A":   PN = "1"  !CDS_PN = "1";
"B":   PN = "2"  !CDS_PN = "2";
BODY = "CAP","I320": #LOCATION = "C5P1" !CDS_LOCATION = "C5P1" #SEC = "1" !CDS_SEC = "1";
"A":   PN = "1"  !CDS_PN = "1";
"B":   PN = "2"  !CDS_PN = "2";
BODY = "CAP","I321": #LOCATION = "C5A10" !CDS_LOCATION = "C5A10" #SEC = "1" !CDS_SEC = "1";
"A":   PN = "1"  !CDS_PN = "1";
"B":   PN = "2"  !CDS_PN = "2";
BODY = "SE100U16VM-48-GP","I324": #LOCATION = "C7W2" !CDS_LOCATION = "C7W2" #SEC = "1" !CDS_SEC = "1";
"1":   PN = "1"  !CDS_PN = "1";
"2":   PN = "2"  !CDS_PN = "2";
DRAWING = "@baseboard_fab2_lib.baseboard_fab2(sch_1):page221";
BODY = "CAP","I22": #LOCATION = "C4G16" !CDS_LOCATION = "C4G16" #SEC = "1" !CDS_SEC = "1";
"A":   PN = "1"  !CDS_PN = "1";
"B":   PN = "2"  !CDS_PN = "2";
BODY = "CAP","I24": #LOCATION = "C4G24" !CDS_LOCATION = "C4G24" #SEC = "1" !CDS_SEC = "1";
"A":   PN = "1"  !CDS_PN = "1";
"B":   PN = "2"  !CDS_PN = "2";
BODY = "CAP","I2": #LOCATION = "C4G23" !CDS_LOCATION = "C4G23" #SEC = "1" !CDS_SEC = "1";
"A":   PN = "1"  !CDS_PN = "1";
"B":   PN = "2"  !CDS_PN = "2";
BODY = "RES","I4": #LOCATION = "R4G23" !CDS_LOCATION = "R4G23" #SEC = "1" !CDS_SEC = "1";
"A":   PN = "1"  !CDS_PN = "1";
"B":   PN = "2"  !CDS_PN = "2";
BODY = "RES","I5": #LOCATION = "R6U15" !CDS_LOCATION = "R6U15" #SEC = "1" !CDS_SEC = "1";
"A":   PN = "1"  !CDS_PN = "1";
"B":   PN = "2"  !CDS_PN = "2";
BODY = "RES","I6": #LOCATION = "R6U5" !CDS_LOCATION = "R6U5" #SEC = "1" !CDS_SEC = "1";
"A":   PN = "1"  !CDS_PN = "1";
"B":   PN = "2"  !CDS_PN = "2";
BODY = "SHUNT","I9": #LOCATION = "SH5U1" !CDS_LOCATION = "SH5U1" #SEC = "1" !CDS_SEC = "1";
"A":   PN = "1"  !CDS_PN = "1";
"B":   PN = "2"  !CDS_PN = "2";
BODY = "CAP","I11": #LOCATION = "C6U12" !CDS_LOCATION = "C6U12" #SEC = "1" !CDS_SEC = "1";
"A":   PN = "1"  !CDS_PN = "1";
"B":   PN = "2"  !CDS_PN = "2";
BODY = "CAP","I13": #LOCATION = "C4G15" !CDS_LOCATION = "C4G15" &SEC = "1" #&CDS_SEC = "1";
"A":   PN = "1"  !CDS_PN = "1";
"B":   PN = "2"  !CDS_PN = "2";
BODY = "RES","I14": #LOCATION = "R6U4" !CDS_LOCATION = "R6U4" #SEC = "1" !CDS_SEC = "1";
"A":   PN = "1"  !CDS_PN = "1";
"B":   PN = "2"  !CDS_PN = "2";
BODY = "CAP","I18": #LOCATION = "C6U15" !CDS_LOCATION = "C6U15" #SEC = "1" !CDS_SEC = "1";
"A":   PN = "1"  !CDS_PN = "1";
"B":   PN = "2"  !CDS_PN = "2";
BODY = "CAP","I19": #LOCATION = "C6U16" !CDS_LOCATION = "C6U16" #SEC = "1" !CDS_SEC = "1";
"A":   PN = "1"  !CDS_PN = "1";
"B":   PN = "2"  !CDS_PN = "2";
BODY = "RES","I25": #LOCATION = "R4G18" !CDS_LOCATION = "R4G18" #SEC = "1" !CDS_SEC = "1";
"A":   PN = "1"  !CDS_PN = "1";
"B":   PN = "2"  !CDS_PN = "2";
BODY = "CAP","I30": #LOCATION = "C4G14" !CDS_LOCATION = "C4G14" #SEC = "1" !CDS_SEC = "1";
"A":   PN = "1"  !CDS_PN = "1";
"B":   PN = "2"  !CDS_PN = "2";
BODY = "RES","I33": #LOCATION = "R4G19" !CDS_LOCATION = "R4G19" #SEC = "1" !CDS_SEC = "1";
"A":   PN = "1"  !CDS_PN = "1";
"B":   PN = "2"  !CDS_PN = "2";
BODY = "MIC5166","I15": #LOCATION = "EU4G3" !CDS_LOCATION = "EU4G3" #SEC = "1" !CDS_SEC = "1";
"AGND":   PN = "3"  !CDS_PN = "3";
"BIAS":   PN = "2"  !CDS_PN = "2";
"EN":   PN = "7"  !CDS_PN = "7";
"PG":   PN = "5"  !CDS_PN = "5";
"PGND":   PN = "8"  !CDS_PN = "8";
"SNS":   PN = "6"  !CDS_PN = "6";
"THPAD":   PN = "11"  !CDS_PN = "11";
"VDDQ":   PN = "4"  !CDS_PN = "4";
"VIN":   PN = "10"  !CDS_PN = "10";
"VREF":   PN = "1"  !CDS_PN = "1";
"VTT":   PN = "9"  !CDS_PN = "9";
BODY = "CAP_A","I40": #LOCATION = "C5T3" !CDS_LOCATION = "C5T3" #SEC = "1" !CDS_SEC = "1";
"A":   PN = "1"  !CDS_PN = "1";
"B":   PN = "2"  !CDS_PN = "2";
BODY = "CAP","I44": #LOCATION = "C6W11" !CDS_LOCATION = "C6W11" #SEC = "1" !CDS_SEC = "1";
"A":   PN = "1"  !CDS_PN = "1";
"B":   PN = "2"  !CDS_PN = "2";
BODY = "CAP","I45": #LOCATION = "C5U12" !CDS_LOCATION = "C5U12" #SEC = "1" !CDS_SEC = "1";
"A":   PN = "1"  !CDS_PN = "1";
"B":   PN = "2"  !CDS_PN = "2";
BODY = "CAP","I46": #LOCATION = "C5U16" !CDS_LOCATION = "C5U16" #SEC = "1" !CDS_SEC = "1";
"A":   PN = "1"  !CDS_PN = "1";
"B":   PN = "2"  !CDS_PN = "2";
DRAWING = "@baseboard_fab2_lib.baseboard_fab2(sch_1):page222";
BODY = "CAP","I12": #LOCATION = "C4A10" !CDS_LOCATION = "C4A10" #SEC = "1" !CDS_SEC = "1";
"A":   PN = "1"  !CDS_PN = "1";
"B":   PN = "2"  !CDS_PN = "2";
BODY = "CAP","I28": #LOCATION = "C4A1" !CDS_LOCATION = "C4A1" #SEC = "1" !CDS_SEC = "1";
"A":   PN = "1"  !CDS_PN = "1";
"B":   PN = "2"  !CDS_PN = "2";
BODY = "CAP","I2": #LOCATION = "C4A2" !CDS_LOCATION = "C4A2" #SEC = "1" !CDS_SEC = "1";
"A":   PN = "1"  !CDS_PN = "1";
"B":   PN = "2"  !CDS_PN = "2";
BODY = "RES","I4": #LOCATION = "R4A2" !CDS_LOCATION = "R4A2" #SEC = "1" !CDS_SEC = "1";
"A":   PN = "1"  !CDS_PN = "1";
"B":   PN = "2"  !CDS_PN = "2";
BODY = "RES","I5": #LOCATION = "R6L4" !CDS_LOCATION = "R6L4" #SEC = "1" !CDS_SEC = "1";
"A":   PN = "1"  !CDS_PN = "1";
"B":   PN = "2"  !CDS_PN = "2";
BODY = "RES","I6": #LOCATION = "R6L10" !CDS_LOCATION = "R6L10" #SEC = "1" !CDS_SEC = "1";
"A":   PN = "1"  !CDS_PN = "1";
"B":   PN = "2"  !CDS_PN = "2";
BODY = "CAP","I9": #LOCATION = "C4A11" !CDS_LOCATION = "C4A11" #SEC = "1" !CDS_SEC = "1";
"A":   PN = "1"  !CDS_PN = "1";
"B":   PN = "2"  !CDS_PN = "2";
BODY = "RES","I10": #LOCATION = "R6L11" !CDS_LOCATION = "R6L11" #SEC = "1" !CDS_SEC = "1";
"A":   PN = "1"  !CDS_PN = "1";
"B":   PN = "2"  !CDS_PN = "2";
BODY = "MIC5166","I13": #LOCATION = "EU4A1" !CDS_LOCATION = "EU4A1" #SEC = "1" !CDS_SEC = "1";
"AGND":   PN = "3"  !CDS_PN = "3";
"BIAS":   PN = "2"  !CDS_PN = "2";
"EN":   PN = "7"  !CDS_PN = "7";
"PG":   PN = "5"  !CDS_PN = "5";
"PGND":   PN = "8"  !CDS_PN = "8";
"SNS":   PN = "6"  !CDS_PN = "6";
"THPAD":   PN = "11"  !CDS_PN = "11";
"VDDQ":   PN = "4"  !CDS_PN = "4";
"VIN":   PN = "10"  !CDS_PN = "10";
"VREF":   PN = "1"  !CDS_PN = "1";
"VTT":   PN = "9"  !CDS_PN = "9";
BODY = "CAP","I15": #LOCATION = "C6L4" !CDS_LOCATION = "C6L4" #SEC = "1" !CDS_SEC = "1";
"A":   PN = "1"  !CDS_PN = "1";
"B":   PN = "2"  !CDS_PN = "2";
BODY = "CAP","I17": #LOCATION = "C6L3" !CDS_LOCATION = "C6L3" #SEC = "1" !CDS_SEC = "1";
"A":   PN = "1"  !CDS_PN = "1";
"B":   PN = "2"  !CDS_PN = "2";
BODY = "CAP","I20": #LOCATION = "C4A9" !CDS_LOCATION = "C4A9" #SEC = "1" !CDS_SEC = "1";
"A":   PN = "1"  !CDS_PN = "1";
"B":   PN = "2"  !CDS_PN = "2";
BODY = "CAP","I22": #LOCATION = "C4A12" !CDS_LOCATION = "C4A12" #SEC = "1" !CDS_SEC = "1";
"A":   PN = "1"  !CDS_PN = "1";
"B":   PN = "2"  !CDS_PN = "2";
BODY = "RES","I23": #LOCATION = "R6L9" !CDS_LOCATION = "R6L9" #SEC = "1" !CDS_SEC = "1";
"A":   PN = "1"  !CDS_PN = "1";
"B":   PN = "2"  !CDS_PN = "2";
BODY = "SHUNT","I30": #LOCATION = "SH5L1" !CDS_LOCATION = "SH5L1" #SEC = "1" !CDS_SEC = "1";
"A":   PN = "1"  !CDS_PN = "1";
"B":   PN = "2"  !CDS_PN = "2";
BODY = "RES","I31": #LOCATION = "R4A6" !CDS_LOCATION = "R4A6" #SEC = "1" !CDS_SEC = "1";
"A":   PN = "1"  !CDS_PN = "1";
"B":   PN = "2"  !CDS_PN = "2";
BODY = "CAP_A","I41": #LOCATION = "C5M13" !CDS_LOCATION = "C5M13" #SEC = "1" !CDS_SEC = "1";
"A":   PN = "1"  !CDS_PN = "1";
"B":   PN = "2"  !CDS_PN = "2";
BODY = "CAP","I44": #LOCATION = "C5L5" !CDS_LOCATION = "C5L5" #SEC = "1" !CDS_SEC = "1";
"A":   PN = "1"  !CDS_PN = "1";
"B":   PN = "2"  !CDS_PN = "2";
BODY = "CAP","I45": #LOCATION = "C5L4" !CDS_LOCATION = "C5L4" #SEC = "1" !CDS_SEC = "1";
"A":   PN = "1"  !CDS_PN = "1";
"B":   PN = "2"  !CDS_PN = "2";
BODY = "CAP","I46": #LOCATION = "C4W5" !CDS_LOCATION = "C4W5" #SEC = "1" !CDS_SEC = "1";
"A":   PN = "1"  !CDS_PN = "1";
"B":   PN = "2"  !CDS_PN = "2";
DRAWING = "@baseboard_fab2_lib.baseboard_fab2(sch_1):page223";
BODY = "RES","I14": #LOCATION = "R9U7" !CDS_LOCATION = "R9U7" #SEC = "1" !CDS_SEC = "1";
"A":   PN = "1"  !CDS_PN = "1";
"B":   PN = "2"  !CDS_PN = "2";
BODY = "RES","I16": #LOCATION = "RF19" !CDS_LOCATION = "RF19" #SEC = "1" !CDS_SEC = "1";
"A":   PN = "1"  !CDS_PN = "1";
"B":   PN = "2"  !CDS_PN = "2";
BODY = "CAP_A","I44": #LOCATION = "C1G23" !CDS_LOCATION = "C1G23" #SEC = "1" !CDS_SEC = "1";
"A":   PN = "1"  !CDS_PN = "1";
"B":   PN = "2"  !CDS_PN = "2";
BODY = "RES","I53": #LOCATION = "R12W33" !CDS_LOCATION = "R12W33" #SEC = "1" !CDS_SEC = "1";
"A":   PN = "1"  !CDS_PN = "1";
"B":   PN = "2"  !CDS_PN = "2";
BODY = "CAP","I12": #LOCATION = "C1G16" !CDS_LOCATION = "C1G16" #SEC = "1" !CDS_SEC = "1";
"A":   PN = "1"  !CDS_PN = "1";
"B":   PN = "2"  !CDS_PN = "2";
BODY = "SC22P50V2JN-4GP","I15": #LOCATION = "CF19" !CDS_LOCATION = "CF19" &SEC = "1" #&CDS_SEC = "1";
"1":   PN = "1"  !CDS_PN = "1";
"2":   PN = "2"  !CDS_PN = "2";
BODY = "RES","I18": #LOCATION = "R1G7" !CDS_LOCATION = "R1G7" #SEC = "1" !CDS_SEC = "1";
"A":   PN = "1"  !CDS_PN = "1";
"B":   PN = "2"  !CDS_PN = "2";
BODY = "RES","I19": #LOCATION = "RF20" !CDS_LOCATION = "RF20" #SEC = "1" !CDS_SEC = "1";
"A":   PN = "1"  !CDS_PN = "1";
"B":   PN = "2"  !CDS_PN = "2";
BODY = "RES","I31": #LOCATION = "R9U8" !CDS_LOCATION = "R9U8" #SEC = "1" !CDS_SEC = "1";
"A":   PN = "1"  !CDS_PN = "1";
"B":   PN = "2"  !CDS_PN = "2";
BODY = "CAP_A","I35": #LOCATION = "C1G25" !CDS_LOCATION = "C1G25" #SEC = "1" !CDS_SEC = "1";
"A":   PN = "1"  !CDS_PN = "1";
"B":   PN = "2"  !CDS_PN = "2";
BODY = "CAP","I40": #LOCATION = "C1G21" !CDS_LOCATION = "C1G21" #SEC = "1" !CDS_SEC = "1";
"A":   PN = "1"  !CDS_PN = "1";
"B":   PN = "2"  !CDS_PN = "2";
BODY = "CAP_A","I43": #LOCATION = "C1G22" !CDS_LOCATION = "C1G22" #SEC = "1" !CDS_SEC = "1";
"A":   PN = "1"  !CDS_PN = "1";
"B":   PN = "2"  !CDS_PN = "2";
BODY = "RES","I45": #LOCATION = "R12W32" !CDS_LOCATION = "R12W32" #SEC = "1" !CDS_SEC = "1";
"A":   PN = "1"  !CDS_PN = "1";
"B":   PN = "2"  !CDS_PN = "2";
BODY = "RES","I48": #LOCATION = "R1G16" !CDS_LOCATION = "R1G16" #SEC = "1" !CDS_SEC = "1";
"A":   PN = "1"  !CDS_PN = "1";
"B":   PN = "2"  !CDS_PN = "2";
BODY = "RES","I49": #LOCATION = "R1G11" !CDS_LOCATION = "R1G11" #SEC = "1" !CDS_SEC = "1";
"A":   PN = "1"  !CDS_PN = "1";
"B":   PN = "2"  !CDS_PN = "2";
BODY = "RES","I54": #LOCATION = "R1G12" !CDS_LOCATION = "R1G12" #SEC = "1" !CDS_SEC = "1";
"A":   PN = "1"  !CDS_PN = "1";
"B":   PN = "2"  !CDS_PN = "2";
BODY = "RES","I55": #LOCATION = "R1G8" !CDS_LOCATION = "R1G8" #SEC = "1" !CDS_SEC = "1";
"A":   PN = "1"  !CDS_PN = "1";
"B":   PN = "2"  !CDS_PN = "2";
BODY = "RES","I57": #LOCATION = "R9U3" !CDS_LOCATION = "R9U3" #SEC = "1" !CDS_SEC = "1";
"A":   PN = "1"  !CDS_PN = "1";
"B":   PN = "2"  !CDS_PN = "2";
BODY = "PXM1310B","I69": #LOCATION = "EU1G2" !CDS_LOCATION = "EU1G2" #SEC = "1" !CDS_SEC = "1";
"AIREF1":   PN = "21"  !CDS_PN = "21";
"AIREF2":   PN = "23"  !CDS_PN = "23";
"AIREF3":   PN = "25"  !CDS_PN = "25";
"AISEN1":   PN = "22"  !CDS_PN = "22";
"AISEN2":   PN = "24"  !CDS_PN = "24";
"AISEN3":   PN = "26"  !CDS_PN = "26";
"APWM1":   PN = "5"  !CDS_PN = "5";
"APWM2":   PN = "4"  !CDS_PN = "4";
"APWM3":   PN = "3"  !CDS_PN = "3";
"ATSEN":   PN = "35"  !CDS_PN = "35";
"AVREF":   PN = "20"  !CDS_PN = "20";
"AVREN":   PN = "10"  !CDS_PN = "10";
"AVRRDY":   PN = "9"  !CDS_PN = "9";
"AVSEN":   PN = "19"  !CDS_PN = "19";
"BIREF1":   PN = "31"  !CDS_PN = "31";
"BISEN1":   PN = "32"  !CDS_PN = "32";
"BPWM1":   PN = "1"  !CDS_PN = "1";
"BTSEN":   PN = "34"  !CDS_PN = "34";
"BVREF":   PN = "30"  !CDS_PN = "30";
"BVSEN":   PN = "29"  !CDS_PN = "29";
"DNC<0>":   PN = "2"  !CDS_PN = "2";
"DNC<1>":   PN = "28"  !CDS_PN = "28";
"GND":   PN = "27"  !CDS_PN = "27";
"IINSEN":   PN = "38"  !CDS_PN = "38";
"MP0":   PN = "13"  !CDS_PN = "13";
"MP1":   PN = "14"  !CDS_PN = "14";
"MP2":   PN = "18"  !CDS_PN = "18";
"PINALRT_N":   PN = "12"  !CDS_PN = "12";
"RESET_N":   PN = "8"  !CDS_PN = "8";
"SCL":   PN = "7"  !CDS_PN = "7";
"SDA":   PN = "6"  !CDS_PN = "6";
"THPAD":   PN = "41"  !CDS_PN = "41";
"VALRT_N":   PN = "17"  !CDS_PN = "17";
"VCLK":   PN = "15"  !CDS_PN = "15";
"VD12":   PN = "40"  !CDS_PN = "40";
"VDD":   PN = "39"  !CDS_PN = "39";
"VDIO":   PN = "16"  !CDS_PN = "16";
"VINSEN":   PN = "37"  !CDS_PN = "37";
"VRHOT_N":   PN = "11"  !CDS_PN = "11";
"XADDR1":   PN = "36"  !CDS_PN = "36";
"XADDR2":   PN = "33"  !CDS_PN = "33";
BODY = "RES","I13": #LOCATION = "R1G5" !CDS_LOCATION = "R1G5" #SEC = "1" !CDS_SEC = "1";
"A":   PN = "1"  !CDS_PN = "1";
"B":   PN = "2"  !CDS_PN = "2";
BODY = "SC22P50V2JN-4GP","I17": #LOCATION = "CF20" !CDS_LOCATION = "CF20" &SEC = "1" #&CDS_SEC = "1";
"1":   PN = "1"  !CDS_PN = "1";
"2":   PN = "2"  !CDS_PN = "2";
BODY = "CAP","I27": #LOCATION = "C1G24" !CDS_LOCATION = "C1G24" #SEC = "1" !CDS_SEC = "1";
"A":   PN = "1"  !CDS_PN = "1";
"B":   PN = "2"  !CDS_PN = "2";
BODY = "RES","I32": #LOCATION = "R9U10" !CDS_LOCATION = "R9U10" #SEC = "1" !CDS_SEC = "1";
"A":   PN = "1"  !CDS_PN = "1";
"B":   PN = "2"  !CDS_PN = "2";
BODY = "CAP_A","I36": #LOCATION = "C1G27" !CDS_LOCATION = "C1G27" #SEC = "1" !CDS_SEC = "1";
"A":   PN = "1"  !CDS_PN = "1";
"B":   PN = "2"  !CDS_PN = "2";
BODY = "RES","I41": #LOCATION = "R1G10" !CDS_LOCATION = "R1G10" #SEC = "1" !CDS_SEC = "1";
"A":   PN = "1"  !CDS_PN = "1";
"B":   PN = "2"  !CDS_PN = "2";
BODY = "RES","I50": #LOCATION = "R1G9" !CDS_LOCATION = "R1G9" #SEC = "1" !CDS_SEC = "1";
"A":   PN = "1"  !CDS_PN = "1";
"B":   PN = "2"  !CDS_PN = "2";
BODY = "RES","I70": #LOCATION = "R9U4" !CDS_LOCATION = "R9U4" #SEC = "1" !CDS_SEC = "1";
"A":   PN = "1"  !CDS_PN = "1";
"B":   PN = "2"  !CDS_PN = "2";
BODY = "RES","I73": #LOCATION = "R1G23" !CDS_LOCATION = "R1G23" #SEC = "1" !CDS_SEC = "1";
"A":   PN = "1"  !CDS_PN = "1";
"B":   PN = "2"  !CDS_PN = "2";
BODY = "RES","I74": #LOCATION = "R1G22" !CDS_LOCATION = "R1G22" #SEC = "1" !CDS_SEC = "1";
"A":   PN = "1"  !CDS_PN = "1";
"B":   PN = "2"  !CDS_PN = "2";
BODY = "RES","I75": #LOCATION = "R12W31" !CDS_LOCATION = "R12W31" #SEC = "1" !CDS_SEC = "1";
"A":   PN = "1"  !CDS_PN = "1";
"B":   PN = "2"  !CDS_PN = "2";
BODY = "RES","I76": #LOCATION = "R1G6" !CDS_LOCATION = "R1G6" #SEC = "1" !CDS_SEC = "1";
"A":   PN = "1"  !CDS_PN = "1";
"B":   PN = "2"  !CDS_PN = "2";
DRAWING = "@baseboard_fab2_lib.baseboard_fab2(sch_1):page224";
BODY = "CAP","I6": #LOCATION = "C1G17" !CDS_LOCATION = "C1G17" #SEC = "1" !CDS_SEC = "1";
"A":   PN = "1"  !CDS_PN = "1";
"B":   PN = "2"  !CDS_PN = "2";
BODY = "CAP","I44": #LOCATION = "C1G11" !CDS_LOCATION = "C1G11" #SEC = "1" !CDS_SEC = "1";
"A":   PN = "1"  !CDS_PN = "1";
"B":   PN = "2"  !CDS_PN = "2";
BODY = "CAP","I45": #LOCATION = "C9U6" !CDS_LOCATION = "C9U6" #SEC = "1" !CDS_SEC = "1";
"A":   PN = "1"  !CDS_PN = "1";
"B":   PN = "2"  !CDS_PN = "2";
BODY = "CAP","I46": #LOCATION = "C9U4" !CDS_LOCATION = "C9U4" #SEC = "1" !CDS_SEC = "1";
"A":   PN = "1"  !CDS_PN = "1";
"B":   PN = "2"  !CDS_PN = "2";
BODY = "CAP","I47": #LOCATION = "C9T4" !CDS_LOCATION = "C9T4" #SEC = "1" !CDS_SEC = "1";
"A":   PN = "1"  !CDS_PN = "1";
"B":   PN = "2"  !CDS_PN = "2";
BODY = "CAP","I48": #LOCATION = "C1F27" !CDS_LOCATION = "C1F27" #SEC = "1" !CDS_SEC = "1";
"A":   PN = "1"  !CDS_PN = "1";
"B":   PN = "2"  !CDS_PN = "2";
BODY = "CAP","I50": #LOCATION = "C1G6" !CDS_LOCATION = "C1G6" #SEC = "1" !CDS_SEC = "1";
"A":   PN = "1"  !CDS_PN = "1";
"B":   PN = "2"  !CDS_PN = "2";
BODY = "CAP_A","I51": #LOCATION = "C1G14" !CDS_LOCATION = "C1G14" #SEC = "1" !CDS_SEC = "1";
"A":   PN = "1"  !CDS_PN = "1";
"B":   PN = "2"  !CDS_PN = "2";
BODY = "CAP","I54": #LOCATION = "C1G5" !CDS_LOCATION = "C1G5" #SEC = "1" !CDS_SEC = "1";
"A":   PN = "1"  !CDS_PN = "1";
"B":   PN = "2"  !CDS_PN = "2";
BODY = "CAP","I68": #LOCATION = "C1G20" !CDS_LOCATION = "C1G20" #SEC = "1" !CDS_SEC = "1";
"A":   PN = "1"  !CDS_PN = "1";
"B":   PN = "2"  !CDS_PN = "2";
BODY = "CAP","I72": #LOCATION = "C1G29" !CDS_LOCATION = "C1G29" #SEC = "1" !CDS_SEC = "1";
"A":   PN = "1"  !CDS_PN = "1";
"B":   PN = "2"  !CDS_PN = "2";
BODY = "CAP","I75": #LOCATION = "C1F26" !CDS_LOCATION = "C1F26" #SEC = "1" !CDS_SEC = "1";
"A":   PN = "1"  !CDS_PN = "1";
"B":   PN = "2"  !CDS_PN = "2";
BODY = "CAP","I77": #LOCATION = "C1G28" !CDS_LOCATION = "C1G28" #SEC = "1" !CDS_SEC = "1";
"A":   PN = "1"  !CDS_PN = "1";
"B":   PN = "2"  !CDS_PN = "2";
BODY = "CAP_A","I78": #LOCATION = "C1F28" !CDS_LOCATION = "C1F28" #SEC = "1" !CDS_SEC = "1";
"A":   PN = "1"  !CDS_PN = "1";
"B":   PN = "2"  !CDS_PN = "2";
BODY = "CAP","I79": #LOCATION = "C1G13" !CDS_LOCATION = "C1G13" #SEC = "1" !CDS_SEC = "1";
"A":   PN = "1"  !CDS_PN = "1";
"B":   PN = "2"  !CDS_PN = "2";
BODY = "CAP","I80": #LOCATION = "C9U3" !CDS_LOCATION = "C9U3" #SEC = "1" !CDS_SEC = "1";
"A":   PN = "1"  !CDS_PN = "1";
"B":   PN = "2"  !CDS_PN = "2";
BODY = "CAP","I81": #LOCATION = "C9T6" !CDS_LOCATION = "C9T6" #SEC = "1" !CDS_SEC = "1";
"A":   PN = "1"  !CDS_PN = "1";
"B":   PN = "2"  !CDS_PN = "2";
BODY = "CAP","I84": #LOCATION = "C9T9" !CDS_LOCATION = "C9T9" #SEC = "1" !CDS_SEC = "1";
"A":   PN = "1"  !CDS_PN = "1";
"B":   PN = "2"  !CDS_PN = "2";
BODY = "IR354XX","I110": #LOCATION = "EU1G1" !CDS_LOCATION = "EU1G1" #SEC = "1" !CDS_SEC = "1";
"BOOST":   PN = "33"  !CDS_PN = "33";
"EN":   PN = "35"  !CDS_PN = "35";
"GL<0>":   PN = "6"  !CDS_PN = "6";
"GL<1>":   PN = "41"  !CDS_PN = "41";
"IOUT":   PN = "38"  !CDS_PN = "38";
"LGND":   PN = "2"  !CDS_PN = "2";
"NC":   PN = "31"  !CDS_PN = "31";
"OCSET":   PN = "37"  !CDS_PN = "37";
"PGND<0>":   PN = "5"  !CDS_PN = "5";
"PGND<1>":   PN = "7"  !CDS_PN = "7";
"PGND<2>":   PN = "40"  !CDS_PN = "40";
"PHASE":   PN = "32"  !CDS_PN = "32";
"PWM":   PN = "34"  !CDS_PN = "34";
"REFIN":   PN = "39"  !CDS_PN = "39";
"SW":   PN = "10"  !CDS_PN = "10";
"TOUT_FLT":   PN = "36"  !CDS_PN = "36";
"VCC":   PN = "3"  !CDS_PN = "3";
"VDRV":   PN = "4"  !CDS_PN = "4";
"VIN<0>":   PN = "25"  !CDS_PN = "25";
"VIN<1>":   PN = "30"  !CDS_PN = "30";
"VOS":   PN = "1"  !CDS_PN = "1";
BODY = "IR354XX","I111": #LOCATION = "EU1F1" !CDS_LOCATION = "EU1F1" #SEC = "1" !CDS_SEC = "1";
"BOOST":   PN = "33"  !CDS_PN = "33";
"EN":   PN = "35"  !CDS_PN = "35";
"GL<0>":   PN = "6"  !CDS_PN = "6";
"GL<1>":   PN = "41"  !CDS_PN = "41";
"IOUT":   PN = "38"  !CDS_PN = "38";
"LGND":   PN = "2"  !CDS_PN = "2";
"NC":   PN = "31"  !CDS_PN = "31";
"OCSET":   PN = "37"  !CDS_PN = "37";
"PGND<0>":   PN = "5"  !CDS_PN = "5";
"PGND<1>":   PN = "7"  !CDS_PN = "7";
"PGND<2>":   PN = "40"  !CDS_PN = "40";
"PHASE":   PN = "32"  !CDS_PN = "32";
"PWM":   PN = "34"  !CDS_PN = "34";
"REFIN":   PN = "39"  !CDS_PN = "39";
"SW":   PN = "10"  !CDS_PN = "10";
"TOUT_FLT":   PN = "36"  !CDS_PN = "36";
"VCC":   PN = "3"  !CDS_PN = "3";
"VDRV":   PN = "4"  !CDS_PN = "4";
"VIN<0>":   PN = "25"  !CDS_PN = "25";
"VIN<1>":   PN = "30"  !CDS_PN = "30";
"VOS":   PN = "1"  !CDS_PN = "1";
BODY = "RES","I112": #LOCATION = "R1G26" !CDS_LOCATION = "R1G26" #SEC = "1" !CDS_SEC = "1";
"A":   PN = "1"  !CDS_PN = "1";
"B":   PN = "2"  !CDS_PN = "2";
BODY = "RES","I114": #LOCATION = "R1G25" !CDS_LOCATION = "R1G25" #SEC = "1" !CDS_SEC = "1";
"A":   PN = "1"  !CDS_PN = "1";
"B":   PN = "2"  !CDS_PN = "2";
BODY = "CAP_A","I117": #LOCATION = "CT30" !CDS_LOCATION = "CT30" #SEC = "1" !CDS_SEC = "1";
"A":   PN = "1"  !CDS_PN = "1";
"B":   PN = "2"  !CDS_PN = "2";
BODY = "CAP","I122": #LOCATION = "CT28" !CDS_LOCATION = "CT28" #SEC = "1" !CDS_SEC = "1";
"A":   PN = "1"  !CDS_PN = "1";
"B":   PN = "2"  !CDS_PN = "2";
BODY = "CAP_A","I124": #LOCATION = "CT31" !CDS_LOCATION = "CT31" #SEC = "1" !CDS_SEC = "1";
"A":   PN = "1"  !CDS_PN = "1";
"B":   PN = "2"  !CDS_PN = "2";
BODY = "CAP","I130": #LOCATION = "CT32" !CDS_LOCATION = "CT32" #SEC = "1" !CDS_SEC = "1";
"A":   PN = "1"  !CDS_PN = "1";
"B":   PN = "2"  !CDS_PN = "2";
BODY = "CAP","I140": #LOCATION = "CT29" !CDS_LOCATION = "CT29" #SEC = "1" !CDS_SEC = "1";
"A":   PN = "1"  !CDS_PN = "1";
"B":   PN = "2"  !CDS_PN = "2";
BODY = "CAP","I141": #LOCATION = "CT33" !CDS_LOCATION = "CT33" #SEC = "1" !CDS_SEC = "1";
"A":   PN = "1"  !CDS_PN = "1";
"B":   PN = "2"  !CDS_PN = "2";
BODY = "RES","I144": #LOCATION = "RT19" !CDS_LOCATION = "RT19" #SEC = "1" !CDS_SEC = "1";
"A":   PN = "1"  !CDS_PN = "1";
"B":   PN = "2"  !CDS_PN = "2";
BODY = "RES","I145": #LOCATION = "RT21" !CDS_LOCATION = "RT21" #SEC = "1" !CDS_SEC = "1";
"A":   PN = "1"  !CDS_PN = "1";
"B":   PN = "2"  !CDS_PN = "2";
BODY = "RES","I150": #LOCATION = "R9U1" !CDS_LOCATION = "R9U1" #SEC = "1" !CDS_SEC = "1";
"A":   PN = "1"  !CDS_PN = "1";
"B":   PN = "2"  !CDS_PN = "2";
BODY = "RES","I151": #LOCATION = "R9U12" !CDS_LOCATION = "R9U12" #SEC = "1" !CDS_SEC = "1";
"A":   PN = "1"  !CDS_PN = "1";
"B":   PN = "2"  !CDS_PN = "2";
BODY = "SC1U10V2KX-4-GP","I154": #LOCATION = "C1F21" !CDS_LOCATION = "C1F21" #SEC = "1" !CDS_SEC = "1";
"1":   PN = "1"  !CDS_PN = "1";
"2":   PN = "2"  !CDS_PN = "2";
BODY = "SC1U10V2KX-4-GP","I155": #LOCATION = "C1G4" !CDS_LOCATION = "C1G4" #SEC = "1" !CDS_SEC = "1";
"1":   PN = "1"  !CDS_PN = "1";
"2":   PN = "2"  !CDS_PN = "2";
BODY = "1R3F-GP","I156": #LOCATION = "RT20" !CDS_LOCATION = "RT20" #SEC = "1" !CDS_SEC = "1";
"1":   PN = "1"  !CDS_PN = "1";
"2":   PN = "2"  !CDS_PN = "2";
BODY = "1R3F-GP","I157": #LOCATION = "RT22" !CDS_LOCATION = "RT22" #SEC = "1" !CDS_SEC = "1";
"1":   PN = "1"  !CDS_PN = "1";
"2":   PN = "2"  !CDS_PN = "2";
BODY = "IND-120NH-30-GP","I160": #LOCATION = "L1G1" !CDS_LOCATION = "L1G1" #SEC = "1" !CDS_SEC = "1";
"F":   PN = "2"  !CDS_PN = "2";
"S":   PN = "1"  !CDS_PN = "1";
BODY = "IND-120NH-30-GP","I161": #LOCATION = "L1F2" !CDS_LOCATION = "L1F2" #SEC = "1" !CDS_SEC = "1";
"F":   PN = "2"  !CDS_PN = "2";
"S":   PN = "1"  !CDS_PN = "1";
DRAWING = "@baseboard_fab2_lib.baseboard_fab2(sch_1):page225";
BODY = "RES","I58": #LOCATION = "R1G20" !CDS_LOCATION = "R1G20" &SEC = "1" #&CDS_SEC = "1";
"A":   PN = "1"  !CDS_PN = "1";
"B":   PN = "2"  !CDS_PN = "2";
BODY = "RES","I74": #LOCATION = "R7U2" !CDS_LOCATION = "R7U2" #SEC = "1" !CDS_SEC = "1";
"A":   PN = "1"  !CDS_PN = "1";
"B":   PN = "2"  !CDS_PN = "2";
BODY = "CAPP","I75": #LOCATION = "C9T5" !CDS_LOCATION = "C9T5" #SEC = "1" !CDS_SEC = "1";
"A":   PN = "1"  !CDS_PN = "1";
"B":   PN = "2"  !CDS_PN = "2";
BODY = "CAPP","I76": #LOCATION = "C9U2" !CDS_LOCATION = "C9U2" #SEC = "1" !CDS_SEC = "1";
"A":   PN = "1"  !CDS_PN = "1";
"B":   PN = "2"  !CDS_PN = "2";
BODY = "CAPP","I77": #LOCATION = "C9U9" !CDS_LOCATION = "C9U9" #SEC = "1" !CDS_SEC = "1";
"A":   PN = "1"  !CDS_PN = "1";
"B":   PN = "2"  !CDS_PN = "2";
BODY = "CAPP","I78": #LOCATION = "C9U5" !CDS_LOCATION = "C9U5" #SEC = "1" !CDS_SEC = "1";
"A":   PN = "1"  !CDS_PN = "1";
"B":   PN = "2"  !CDS_PN = "2";
BODY = "CAP_A","I196": #LOCATION = "C8T4" !CDS_LOCATION = "C8T4" #SEC = "1" !CDS_SEC = "1";
"A":   PN = "1"  !CDS_PN = "1";
"B":   PN = "2"  !CDS_PN = "2";
BODY = "CAP_A","I197": #LOCATION = "C2G8" !CDS_LOCATION = "C2G8" #SEC = "1" !CDS_SEC = "1";
"A":   PN = "1"  !CDS_PN = "1";
"B":   PN = "2"  !CDS_PN = "2";
BODY = "CAP_A","I198": #LOCATION = "C8T2" !CDS_LOCATION = "C8T2" #SEC = "1" !CDS_SEC = "1";
"A":   PN = "1"  !CDS_PN = "1";
"B":   PN = "2"  !CDS_PN = "2";
BODY = "CAP_A","I199": #LOCATION = "C8U13" !CDS_LOCATION = "C8U13" #SEC = "1" !CDS_SEC = "1";
"A":   PN = "1"  !CDS_PN = "1";
"B":   PN = "2"  !CDS_PN = "2";
BODY = "CAP_A","I200": #LOCATION = "C2G15" !CDS_LOCATION = "C2G15" #SEC = "1" !CDS_SEC = "1";
"A":   PN = "1"  !CDS_PN = "1";
"B":   PN = "2"  !CDS_PN = "2";
BODY = "CAP_A","I201": #LOCATION = "C2F1" !CDS_LOCATION = "C2F1" #SEC = "1" !CDS_SEC = "1";
"A":   PN = "1"  !CDS_PN = "1";
"B":   PN = "2"  !CDS_PN = "2";
BODY = "CAP_A","I202": #LOCATION = "C8T1" !CDS_LOCATION = "C8T1" #SEC = "1" !CDS_SEC = "1";
"A":   PN = "1"  !CDS_PN = "1";
"B":   PN = "2"  !CDS_PN = "2";
BODY = "CAP_A","I203": #LOCATION = "C8U9" !CDS_LOCATION = "C8U9" #SEC = "1" !CDS_SEC = "1";
"A":   PN = "1"  !CDS_PN = "1";
"B":   PN = "2"  !CDS_PN = "2";
BODY = "CAP_A","I204": #LOCATION = "C8T11" !CDS_LOCATION = "C8T11" #SEC = "1" !CDS_SEC = "1";
"A":   PN = "1"  !CDS_PN = "1";
"B":   PN = "2"  !CDS_PN = "2";
BODY = "SHUNT","I243": #LOCATION = "SH7U1" !CDS_LOCATION = "SH7U1" #SEC = "1" !CDS_SEC = "1";
"A":   PN = "1"  !CDS_PN = "1";
"B":   PN = "2"  !CDS_PN = "2";
BODY = "SHUNT","I244": #LOCATION = "SH7U2" !CDS_LOCATION = "SH7U2" #SEC = "1" !CDS_SEC = "1";
"A":   PN = "1"  !CDS_PN = "1";
"B":   PN = "2"  !CDS_PN = "2";
BODY = "SC22U16V5MX-4-GP","I246": #LOCATION = "C22W1" !CDS_LOCATION = "C22W1" #SEC = "1" !CDS_SEC = "1";
"1":   PN = "1"  !CDS_PN = "1";
"2":   PN = "2"  !CDS_PN = "2";
BODY = "SC22U16V5MX-4-GP","I247": #LOCATION = "C22W2" !CDS_LOCATION = "C22W2" #SEC = "1" !CDS_SEC = "1";
"1":   PN = "1"  !CDS_PN = "1";
"2":   PN = "2"  !CDS_PN = "2";
BODY = "SC22U16V5MX-4-GP","I249": #LOCATION = "C22W3" !CDS_LOCATION = "C22W3" #SEC = "1" !CDS_SEC = "1";
"1":   PN = "1"  !CDS_PN = "1";
"2":   PN = "2"  !CDS_PN = "2";
BODY = "SC22U16V5MX-4-GP","I250": #LOCATION = "C1G2" !CDS_LOCATION = "C1G2" #SEC = "1" !CDS_SEC = "1";
"1":   PN = "1"  !CDS_PN = "1";
"2":   PN = "2"  !CDS_PN = "2";
BODY = "SC22U16V5MX-4-GP","I251": #LOCATION = "C22W4" !CDS_LOCATION = "C22W4" #SEC = "1" !CDS_SEC = "1";
"1":   PN = "1"  !CDS_PN = "1";
"2":   PN = "2"  !CDS_PN = "2";
BODY = "IND-100NH-35-GP","I253": #LOCATION = "L1F1" !CDS_LOCATION = "L1F1" #SEC = "1" !CDS_SEC = "1";
"F":   PN = "2"  !CDS_PN = "2";
"S":   PN = "1"  !CDS_PN = "1";
BODY = "CAP_A","I261": #LOCATION = "C2D45" !CDS_LOCATION = "C2D45" &SEC = "1" #&CDS_SEC = "1";
"A":   PN = "1"  !CDS_PN = "1";
"B":   PN = "2"  !CDS_PN = "2";
BODY = "CAP_A","I262": #LOCATION = "C3D25" !CDS_LOCATION = "C3D25" #SEC = "1" !CDS_SEC = "1";
"A":   PN = "1"  !CDS_PN = "1";
"B":   PN = "2"  !CDS_PN = "2";
BODY = "CAP_A","I263": #LOCATION = "C2D47" !CDS_LOCATION = "C2D47" #SEC = "1" !CDS_SEC = "1";
"A":   PN = "1"  !CDS_PN = "1";
"B":   PN = "2"  !CDS_PN = "2";
BODY = "CAP_A","I264": #LOCATION = "C2D46" !CDS_LOCATION = "C2D46" #SEC = "1" !CDS_SEC = "1";
"A":   PN = "1"  !CDS_PN = "1";
"B":   PN = "2"  !CDS_PN = "2";
BODY = "CAP_A","I270": #LOCATION = "C2D43" !CDS_LOCATION = "C2D43" &SEC = "1" #&CDS_SEC = "1";
"A":   PN = "1"  !CDS_PN = "1";
"B":   PN = "2"  !CDS_PN = "2";
BODY = "CAP_A","I271": #LOCATION = "C2D41" !CDS_LOCATION = "C2D41" &SEC = "1" #&CDS_SEC = "1";
"A":   PN = "1"  !CDS_PN = "1";
"B":   PN = "2"  !CDS_PN = "2";
BODY = "CAP_A","I272": #LOCATION = "C2D44" !CDS_LOCATION = "C2D44" &SEC = "1" #&CDS_SEC = "1";
"A":   PN = "1"  !CDS_PN = "1";
"B":   PN = "2"  !CDS_PN = "2";
BODY = "CAP_A","I273": #LOCATION = "C2D42" !CDS_LOCATION = "C2D42" &SEC = "1" #&CDS_SEC = "1";
"A":   PN = "1"  !CDS_PN = "1";
"B":   PN = "2"  !CDS_PN = "2";
BODY = "CAP_A","I274": #LOCATION = "C2G10" !CDS_LOCATION = "C2G10" #SEC = "1" !CDS_SEC = "1";
"A":   PN = "1"  !CDS_PN = "1";
"B":   PN = "2"  !CDS_PN = "2";
BODY = "CAP_A","I275": #LOCATION = "C2G11" !CDS_LOCATION = "C2G11" #SEC = "1" !CDS_SEC = "1";
"A":   PN = "1"  !CDS_PN = "1";
"B":   PN = "2"  !CDS_PN = "2";
BODY = "CAP_A","I276": #LOCATION = "C2G12" !CDS_LOCATION = "C2G12" #SEC = "1" !CDS_SEC = "1";
"A":   PN = "1"  !CDS_PN = "1";
"B":   PN = "2"  !CDS_PN = "2";
BODY = "CAP_A","I277": #LOCATION = "C2G1" !CDS_LOCATION = "C2G1" #SEC = "1" !CDS_SEC = "1";
"A":   PN = "1"  !CDS_PN = "1";
"B":   PN = "2"  !CDS_PN = "2";
BODY = "CAP_A","I278": #LOCATION = "C2G9" !CDS_LOCATION = "C2G9" #SEC = "1" !CDS_SEC = "1";
"A":   PN = "1"  !CDS_PN = "1";
"B":   PN = "2"  !CDS_PN = "2";
BODY = "CAP_A","I279": #LOCATION = "C2G2" !CDS_LOCATION = "C2G2" #SEC = "1" !CDS_SEC = "1";
"A":   PN = "1"  !CDS_PN = "1";
"B":   PN = "2"  !CDS_PN = "2";
BODY = "CAP_A","I280": #LOCATION = "C2G3" !CDS_LOCATION = "C2G3" #SEC = "1" !CDS_SEC = "1";
"A":   PN = "1"  !CDS_PN = "1";
"B":   PN = "2"  !CDS_PN = "2";
BODY = "CAP_A","I281": #LOCATION = "C2G4" !CDS_LOCATION = "C2G4" #SEC = "1" !CDS_SEC = "1";
"A":   PN = "1"  !CDS_PN = "1";
"B":   PN = "2"  !CDS_PN = "2";
BODY = "CAP_A","I282": #LOCATION = "C2G5" !CDS_LOCATION = "C2G5" #SEC = "1" !CDS_SEC = "1";
"A":   PN = "1"  !CDS_PN = "1";
"B":   PN = "2"  !CDS_PN = "2";
BODY = "CAP_A","I283": #LOCATION = "C2G6" !CDS_LOCATION = "C2G6" #SEC = "1" !CDS_SEC = "1";
"A":   PN = "1"  !CDS_PN = "1";
"B":   PN = "2"  !CDS_PN = "2";
BODY = "CAP_A","I284": #LOCATION = "C3G1" !CDS_LOCATION = "C3G1" #SEC = "1" !CDS_SEC = "1";
"A":   PN = "1"  !CDS_PN = "1";
"B":   PN = "2"  !CDS_PN = "2";
BODY = "CAP_A","I285": #LOCATION = "C3G2" !CDS_LOCATION = "C3G2" #SEC = "1" !CDS_SEC = "1";
"A":   PN = "1"  !CDS_PN = "1";
"B":   PN = "2"  !CDS_PN = "2";
BODY = "CAP_A","I286": #LOCATION = "C2G13" !CDS_LOCATION = "C2G13" #SEC = "1" !CDS_SEC = "1";
"A":   PN = "1"  !CDS_PN = "1";
"B":   PN = "2"  !CDS_PN = "2";
BODY = "CAP_A","I287": #LOCATION = "C2G14" !CDS_LOCATION = "C2G14" #SEC = "1" !CDS_SEC = "1";
"A":   PN = "1"  !CDS_PN = "1";
"B":   PN = "2"  !CDS_PN = "2";
BODY = "CAP_A","I288": #LOCATION = "C3G5" !CDS_LOCATION = "C3G5" #SEC = "1" !CDS_SEC = "1";
"A":   PN = "1"  !CDS_PN = "1";
"B":   PN = "2"  !CDS_PN = "2";
BODY = "CAP_A","I289": #LOCATION = "C3G6" !CDS_LOCATION = "C3G6" #SEC = "1" !CDS_SEC = "1";
"A":   PN = "1"  !CDS_PN = "1";
"B":   PN = "2"  !CDS_PN = "2";
BODY = "CAP_A","I290": #LOCATION = "C8U7" !CDS_LOCATION = "C8U7" #SEC = "1" !CDS_SEC = "1";
"A":   PN = "1"  !CDS_PN = "1";
"B":   PN = "2"  !CDS_PN = "2";
BODY = "CAP_A","I291": #LOCATION = "C8U2" !CDS_LOCATION = "C8U2" #SEC = "1" !CDS_SEC = "1";
"A":   PN = "1"  !CDS_PN = "1";
"B":   PN = "2"  !CDS_PN = "2";
BODY = "CAP_A","I292": #LOCATION = "C7U2" !CDS_LOCATION = "C7U2" #SEC = "1" !CDS_SEC = "1";
"A":   PN = "1"  !CDS_PN = "1";
"B":   PN = "2"  !CDS_PN = "2";
BODY = "CAP_A","I293": #LOCATION = "C7U1" !CDS_LOCATION = "C7U1" #SEC = "1" !CDS_SEC = "1";
"A":   PN = "1"  !CDS_PN = "1";
"B":   PN = "2"  !CDS_PN = "2";
BODY = "CAP_A","I294": #LOCATION = "C8U3" !CDS_LOCATION = "C8U3" #SEC = "1" !CDS_SEC = "1";
"A":   PN = "1"  !CDS_PN = "1";
"B":   PN = "2"  !CDS_PN = "2";
BODY = "CAP_A","I295": #LOCATION = "C7T4" !CDS_LOCATION = "C7T4" #SEC = "1" !CDS_SEC = "1";
"A":   PN = "1"  !CDS_PN = "1";
"B":   PN = "2"  !CDS_PN = "2";
BODY = "CAP_A","I296": #LOCATION = "C7T5" !CDS_LOCATION = "C7T5" #SEC = "1" !CDS_SEC = "1";
"A":   PN = "1"  !CDS_PN = "1";
"B":   PN = "2"  !CDS_PN = "2";
BODY = "CAP_A","I297": #LOCATION = "C8T5" !CDS_LOCATION = "C8T5" #SEC = "1" !CDS_SEC = "1";
"A":   PN = "1"  !CDS_PN = "1";
"B":   PN = "2"  !CDS_PN = "2";
BODY = "CAP_A","I298": #LOCATION = "C8U6" !CDS_LOCATION = "C8U6" #SEC = "1" !CDS_SEC = "1";
"A":   PN = "1"  !CDS_PN = "1";
"B":   PN = "2"  !CDS_PN = "2";
BODY = "CAP_A","I299": #LOCATION = "C8T6" !CDS_LOCATION = "C8T6" #SEC = "1" !CDS_SEC = "1";
"A":   PN = "1"  !CDS_PN = "1";
"B":   PN = "2"  !CDS_PN = "2";
BODY = "CAP_A","I300": #LOCATION = "C8T7" !CDS_LOCATION = "C8T7" #SEC = "1" !CDS_SEC = "1";
"A":   PN = "1"  !CDS_PN = "1";
"B":   PN = "2"  !CDS_PN = "2";
BODY = "CAP_A","I301": #LOCATION = "C8T8" !CDS_LOCATION = "C8T8" #SEC = "1" !CDS_SEC = "1";
"A":   PN = "1"  !CDS_PN = "1";
"B":   PN = "2"  !CDS_PN = "2";
BODY = "CAP_A","I302": #LOCATION = "C8U5" !CDS_LOCATION = "C8U5" #SEC = "1" !CDS_SEC = "1";
"A":   PN = "1"  !CDS_PN = "1";
"B":   PN = "2"  !CDS_PN = "2";
BODY = "CAP_A","I303": #LOCATION = "C8T9" !CDS_LOCATION = "C8T9" #SEC = "1" !CDS_SEC = "1";
"A":   PN = "1"  !CDS_PN = "1";
"B":   PN = "2"  !CDS_PN = "2";
BODY = "CAP_A","I304": #LOCATION = "C8T10" !CDS_LOCATION = "C8T10" #SEC = "1" !CDS_SEC = "1";
"A":   PN = "1"  !CDS_PN = "1";
"B":   PN = "2"  !CDS_PN = "2";
BODY = "CAP_A","I305": #LOCATION = "C8U4" !CDS_LOCATION = "C8U4" #SEC = "1" !CDS_SEC = "1";
"A":   PN = "1"  !CDS_PN = "1";
"B":   PN = "2"  !CDS_PN = "2";
BODY = "CAP","I307": #LOCATION = "C8U11" !CDS_LOCATION = "C8U11" #SEC = "1" !CDS_SEC = "1";
"A":   PN = "1"  !CDS_PN = "1";
"B":   PN = "2"  !CDS_PN = "2";
BODY = "CAP","I308": #LOCATION = "C7U7" !CDS_LOCATION = "C7U7" #SEC = "1" !CDS_SEC = "1";
"A":   PN = "1"  !CDS_PN = "1";
"B":   PN = "2"  !CDS_PN = "2";
BODY = "CAP","I309": #LOCATION = "C7T1" !CDS_LOCATION = "C7T1" #SEC = "1" !CDS_SEC = "1";
"A":   PN = "1"  !CDS_PN = "1";
"B":   PN = "2"  !CDS_PN = "2";
BODY = "CAP","I310": #LOCATION = "C8U12" !CDS_LOCATION = "C8U12" #SEC = "1" !CDS_SEC = "1";
"A":   PN = "1"  !CDS_PN = "1";
"B":   PN = "2"  !CDS_PN = "2";
BODY = "CAP","I311": #LOCATION = "C2G16" !CDS_LOCATION = "C2G16" #SEC = "1" !CDS_SEC = "1";
"A":   PN = "1"  !CDS_PN = "1";
"B":   PN = "2"  !CDS_PN = "2";
BODY = "CAP","I312": #LOCATION = "C2G7" !CDS_LOCATION = "C2G7" #SEC = "1" !CDS_SEC = "1";
"A":   PN = "1"  !CDS_PN = "1";
"B":   PN = "2"  !CDS_PN = "2";
BODY = "CAP","I313": #LOCATION = "C8P30" !CDS_LOCATION = "C8P30" #SEC = "1" !CDS_SEC = "1";
"A":   PN = "1"  !CDS_PN = "1";
"B":   PN = "2"  !CDS_PN = "2";
BODY = "CAP","I314": #LOCATION = "C8P31" !CDS_LOCATION = "C8P31" #SEC = "1" !CDS_SEC = "1";
"A":   PN = "1"  !CDS_PN = "1";
"B":   PN = "2"  !CDS_PN = "2";
BODY = "CAP","I315": #LOCATION = "C8P34" !CDS_LOCATION = "C8P34" #SEC = "1" !CDS_SEC = "1";
"A":   PN = "1"  !CDS_PN = "1";
"B":   PN = "2"  !CDS_PN = "2";
BODY = "CAP","I316": #LOCATION = "C8P33" !CDS_LOCATION = "C8P33" #SEC = "1" !CDS_SEC = "1";
"A":   PN = "1"  !CDS_PN = "1";
"B":   PN = "2"  !CDS_PN = "2";
BODY = "CAP","I317": #LOCATION = "C8P32" !CDS_LOCATION = "C8P32" #SEC = "1" !CDS_SEC = "1";
"A":   PN = "1"  !CDS_PN = "1";
"B":   PN = "2"  !CDS_PN = "2";
BODY = "CAP","I318": #LOCATION = "C7P20" !CDS_LOCATION = "C7P20" #SEC = "1" !CDS_SEC = "1";
"A":   PN = "1"  !CDS_PN = "1";
"B":   PN = "2"  !CDS_PN = "2";
BODY = "CAP","I319": #LOCATION = "C8U1" !CDS_LOCATION = "C8U1" #SEC = "1" !CDS_SEC = "1";
"A":   PN = "1"  !CDS_PN = "1";
"B":   PN = "2"  !CDS_PN = "2";
BODY = "CAP","I320": #LOCATION = "C8U8" !CDS_LOCATION = "C8U8" #SEC = "1" !CDS_SEC = "1";
"A":   PN = "1"  !CDS_PN = "1";
"B":   PN = "2"  !CDS_PN = "2";
BODY = "ST270U2D5VBM-GP","I327": #LOCATION = "C1G15" !CDS_LOCATION = "C1G15" #SEC = "1" !CDS_SEC = "1";
"1":   PN = "1"  !CDS_PN = "1";
"2":   PN = "2"  !CDS_PN = "2";
BODY = "ST270U2D5VBM-GP","I328": #LOCATION = "C1G12" !CDS_LOCATION = "C1G12" #SEC = "1" !CDS_SEC = "1";
"1":   PN = "1"  !CDS_PN = "1";
"2":   PN = "2"  !CDS_PN = "2";
BODY = "ST270U2D5VBM-GP","I329": #LOCATION = "C1G7" !CDS_LOCATION = "C1G7" #SEC = "1" !CDS_SEC = "1";
"1":   PN = "1"  !CDS_PN = "1";
"2":   PN = "2"  !CDS_PN = "2";
DRAWING = "@baseboard_fab2_lib.baseboard_fab2(sch_1):page226";
BODY = "RES","I14": #LOCATION = "R9M9" !CDS_LOCATION = "R9M9" &SEC = "1" #&CDS_SEC = "1";
"A":   PN = "1"  !CDS_PN = "1";
"B":   PN = "2"  !CDS_PN = "2";
BODY = "RES","I16": #LOCATION = "RF21" !CDS_LOCATION = "RF21" #SEC = "1" !CDS_SEC = "1";
"A":   PN = "1"  !CDS_PN = "1";
"B":   PN = "2"  !CDS_PN = "2";
BODY = "CAP_A","I44": #LOCATION = "C1B2" !CDS_LOCATION = "C1B2" #SEC = "1" !CDS_SEC = "1";
"A":   PN = "1"  !CDS_PN = "1";
"B":   PN = "2"  !CDS_PN = "2";
BODY = "RES","I50": #LOCATION = "R1B2" !CDS_LOCATION = "R1B2" #SEC = "1" !CDS_SEC = "1";
"A":   PN = "1"  !CDS_PN = "1";
"B":   PN = "2"  !CDS_PN = "2";
BODY = "RES","I53": #LOCATION = "R12W36" !CDS_LOCATION = "R12W36" #SEC = "1" !CDS_SEC = "1";
"A":   PN = "1"  !CDS_PN = "1";
"B":   PN = "2"  !CDS_PN = "2";
BODY = "CAP","I12": #LOCATION = "C1B12" !CDS_LOCATION = "C1B12" #SEC = "1" !CDS_SEC = "1";
"A":   PN = "1"  !CDS_PN = "1";
"B":   PN = "2"  !CDS_PN = "2";
BODY = "SC22P50V2JN-4GP","I15": #LOCATION = "CF21" !CDS_LOCATION = "CF21" &SEC = "1" #&CDS_SEC = "1";
"1":   PN = "1"  !CDS_PN = "1";
"2":   PN = "2"  !CDS_PN = "2";
BODY = "RES","I18": #LOCATION = "RF22" !CDS_LOCATION = "RF22" #SEC = "1" !CDS_SEC = "1";
"A":   PN = "1"  !CDS_PN = "1";
"B":   PN = "2"  !CDS_PN = "2";
BODY = "RES","I19": #LOCATION = "R1B8" !CDS_LOCATION = "R1B8" #SEC = "1" !CDS_SEC = "1";
"A":   PN = "1"  !CDS_PN = "1";
"B":   PN = "2"  !CDS_PN = "2";
BODY = "RES","I34": #LOCATION = "R9M5" !CDS_LOCATION = "R9M5" #SEC = "1" !CDS_SEC = "1";
"A":   PN = "1"  !CDS_PN = "1";
"B":   PN = "2"  !CDS_PN = "2";
BODY = "CAP_A","I38": #LOCATION = "C1B6" !CDS_LOCATION = "C1B6" #SEC = "1" !CDS_SEC = "1";
"A":   PN = "1"  !CDS_PN = "1";
"B":   PN = "2"  !CDS_PN = "2";
BODY = "CAP","I40": #LOCATION = "C1B4" !CDS_LOCATION = "C1B4" #SEC = "1" !CDS_SEC = "1";
"A":   PN = "1"  !CDS_PN = "1";
"B":   PN = "2"  !CDS_PN = "2";
BODY = "CAP_A","I45": #LOCATION = "C1B3" !CDS_LOCATION = "C1B3" #SEC = "1" !CDS_SEC = "1";
"A":   PN = "1"  !CDS_PN = "1";
"B":   PN = "2"  !CDS_PN = "2";
BODY = "RES","I46": #LOCATION = "R12W35" !CDS_LOCATION = "R12W35" #SEC = "1" !CDS_SEC = "1";
"A":   PN = "1"  !CDS_PN = "1";
"B":   PN = "2"  !CDS_PN = "2";
BODY = "RES","I48": #LOCATION = "R1B11" !CDS_LOCATION = "R1B11" #SEC = "1" !CDS_SEC = "1";
"A":   PN = "1"  !CDS_PN = "1";
"B":   PN = "2"  !CDS_PN = "2";
BODY = "RES","I49": #LOCATION = "R1B1" !CDS_LOCATION = "R1B1" #SEC = "1" !CDS_SEC = "1";
"A":   PN = "1"  !CDS_PN = "1";
"B":   PN = "2"  !CDS_PN = "2";
BODY = "RES","I54": #LOCATION = "R1B4" !CDS_LOCATION = "R1B4" #SEC = "1" !CDS_SEC = "1";
"A":   PN = "1"  !CDS_PN = "1";
"B":   PN = "2"  !CDS_PN = "2";
BODY = "RES","I55": #LOCATION = "R1B5" !CDS_LOCATION = "R1B5" #SEC = "1" !CDS_SEC = "1";
"A":   PN = "1"  !CDS_PN = "1";
"B":   PN = "2"  !CDS_PN = "2";
BODY = "RES","I57": #LOCATION = "R9M7" !CDS_LOCATION = "R9M7" #SEC = "1" !CDS_SEC = "1";
"A":   PN = "1"  !CDS_PN = "1";
"B":   PN = "2"  !CDS_PN = "2";
BODY = "PXM1310B","I69": #LOCATION = "EU1B1" !CDS_LOCATION = "EU1B1" #SEC = "1" !CDS_SEC = "1";
"AIREF1":   PN = "21"  !CDS_PN = "21";
"AIREF2":   PN = "23"  !CDS_PN = "23";
"AIREF3":   PN = "25"  !CDS_PN = "25";
"AISEN1":   PN = "22"  !CDS_PN = "22";
"AISEN2":   PN = "24"  !CDS_PN = "24";
"AISEN3":   PN = "26"  !CDS_PN = "26";
"APWM1":   PN = "5"  !CDS_PN = "5";
"APWM2":   PN = "4"  !CDS_PN = "4";
"APWM3":   PN = "3"  !CDS_PN = "3";
"ATSEN":   PN = "35"  !CDS_PN = "35";
"AVREF":   PN = "20"  !CDS_PN = "20";
"AVREN":   PN = "10"  !CDS_PN = "10";
"AVRRDY":   PN = "9"  !CDS_PN = "9";
"AVSEN":   PN = "19"  !CDS_PN = "19";
"BIREF1":   PN = "31"  !CDS_PN = "31";
"BISEN1":   PN = "32"  !CDS_PN = "32";
"BPWM1":   PN = "1"  !CDS_PN = "1";
"BTSEN":   PN = "34"  !CDS_PN = "34";
"BVREF":   PN = "30"  !CDS_PN = "30";
"BVSEN":   PN = "29"  !CDS_PN = "29";
"DNC<0>":   PN = "2"  !CDS_PN = "2";
"DNC<1>":   PN = "28"  !CDS_PN = "28";
"GND":   PN = "27"  !CDS_PN = "27";
"IINSEN":   PN = "38"  !CDS_PN = "38";
"MP0":   PN = "13"  !CDS_PN = "13";
"MP1":   PN = "14"  !CDS_PN = "14";
"MP2":   PN = "18"  !CDS_PN = "18";
"PINALRT_N":   PN = "12"  !CDS_PN = "12";
"RESET_N":   PN = "8"  !CDS_PN = "8";
"SCL":   PN = "7"  !CDS_PN = "7";
"SDA":   PN = "6"  !CDS_PN = "6";
"THPAD":   PN = "41"  !CDS_PN = "41";
"VALRT_N":   PN = "17"  !CDS_PN = "17";
"VCLK":   PN = "15"  !CDS_PN = "15";
"VD12":   PN = "40"  !CDS_PN = "40";
"VDD":   PN = "39"  !CDS_PN = "39";
"VDIO":   PN = "16"  !CDS_PN = "16";
"VINSEN":   PN = "37"  !CDS_PN = "37";
"VRHOT_N":   PN = "11"  !CDS_PN = "11";
"XADDR1":   PN = "36"  !CDS_PN = "36";
"XADDR2":   PN = "33"  !CDS_PN = "33";
BODY = "RES","I13": #LOCATION = "R1B16" !CDS_LOCATION = "R1B16" #SEC = "1" !CDS_SEC = "1";
"A":   PN = "1"  !CDS_PN = "1";
"B":   PN = "2"  !CDS_PN = "2";
BODY = "SC22P50V2JN-4GP","I17": #LOCATION = "CF22" !CDS_LOCATION = "CF22" &SEC = "1" #&CDS_SEC = "1";
"1":   PN = "1"  !CDS_PN = "1";
"2":   PN = "2"  !CDS_PN = "2";
BODY = "CAP","I23": #LOCATION = "C1B11" !CDS_LOCATION = "C1B11" #SEC = "1" !CDS_SEC = "1";
"A":   PN = "1"  !CDS_PN = "1";
"B":   PN = "2"  !CDS_PN = "2";
BODY = "CAP_A","I32": #LOCATION = "C1B5" !CDS_LOCATION = "C1B5" #SEC = "1" !CDS_SEC = "1";
"A":   PN = "1"  !CDS_PN = "1";
"B":   PN = "2"  !CDS_PN = "2";
BODY = "RES","I36": #LOCATION = "R9M3" !CDS_LOCATION = "R9M3" #SEC = "1" !CDS_SEC = "1";
"A":   PN = "1"  !CDS_PN = "1";
"B":   PN = "2"  !CDS_PN = "2";
BODY = "RES","I41": #LOCATION = "R1B10" !CDS_LOCATION = "R1B10" #SEC = "1" !CDS_SEC = "1";
"A":   PN = "1"  !CDS_PN = "1";
"B":   PN = "2"  !CDS_PN = "2";
BODY = "RES","I70": #LOCATION = "R9M6" !CDS_LOCATION = "R9M6" #SEC = "1" !CDS_SEC = "1";
"A":   PN = "1"  !CDS_PN = "1";
"B":   PN = "2"  !CDS_PN = "2";
BODY = "RES","I72": #LOCATION = "R1B12" !CDS_LOCATION = "R1B12" &SEC = "1" #&CDS_SEC = "1";
"A":   PN = "1"  !CDS_PN = "1";
"B":   PN = "2"  !CDS_PN = "2";
BODY = "RES","I73": #LOCATION = "R1B15" !CDS_LOCATION = "R1B15" #SEC = "1" !CDS_SEC = "1";
"A":   PN = "1"  !CDS_PN = "1";
"B":   PN = "2"  !CDS_PN = "2";
BODY = "RES","I74": #LOCATION = "R12W34" !CDS_LOCATION = "R12W34" #SEC = "1" !CDS_SEC = "1";
"A":   PN = "1"  !CDS_PN = "1";
"B":   PN = "2"  !CDS_PN = "2";
BODY = "RES","I75": #LOCATION = "R1B13" !CDS_LOCATION = "R1B13" &SEC = "1" #&CDS_SEC = "1";
"A":   PN = "1"  !CDS_PN = "1";
"B":   PN = "2"  !CDS_PN = "2";
DRAWING = "@baseboard_fab2_lib.baseboard_fab2(sch_1):page227";
BODY = "CAP","I6": #LOCATION = "C1A12" !CDS_LOCATION = "C1A12" #SEC = "1" !CDS_SEC = "1";
"A":   PN = "1"  !CDS_PN = "1";
"B":   PN = "2"  !CDS_PN = "2";
BODY = "CAP","I44": #LOCATION = "C1A18" !CDS_LOCATION = "C1A18" #SEC = "1" !CDS_SEC = "1";
"A":   PN = "1"  !CDS_PN = "1";
"B":   PN = "2"  !CDS_PN = "2";
BODY = "CAP","I45": #LOCATION = "C9L11" !CDS_LOCATION = "C9L11" #SEC = "1" !CDS_SEC = "1";
"A":   PN = "1"  !CDS_PN = "1";
"B":   PN = "2"  !CDS_PN = "2";
BODY = "CAP","I46": #LOCATION = "C9L10" !CDS_LOCATION = "C9L10" #SEC = "1" !CDS_SEC = "1";
"A":   PN = "1"  !CDS_PN = "1";
"B":   PN = "2"  !CDS_PN = "2";
BODY = "CAP","I47": #LOCATION = "C9L6" !CDS_LOCATION = "C9L6" #SEC = "1" !CDS_SEC = "1";
"A":   PN = "1"  !CDS_PN = "1";
"B":   PN = "2"  !CDS_PN = "2";
BODY = "CAP","I48": #LOCATION = "C1A19" !CDS_LOCATION = "C1A19" #SEC = "1" !CDS_SEC = "1";
"A":   PN = "1"  !CDS_PN = "1";
"B":   PN = "2"  !CDS_PN = "2";
BODY = "CAP","I50": #LOCATION = "C1B20" !CDS_LOCATION = "C1B20" #SEC = "1" !CDS_SEC = "1";
"A":   PN = "1"  !CDS_PN = "1";
"B":   PN = "2"  !CDS_PN = "2";
BODY = "CAP_A","I51": #LOCATION = "C1A10" !CDS_LOCATION = "C1A10" #SEC = "1" !CDS_SEC = "1";
"A":   PN = "1"  !CDS_PN = "1";
"B":   PN = "2"  !CDS_PN = "2";
BODY = "CAP","I54": #LOCATION = "C1B21" !CDS_LOCATION = "C1B21" #SEC = "1" !CDS_SEC = "1";
"A":   PN = "1"  !CDS_PN = "1";
"B":   PN = "2"  !CDS_PN = "2";
BODY = "CAP","I68": #LOCATION = "C1A1" !CDS_LOCATION = "C1A1" #SEC = "1" !CDS_SEC = "1";
"A":   PN = "1"  !CDS_PN = "1";
"B":   PN = "2"  !CDS_PN = "2";
BODY = "CAP","I72": #LOCATION = "C1A13" !CDS_LOCATION = "C1A13" #SEC = "1" !CDS_SEC = "1";
"A":   PN = "1"  !CDS_PN = "1";
"B":   PN = "2"  !CDS_PN = "2";
BODY = "CAP","I75": #LOCATION = "C1A8" !CDS_LOCATION = "C1A8" #SEC = "1" !CDS_SEC = "1";
"A":   PN = "1"  !CDS_PN = "1";
"B":   PN = "2"  !CDS_PN = "2";
BODY = "CAP","I77": #LOCATION = "C1A6" !CDS_LOCATION = "C1A6" #SEC = "1" !CDS_SEC = "1";
"A":   PN = "1"  !CDS_PN = "1";
"B":   PN = "2"  !CDS_PN = "2";
BODY = "CAP_A","I78": #LOCATION = "C1A20" !CDS_LOCATION = "C1A20" #SEC = "1" !CDS_SEC = "1";
"A":   PN = "1"  !CDS_PN = "1";
"B":   PN = "2"  !CDS_PN = "2";
BODY = "CAP","I79": #LOCATION = "C1A9" !CDS_LOCATION = "C1A9" #SEC = "1" !CDS_SEC = "1";
"A":   PN = "1"  !CDS_PN = "1";
"B":   PN = "2"  !CDS_PN = "2";
BODY = "CAP","I80": #LOCATION = "C9L5" !CDS_LOCATION = "C9L5" #SEC = "1" !CDS_SEC = "1";
"A":   PN = "1"  !CDS_PN = "1";
"B":   PN = "2"  !CDS_PN = "2";
BODY = "CAP","I81": #LOCATION = "C9L13" !CDS_LOCATION = "C9L13" #SEC = "1" !CDS_SEC = "1";
"A":   PN = "1"  !CDS_PN = "1";
"B":   PN = "2"  !CDS_PN = "2";
BODY = "CAP","I84": #LOCATION = "C9L14" !CDS_LOCATION = "C9L14" #SEC = "1" !CDS_SEC = "1";
"A":   PN = "1"  !CDS_PN = "1";
"B":   PN = "2"  !CDS_PN = "2";
BODY = "IR354XX","I101": #LOCATION = "EU1A2" !CDS_LOCATION = "EU1A2" #SEC = "1" !CDS_SEC = "1";
"BOOST":   PN = "33"  !CDS_PN = "33";
"EN":   PN = "35"  !CDS_PN = "35";
"GL<0>":   PN = "6"  !CDS_PN = "6";
"GL<1>":   PN = "41"  !CDS_PN = "41";
"IOUT":   PN = "38"  !CDS_PN = "38";
"LGND":   PN = "2"  !CDS_PN = "2";
"NC":   PN = "31"  !CDS_PN = "31";
"OCSET":   PN = "37"  !CDS_PN = "37";
"PGND<0>":   PN = "5"  !CDS_PN = "5";
"PGND<1>":   PN = "7"  !CDS_PN = "7";
"PGND<2>":   PN = "40"  !CDS_PN = "40";
"PHASE":   PN = "32"  !CDS_PN = "32";
"PWM":   PN = "34"  !CDS_PN = "34";
"REFIN":   PN = "39"  !CDS_PN = "39";
"SW":   PN = "10"  !CDS_PN = "10";
"TOUT_FLT":   PN = "36"  !CDS_PN = "36";
"VCC":   PN = "3"  !CDS_PN = "3";
"VDRV":   PN = "4"  !CDS_PN = "4";
"VIN<0>":   PN = "25"  !CDS_PN = "25";
"VIN<1>":   PN = "30"  !CDS_PN = "30";
"VOS":   PN = "1"  !CDS_PN = "1";
BODY = "IR354XX","I102": #LOCATION = "EU1A1" !CDS_LOCATION = "EU1A1" #SEC = "1" !CDS_SEC = "1";
"BOOST":   PN = "33"  !CDS_PN = "33";
"EN":   PN = "35"  !CDS_PN = "35";
"GL<0>":   PN = "6"  !CDS_PN = "6";
"GL<1>":   PN = "41"  !CDS_PN = "41";
"IOUT":   PN = "38"  !CDS_PN = "38";
"LGND":   PN = "2"  !CDS_PN = "2";
"NC":   PN = "31"  !CDS_PN = "31";
"OCSET":   PN = "37"  !CDS_PN = "37";
"PGND<0>":   PN = "5"  !CDS_PN = "5";
"PGND<1>":   PN = "7"  !CDS_PN = "7";
"PGND<2>":   PN = "40"  !CDS_PN = "40";
"PHASE":   PN = "32"  !CDS_PN = "32";
"PWM":   PN = "34"  !CDS_PN = "34";
"REFIN":   PN = "39"  !CDS_PN = "39";
"SW":   PN = "10"  !CDS_PN = "10";
"TOUT_FLT":   PN = "36"  !CDS_PN = "36";
"VCC":   PN = "3"  !CDS_PN = "3";
"VDRV":   PN = "4"  !CDS_PN = "4";
"VIN<0>":   PN = "25"  !CDS_PN = "25";
"VIN<1>":   PN = "30"  !CDS_PN = "30";
"VOS":   PN = "1"  !CDS_PN = "1";
BODY = "RES","I103": #LOCATION = "R1A3" !CDS_LOCATION = "R1A3" #SEC = "1" !CDS_SEC = "1";
"A":   PN = "1"  !CDS_PN = "1";
"B":   PN = "2"  !CDS_PN = "2";
BODY = "RES","I105": #LOCATION = "R1A2" !CDS_LOCATION = "R1A2" #SEC = "1" !CDS_SEC = "1";
"A":   PN = "1"  !CDS_PN = "1";
"B":   PN = "2"  !CDS_PN = "2";
BODY = "CAP_A","I109": #LOCATION = "CT7" !CDS_LOCATION = "CT7" #SEC = "1" !CDS_SEC = "1";
"A":   PN = "1"  !CDS_PN = "1";
"B":   PN = "2"  !CDS_PN = "2";
BODY = "CAP","I114": #LOCATION = "CT8" !CDS_LOCATION = "CT8" #SEC = "1" !CDS_SEC = "1";
"A":   PN = "1"  !CDS_PN = "1";
"B":   PN = "2"  !CDS_PN = "2";
BODY = "CAP","I119": #LOCATION = "CT10" !CDS_LOCATION = "CT10" #SEC = "1" !CDS_SEC = "1";
"A":   PN = "1"  !CDS_PN = "1";
"B":   PN = "2"  !CDS_PN = "2";
BODY = "CAP_A","I122": #LOCATION = "CT12" !CDS_LOCATION = "CT12" #SEC = "1" !CDS_SEC = "1";
"A":   PN = "1"  !CDS_PN = "1";
"B":   PN = "2"  !CDS_PN = "2";
BODY = "CAP","I134": #LOCATION = "CT9" !CDS_LOCATION = "CT9" #SEC = "1" !CDS_SEC = "1";
"A":   PN = "1"  !CDS_PN = "1";
"B":   PN = "2"  !CDS_PN = "2";
BODY = "CAP","I135": #LOCATION = "CT11" !CDS_LOCATION = "CT11" #SEC = "1" !CDS_SEC = "1";
"A":   PN = "1"  !CDS_PN = "1";
"B":   PN = "2"  !CDS_PN = "2";
BODY = "RES","I138": #LOCATION = "RT5" !CDS_LOCATION = "RT5" #SEC = "1" !CDS_SEC = "1";
"A":   PN = "1"  !CDS_PN = "1";
"B":   PN = "2"  !CDS_PN = "2";
BODY = "RES","I139": #LOCATION = "RT8" !CDS_LOCATION = "RT8" #SEC = "1" !CDS_SEC = "1";
"A":   PN = "1"  !CDS_PN = "1";
"B":   PN = "2"  !CDS_PN = "2";
BODY = "SC1U10V2KX-4-GP","I147": #LOCATION = "C1A11" !CDS_LOCATION = "C1A11" #SEC = "1" !CDS_SEC = "1";
"1":   PN = "1"  !CDS_PN = "1";
"2":   PN = "2"  !CDS_PN = "2";
BODY = "SC1U10V2KX-4-GP","I148": #LOCATION = "C1A2" !CDS_LOCATION = "C1A2" #SEC = "1" !CDS_SEC = "1";
"1":   PN = "1"  !CDS_PN = "1";
"2":   PN = "2"  !CDS_PN = "2";
BODY = "1R3F-GP","I149": #LOCATION = "RT6" !CDS_LOCATION = "RT6" #SEC = "1" !CDS_SEC = "1";
"1":   PN = "1"  !CDS_PN = "1";
"2":   PN = "2"  !CDS_PN = "2";
BODY = "1R3F-GP","I150": #LOCATION = "RT7" !CDS_LOCATION = "RT7" #SEC = "1" !CDS_SEC = "1";
"1":   PN = "1"  !CDS_PN = "1";
"2":   PN = "2"  !CDS_PN = "2";
BODY = "IND-120NH-30-GP","I152": #LOCATION = "L1A2" !CDS_LOCATION = "L1A2" #SEC = "1" !CDS_SEC = "1";
"F":   PN = "2"  !CDS_PN = "2";
"S":   PN = "1"  !CDS_PN = "1";
BODY = "IND-120NH-30-GP","I153": #LOCATION = "L1A1" !CDS_LOCATION = "L1A1" #SEC = "1" !CDS_SEC = "1";
"F":   PN = "2"  !CDS_PN = "2";
"S":   PN = "1"  !CDS_PN = "1";
BODY = "RES","I154": #LOCATION = "R9L9" !CDS_LOCATION = "R9L9" #SEC = "1" !CDS_SEC = "1";
"A":   PN = "1"  !CDS_PN = "1";
"B":   PN = "2"  !CDS_PN = "2";
BODY = "RES","I155": #LOCATION = "R9L4" !CDS_LOCATION = "R9L4" #SEC = "1" !CDS_SEC = "1";
"A":   PN = "1"  !CDS_PN = "1";
"B":   PN = "2"  !CDS_PN = "2";
DRAWING = "@baseboard_fab2_lib.baseboard_fab2(sch_1):page228";
BODY = "RES","I58": #LOCATION = "R1A1" !CDS_LOCATION = "R1A1" &SEC = "1" #&CDS_SEC = "1";
"A":   PN = "1"  !CDS_PN = "1";
"B":   PN = "2"  !CDS_PN = "2";
BODY = "RES","I74": #LOCATION = "R7L2" !CDS_LOCATION = "R7L2" #SEC = "1" !CDS_SEC = "1";
"A":   PN = "1"  !CDS_PN = "1";
"B":   PN = "2"  !CDS_PN = "2";
BODY = "CAPP","I75": #LOCATION = "C9L9" !CDS_LOCATION = "C9L9" #SEC = "1" !CDS_SEC = "1";
"A":   PN = "1"  !CDS_PN = "1";
"B":   PN = "2"  !CDS_PN = "2";
BODY = "CAPP","I76": #LOCATION = "C9L12" !CDS_LOCATION = "C9L12" #SEC = "1" !CDS_SEC = "1";
"A":   PN = "1"  !CDS_PN = "1";
"B":   PN = "2"  !CDS_PN = "2";
BODY = "CAPP","I77": #LOCATION = "C9L4" !CDS_LOCATION = "C9L4" #SEC = "1" !CDS_SEC = "1";
"A":   PN = "1"  !CDS_PN = "1";
"B":   PN = "2"  !CDS_PN = "2";
BODY = "CAPP","I78": #LOCATION = "C9L2" !CDS_LOCATION = "C9L2" #SEC = "1" !CDS_SEC = "1";
"A":   PN = "1"  !CDS_PN = "1";
"B":   PN = "2"  !CDS_PN = "2";
BODY = "CAPP","I175": #LOCATION = "C1B10" !CDS_LOCATION = "C1B10" #SEC = "1" !CDS_SEC = "1";
"A":   PN = "1"  !CDS_PN = "1";
"B":   PN = "2"  !CDS_PN = "2";
BODY = "CAP_A","I198": #LOCATION = "C8M8" !CDS_LOCATION = "C8M8" #SEC = "1" !CDS_SEC = "1";
"A":   PN = "1"  !CDS_PN = "1";
"B":   PN = "2"  !CDS_PN = "2";
BODY = "CAP_A","I199": #LOCATION = "C2A5" !CDS_LOCATION = "C2A5" #SEC = "1" !CDS_SEC = "1";
"A":   PN = "1"  !CDS_PN = "1";
"B":   PN = "2"  !CDS_PN = "2";
BODY = "CAP_A","I200": #LOCATION = "C2B1" !CDS_LOCATION = "C2B1" #SEC = "1" !CDS_SEC = "1";
"A":   PN = "1"  !CDS_PN = "1";
"B":   PN = "2"  !CDS_PN = "2";
BODY = "CAP_A","I201": #LOCATION = "C8L12" !CDS_LOCATION = "C8L12" #SEC = "1" !CDS_SEC = "1";
"A":   PN = "1"  !CDS_PN = "1";
"B":   PN = "2"  !CDS_PN = "2";
BODY = "CAP_A","I202": #LOCATION = "C7M5" !CDS_LOCATION = "C7M5" #SEC = "1" !CDS_SEC = "1";
"A":   PN = "1"  !CDS_PN = "1";
"B":   PN = "2"  !CDS_PN = "2";
BODY = "CAP_A","I203": #LOCATION = "C8M10" !CDS_LOCATION = "C8M10" #SEC = "1" !CDS_SEC = "1";
"A":   PN = "1"  !CDS_PN = "1";
"B":   PN = "2"  !CDS_PN = "2";
BODY = "CAP_A","I204": #LOCATION = "C2B2" !CDS_LOCATION = "C2B2" #SEC = "1" !CDS_SEC = "1";
"A":   PN = "1"  !CDS_PN = "1";
"B":   PN = "2"  !CDS_PN = "2";
BODY = "CAP_A","I205": #LOCATION = "C8M9" !CDS_LOCATION = "C8M9" #SEC = "1" !CDS_SEC = "1";
"A":   PN = "1"  !CDS_PN = "1";
"B":   PN = "2"  !CDS_PN = "2";
BODY = "CAP_A","I206": #LOCATION = "C8M2" !CDS_LOCATION = "C8M2" #SEC = "1" !CDS_SEC = "1";
"A":   PN = "1"  !CDS_PN = "1";
"B":   PN = "2"  !CDS_PN = "2";
BODY = "SHUNT","I245": #LOCATION = "SH7L2" !CDS_LOCATION = "SH7L2" #SEC = "1" !CDS_SEC = "1";
"A":   PN = "1"  !CDS_PN = "1";
"B":   PN = "2"  !CDS_PN = "2";
BODY = "SHUNT","I246": #LOCATION = "SH7L1" !CDS_LOCATION = "SH7L1" #SEC = "1" !CDS_SEC = "1";
"A":   PN = "1"  !CDS_PN = "1";
"B":   PN = "2"  !CDS_PN = "2";
BODY = "IND-100NH-35-GP","I247": #LOCATION = "L1B1" !CDS_LOCATION = "L1B1" #SEC = "1" !CDS_SEC = "1";
"F":   PN = "2"  !CDS_PN = "2";
"S":   PN = "1"  !CDS_PN = "1";
BODY = "CAP_A","I255": #LOCATION = "C3D1" !CDS_LOCATION = "C3D1" &SEC = "1" #&CDS_SEC = "1";
"A":   PN = "1"  !CDS_PN = "1";
"B":   PN = "2"  !CDS_PN = "2";
BODY = "CAP_A","I256": #LOCATION = "C2D3" !CDS_LOCATION = "C2D3" #SEC = "1" !CDS_SEC = "1";
"A":   PN = "1"  !CDS_PN = "1";
"B":   PN = "2"  !CDS_PN = "2";
BODY = "CAP_A","I257": #LOCATION = "C2D2" !CDS_LOCATION = "C2D2" #SEC = "1" !CDS_SEC = "1";
"A":   PN = "1"  !CDS_PN = "1";
"B":   PN = "2"  !CDS_PN = "2";
BODY = "CAP_A","I258": #LOCATION = "C2D1" !CDS_LOCATION = "C2D1" &SEC = "1" #&CDS_SEC = "1";
"A":   PN = "1"  !CDS_PN = "1";
"B":   PN = "2"  !CDS_PN = "2";
BODY = "CAP_A","I264": #LOCATION = "C2D7" !CDS_LOCATION = "C2D7" &SEC = "1" #&CDS_SEC = "1";
"A":   PN = "1"  !CDS_PN = "1";
"B":   PN = "2"  !CDS_PN = "2";
BODY = "CAP_A","I265": #LOCATION = "C2D4" !CDS_LOCATION = "C2D4" &SEC = "1" #&CDS_SEC = "1";
"A":   PN = "1"  !CDS_PN = "1";
"B":   PN = "2"  !CDS_PN = "2";
BODY = "CAP_A","I266": #LOCATION = "C2D5" !CDS_LOCATION = "C2D5" &SEC = "1" #&CDS_SEC = "1";
"A":   PN = "1"  !CDS_PN = "1";
"B":   PN = "2"  !CDS_PN = "2";
BODY = "CAP_A","I267": #LOCATION = "C2D6" !CDS_LOCATION = "C2D6" &SEC = "1" #&CDS_SEC = "1";
"A":   PN = "1"  !CDS_PN = "1";
"B":   PN = "2"  !CDS_PN = "2";
BODY = "CAP_A","I268": #LOCATION = "C7L5" !CDS_LOCATION = "C7L5" #SEC = "1" !CDS_SEC = "1";
"A":   PN = "1"  !CDS_PN = "1";
"B":   PN = "2"  !CDS_PN = "2";
BODY = "CAP_A","I269": #LOCATION = "C3A6" !CDS_LOCATION = "C3A6" #SEC = "1" !CDS_SEC = "1";
"A":   PN = "1"  !CDS_PN = "1";
"B":   PN = "2"  !CDS_PN = "2";
BODY = "CAP_A","I270": #LOCATION = "C3A5" !CDS_LOCATION = "C3A5" #SEC = "1" !CDS_SEC = "1";
"A":   PN = "1"  !CDS_PN = "1";
"B":   PN = "2"  !CDS_PN = "2";
BODY = "CAP_A","I271": #LOCATION = "C2A15" !CDS_LOCATION = "C2A15" #SEC = "1" !CDS_SEC = "1";
"A":   PN = "1"  !CDS_PN = "1";
"B":   PN = "2"  !CDS_PN = "2";
BODY = "CAP_A","I272": #LOCATION = "C2A14" !CDS_LOCATION = "C2A14" #SEC = "1" !CDS_SEC = "1";
"A":   PN = "1"  !CDS_PN = "1";
"B":   PN = "2"  !CDS_PN = "2";
BODY = "CAP_A","I273": #LOCATION = "C2A6" !CDS_LOCATION = "C2A6" #SEC = "1" !CDS_SEC = "1";
"A":   PN = "1"  !CDS_PN = "1";
"B":   PN = "2"  !CDS_PN = "2";
BODY = "CAP_A","I274": #LOCATION = "C2A7" !CDS_LOCATION = "C2A7" #SEC = "1" !CDS_SEC = "1";
"A":   PN = "1"  !CDS_PN = "1";
"B":   PN = "2"  !CDS_PN = "2";
BODY = "CAP_A","I275": #LOCATION = "C3A1" !CDS_LOCATION = "C3A1" #SEC = "1" !CDS_SEC = "1";
"A":   PN = "1"  !CDS_PN = "1";
"B":   PN = "2"  !CDS_PN = "2";
BODY = "CAP_A","I276": #LOCATION = "C3A2" !CDS_LOCATION = "C3A2" #SEC = "1" !CDS_SEC = "1";
"A":   PN = "1"  !CDS_PN = "1";
"B":   PN = "2"  !CDS_PN = "2";
BODY = "CAP_A","I277": #LOCATION = "C2A9" !CDS_LOCATION = "C2A9" #SEC = "1" !CDS_SEC = "1";
"A":   PN = "1"  !CDS_PN = "1";
"B":   PN = "2"  !CDS_PN = "2";
BODY = "CAP_A","I278": #LOCATION = "C2A10" !CDS_LOCATION = "C2A10" #SEC = "1" !CDS_SEC = "1";
"A":   PN = "1"  !CDS_PN = "1";
"B":   PN = "2"  !CDS_PN = "2";
BODY = "CAP_A","I279": #LOCATION = "C2A11" !CDS_LOCATION = "C2A11" #SEC = "1" !CDS_SEC = "1";
"A":   PN = "1"  !CDS_PN = "1";
"B":   PN = "2"  !CDS_PN = "2";
BODY = "CAP_A","I280": #LOCATION = "C2A13" !CDS_LOCATION = "C2A13" #SEC = "1" !CDS_SEC = "1";
"A":   PN = "1"  !CDS_PN = "1";
"B":   PN = "2"  !CDS_PN = "2";
BODY = "CAP_A","I281": #LOCATION = "C2A12" !CDS_LOCATION = "C2A12" #SEC = "1" !CDS_SEC = "1";
"A":   PN = "1"  !CDS_PN = "1";
"B":   PN = "2"  !CDS_PN = "2";
BODY = "CAP_A","I282": #LOCATION = "C2A1" !CDS_LOCATION = "C2A1" #SEC = "1" !CDS_SEC = "1";
"A":   PN = "1"  !CDS_PN = "1";
"B":   PN = "2"  !CDS_PN = "2";
BODY = "CAP_A","I283": #LOCATION = "C2A2" !CDS_LOCATION = "C2A2" #SEC = "1" !CDS_SEC = "1";
"A":   PN = "1"  !CDS_PN = "1";
"B":   PN = "2"  !CDS_PN = "2";
BODY = "CAP_A","I284": #LOCATION = "C8M1" !CDS_LOCATION = "C8M1" #SEC = "1" !CDS_SEC = "1";
"A":   PN = "1"  !CDS_PN = "1";
"B":   PN = "2"  !CDS_PN = "2";
BODY = "CAP_A","I285": #LOCATION = "C8L5" !CDS_LOCATION = "C8L5" #SEC = "1" !CDS_SEC = "1";
"A":   PN = "1"  !CDS_PN = "1";
"B":   PN = "2"  !CDS_PN = "2";
BODY = "CAP_A","I286": #LOCATION = "C8L6" !CDS_LOCATION = "C8L6" #SEC = "1" !CDS_SEC = "1";
"A":   PN = "1"  !CDS_PN = "1";
"B":   PN = "2"  !CDS_PN = "2";
BODY = "CAP_A","I287": #LOCATION = "C8L7" !CDS_LOCATION = "C8L7" #SEC = "1" !CDS_SEC = "1";
"A":   PN = "1"  !CDS_PN = "1";
"B":   PN = "2"  !CDS_PN = "2";
BODY = "CAP_A","I288": #LOCATION = "C7L4" !CDS_LOCATION = "C7L4" #SEC = "1" !CDS_SEC = "1";
"A":   PN = "1"  !CDS_PN = "1";
"B":   PN = "2"  !CDS_PN = "2";
BODY = "CAP_A","I289": #LOCATION = "C8L8" !CDS_LOCATION = "C8L8" #SEC = "1" !CDS_SEC = "1";
"A":   PN = "1"  !CDS_PN = "1";
"B":   PN = "2"  !CDS_PN = "2";
BODY = "CAP_A","I290": #LOCATION = "C8L9" !CDS_LOCATION = "C8L9" #SEC = "1" !CDS_SEC = "1";
"A":   PN = "1"  !CDS_PN = "1";
"B":   PN = "2"  !CDS_PN = "2";
BODY = "CAP_A","I291": #LOCATION = "C8M6" !CDS_LOCATION = "C8M6" #SEC = "1" !CDS_SEC = "1";
"A":   PN = "1"  !CDS_PN = "1";
"B":   PN = "2"  !CDS_PN = "2";
BODY = "CAP_A","I292": #LOCATION = "C2A4" !CDS_LOCATION = "C2A4" #SEC = "1" !CDS_SEC = "1";
"A":   PN = "1"  !CDS_PN = "1";
"B":   PN = "2"  !CDS_PN = "2";
BODY = "CAP_A","I293": #LOCATION = "C8M4" !CDS_LOCATION = "C8M4" #SEC = "1" !CDS_SEC = "1";
"A":   PN = "1"  !CDS_PN = "1";
"B":   PN = "2"  !CDS_PN = "2";
BODY = "CAP_A","I294": #LOCATION = "C7M2" !CDS_LOCATION = "C7M2" #SEC = "1" !CDS_SEC = "1";
"A":   PN = "1"  !CDS_PN = "1";
"B":   PN = "2"  !CDS_PN = "2";
BODY = "CAP_A","I295": #LOCATION = "C7M1" !CDS_LOCATION = "C7M1" #SEC = "1" !CDS_SEC = "1";
"A":   PN = "1"  !CDS_PN = "1";
"B":   PN = "2"  !CDS_PN = "2";
BODY = "CAP_A","I296": #LOCATION = "C2A3" !CDS_LOCATION = "C2A3" #SEC = "1" !CDS_SEC = "1";
"A":   PN = "1"  !CDS_PN = "1";
"B":   PN = "2"  !CDS_PN = "2";
BODY = "CAP_A","I297": #LOCATION = "C8L10" !CDS_LOCATION = "C8L10" #SEC = "1" !CDS_SEC = "1";
"A":   PN = "1"  !CDS_PN = "1";
"B":   PN = "2"  !CDS_PN = "2";
BODY = "CAP_A","I298": #LOCATION = "C8M5" !CDS_LOCATION = "C8M5" #SEC = "1" !CDS_SEC = "1";
"A":   PN = "1"  !CDS_PN = "1";
"B":   PN = "2"  !CDS_PN = "2";
BODY = "CAP_A","I299": #LOCATION = "C8M3" !CDS_LOCATION = "C8M3" #SEC = "1" !CDS_SEC = "1";
"A":   PN = "1"  !CDS_PN = "1";
"B":   PN = "2"  !CDS_PN = "2";
BODY = "CAP","I301": #LOCATION = "C8L1" !CDS_LOCATION = "C8L1" #SEC = "1" !CDS_SEC = "1";
"A":   PN = "1"  !CDS_PN = "1";
"B":   PN = "2"  !CDS_PN = "2";
BODY = "CAP","I302": #LOCATION = "C8L11" !CDS_LOCATION = "C8L11" #SEC = "1" !CDS_SEC = "1";
"A":   PN = "1"  !CDS_PN = "1";
"B":   PN = "2"  !CDS_PN = "2";
BODY = "CAP","I303": #LOCATION = "C8P2" !CDS_LOCATION = "C8P2" #SEC = "1" !CDS_SEC = "1";
"A":   PN = "1"  !CDS_PN = "1";
"B":   PN = "2"  !CDS_PN = "2";
BODY = "CAP","I304": #LOCATION = "C8P1" !CDS_LOCATION = "C8P1" #SEC = "1" !CDS_SEC = "1";
"A":   PN = "1"  !CDS_PN = "1";
"B":   PN = "2"  !CDS_PN = "2";
BODY = "CAP","I305": #LOCATION = "C7P2" !CDS_LOCATION = "C7P2" #SEC = "1" !CDS_SEC = "1";
"A":   PN = "1"  !CDS_PN = "1";
"B":   PN = "2"  !CDS_PN = "2";
BODY = "CAP","I306": #LOCATION = "C8P3" !CDS_LOCATION = "C8P3" #SEC = "1" !CDS_SEC = "1";
"A":   PN = "1"  !CDS_PN = "1";
"B":   PN = "2"  !CDS_PN = "2";
BODY = "CAP","I307": #LOCATION = "C8P4" !CDS_LOCATION = "C8P4" #SEC = "1" !CDS_SEC = "1";
"A":   PN = "1"  !CDS_PN = "1";
"B":   PN = "2"  !CDS_PN = "2";
BODY = "CAP","I308": #LOCATION = "C7P1" !CDS_LOCATION = "C7P1" #SEC = "1" !CDS_SEC = "1";
"A":   PN = "1"  !CDS_PN = "1";
"B":   PN = "2"  !CDS_PN = "2";
BODY = "CAP","I309": #LOCATION = "C2A8" !CDS_LOCATION = "C2A8" #SEC = "1" !CDS_SEC = "1";
"A":   PN = "1"  !CDS_PN = "1";
"B":   PN = "2"  !CDS_PN = "2";
BODY = "CAP","I310": #LOCATION = "C8L2" !CDS_LOCATION = "C8L2" #SEC = "1" !CDS_SEC = "1";
"A":   PN = "1"  !CDS_PN = "1";
"B":   PN = "2"  !CDS_PN = "2";
BODY = "CAP","I311": #LOCATION = "C8M11" !CDS_LOCATION = "C8M11" #SEC = "1" !CDS_SEC = "1";
"A":   PN = "1"  !CDS_PN = "1";
"B":   PN = "2"  !CDS_PN = "2";
BODY = "CAP","I312": #LOCATION = "C8M7" !CDS_LOCATION = "C8M7" #SEC = "1" !CDS_SEC = "1";
"A":   PN = "1"  !CDS_PN = "1";
"B":   PN = "2"  !CDS_PN = "2";
BODY = "CAP","I313": #LOCATION = "C2A16" !CDS_LOCATION = "C2A16" #SEC = "1" !CDS_SEC = "1";
"A":   PN = "1"  !CDS_PN = "1";
"B":   PN = "2"  !CDS_PN = "2";
BODY = "CAP","I314": #LOCATION = "C7L1" !CDS_LOCATION = "C7L1" #SEC = "1" !CDS_SEC = "1";
"A":   PN = "1"  !CDS_PN = "1";
"B":   PN = "2"  !CDS_PN = "2";
DRAWING = "@baseboard_fab2_lib.baseboard_fab2(sch_1):page229";
BODY = "CAP","I21": #LOCATION = "C4G21" !CDS_LOCATION = "C4G21" #SEC = "1" !CDS_SEC = "1";
"A":   PN = "1"  !CDS_PN = "1";
"B":   PN = "2"  !CDS_PN = "2";
BODY = "RES","I32": #LOCATION = "R4G15" !CDS_LOCATION = "R4G15" #SEC = "1" !CDS_SEC = "1";
"A":   PN = "1"  !CDS_PN = "1";
"B":   PN = "2"  !CDS_PN = "2";
BODY = "CAP","I2": #LOCATION = "C4G12" !CDS_LOCATION = "C4G12" #SEC = "1" !CDS_SEC = "1";
"A":   PN = "1"  !CDS_PN = "1";
"B":   PN = "2"  !CDS_PN = "2";
BODY = "RES","I4": #LOCATION = "R4G16" !CDS_LOCATION = "R4G16" #SEC = "1" !CDS_SEC = "1";
"A":   PN = "1"  !CDS_PN = "1";
"B":   PN = "2"  !CDS_PN = "2";
BODY = "RES","I5": #LOCATION = "R6U3" !CDS_LOCATION = "R6U3" #SEC = "1" !CDS_SEC = "1";
"A":   PN = "1"  !CDS_PN = "1";
"B":   PN = "2"  !CDS_PN = "2";
BODY = "RES","I6": #LOCATION = "R6U6" !CDS_LOCATION = "R6U6" #SEC = "1" !CDS_SEC = "1";
"A":   PN = "1"  !CDS_PN = "1";
"B":   PN = "2"  !CDS_PN = "2";
BODY = "RES","I9": #LOCATION = "R6U7" !CDS_LOCATION = "R6U7" #SEC = "1" !CDS_SEC = "1";
"A":   PN = "1"  !CDS_PN = "1";
"B":   PN = "2"  !CDS_PN = "2";
BODY = "CAP","I11": #LOCATION = "C6U13" !CDS_LOCATION = "C6U13" #SEC = "1" !CDS_SEC = "1";
"A":   PN = "1"  !CDS_PN = "1";
"B":   PN = "2"  !CDS_PN = "2";
BODY = "SHUNT","I12": #LOCATION = "SH8U1" !CDS_LOCATION = "SH8U1" #SEC = "1" !CDS_SEC = "1";
"A":   PN = "1"  !CDS_PN = "1";
"B":   PN = "2"  !CDS_PN = "2";
BODY = "CAP","I16": #LOCATION = "C4G18" !CDS_LOCATION = "C4G18" #SEC = "1" !CDS_SEC = "1";
"A":   PN = "1"  !CDS_PN = "1";
"B":   PN = "2"  !CDS_PN = "2";
BODY = "CAP","I18": #LOCATION = "C6U14" !CDS_LOCATION = "C6U14" #SEC = "1" !CDS_SEC = "1";
"A":   PN = "1"  !CDS_PN = "1";
"B":   PN = "2"  !CDS_PN = "2";
BODY = "CAP","I23": #LOCATION = "C4G20" !CDS_LOCATION = "C4G20" #SEC = "1" !CDS_SEC = "1";
"A":   PN = "1"  !CDS_PN = "1";
"B":   PN = "2"  !CDS_PN = "2";
BODY = "CAP","I26": #LOCATION = "C4G13" !CDS_LOCATION = "C4G13" #SEC = "1" !CDS_SEC = "1";
"A":   PN = "1"  !CDS_PN = "1";
"B":   PN = "2"  !CDS_PN = "2";
BODY = "CAP_A","I28": #LOCATION = "C2F2" !CDS_LOCATION = "C2F2" #SEC = "1" !CDS_SEC = "1";
"A":   PN = "1"  !CDS_PN = "1";
"B":   PN = "2"  !CDS_PN = "2";
BODY = "MIC5166","I37": #LOCATION = "EU4G2" !CDS_LOCATION = "EU4G2" #SEC = "1" !CDS_SEC = "1";
"AGND":   PN = "3"  !CDS_PN = "3";
"BIAS":   PN = "2"  !CDS_PN = "2";
"EN":   PN = "7"  !CDS_PN = "7";
"PG":   PN = "5"  !CDS_PN = "5";
"PGND":   PN = "8"  !CDS_PN = "8";
"SNS":   PN = "6"  !CDS_PN = "6";
"THPAD":   PN = "11"  !CDS_PN = "11";
"VDDQ":   PN = "4"  !CDS_PN = "4";
"VIN":   PN = "10"  !CDS_PN = "10";
"VREF":   PN = "1"  !CDS_PN = "1";
"VTT":   PN = "9"  !CDS_PN = "9";
BODY = "CAP","I14": #LOCATION = "C6U11" !CDS_LOCATION = "C6U11" #SEC = "1" !CDS_SEC = "1";
"A":   PN = "1"  !CDS_PN = "1";
"B":   PN = "2"  !CDS_PN = "2";
BODY = "RES","I24": #LOCATION = "R4G17" !CDS_LOCATION = "R4G17" #SEC = "1" !CDS_SEC = "1";
"A":   PN = "1"  !CDS_PN = "1";
"B":   PN = "2"  !CDS_PN = "2";
BODY = "CAP","I41": #LOCATION = "C8T3" !CDS_LOCATION = "C8T3" #SEC = "1" !CDS_SEC = "1";
"A":   PN = "1"  !CDS_PN = "1";
"B":   PN = "2"  !CDS_PN = "2";
BODY = "CAP","I42": #LOCATION = "C8U10" !CDS_LOCATION = "C8U10" #SEC = "1" !CDS_SEC = "1";
"A":   PN = "1"  !CDS_PN = "1";
"B":   PN = "2"  !CDS_PN = "2";
BODY = "CAP","I43": #LOCATION = "C6W12" !CDS_LOCATION = "C6W12" #SEC = "1" !CDS_SEC = "1";
"A":   PN = "1"  !CDS_PN = "1";
"B":   PN = "2"  !CDS_PN = "2";
DRAWING = "@baseboard_fab2_lib.baseboard_fab2(sch_1):page231";
BODY = "CAP","I122": #LOCATION = "C6F6" !CDS_LOCATION = "C6F6" &SEC = "1" #&CDS_SEC = "1";
"A":   PN = "1"  !CDS_PN = "1";
"B":   PN = "2"  !CDS_PN = "2";
BODY = "CAP","I124": #LOCATION = "C4T6" !CDS_LOCATION = "C4T6" &SEC = "1" #&CDS_SEC = "1";
"A":   PN = "1"  !CDS_PN = "1";
"B":   PN = "2"  !CDS_PN = "2";
BODY = "CAP","I125": #LOCATION = "C4T5" !CDS_LOCATION = "C4T5" &SEC = "1" #&CDS_SEC = "1";
"A":   PN = "1"  !CDS_PN = "1";
"B":   PN = "2"  !CDS_PN = "2";
BODY = "CAP","I126": #LOCATION = "C6G1" !CDS_LOCATION = "C6G1" &SEC = "1" #&CDS_SEC = "1";
"A":   PN = "1"  !CDS_PN = "1";
"B":   PN = "2"  !CDS_PN = "2";
BODY = "CAP","I128": #LOCATION = "C6G2" !CDS_LOCATION = "C6G2" &SEC = "1" #&CDS_SEC = "1";
"A":   PN = "1"  !CDS_PN = "1";
"B":   PN = "2"  !CDS_PN = "2";
BODY = "CAP","I129": #LOCATION = "C4U2" !CDS_LOCATION = "C4U2" &SEC = "1" #&CDS_SEC = "1";
"A":   PN = "1"  !CDS_PN = "1";
"B":   PN = "2"  !CDS_PN = "2";
BODY = "CAP","I130": #LOCATION = "C4U1" !CDS_LOCATION = "C4U1" &SEC = "1" #&CDS_SEC = "1";
"A":   PN = "1"  !CDS_PN = "1";
"B":   PN = "2"  !CDS_PN = "2";
BODY = "CAP","I131": #LOCATION = "C6G4" !CDS_LOCATION = "C6G4" &SEC = "1" #&CDS_SEC = "1";
"A":   PN = "1"  !CDS_PN = "1";
"B":   PN = "2"  !CDS_PN = "2";
BODY = "RES","I134": #LOCATION = "R7F15" !CDS_LOCATION = "R7F15" &SEC = "1" #&CDS_SEC = "1";
"A":   PN = "1"  !CDS_PN = "1";
"B":   PN = "2"  !CDS_PN = "2";
BODY = "RES","I136": #LOCATION = "R7F14" !CDS_LOCATION = "R7F14" &SEC = "1" #&CDS_SEC = "1";
"A":   PN = "1"  !CDS_PN = "1";
"B":   PN = "2"  !CDS_PN = "2";
BODY = "CAP","I140": #LOCATION = "C7F8" !CDS_LOCATION = "C7F8" &SEC = "1" #&CDS_SEC = "1";
"A":   PN = "1"  !CDS_PN = "1";
"B":   PN = "2"  !CDS_PN = "2";
BODY = "CAP","I142": #LOCATION = "C7F11" !CDS_LOCATION = "C7F11" &SEC = "1" #&CDS_SEC = "1";
"A":   PN = "1"  !CDS_PN = "1";
"B":   PN = "2"  !CDS_PN = "2";
BODY = "RES","I143": #LOCATION = "R7F19" !CDS_LOCATION = "R7F19" #SEC = "1" !CDS_SEC = "1";
"A":   PN = "1"  !CDS_PN = "1";
"B":   PN = "2"  !CDS_PN = "2";
BODY = "CAP","I145": #LOCATION = "C6G5" !CDS_LOCATION = "C6G5" &SEC = "1" #&CDS_SEC = "1";
"A":   PN = "1"  !CDS_PN = "1";
"B":   PN = "2"  !CDS_PN = "2";
BODY = "CAP","I146": #LOCATION = "C4U4" !CDS_LOCATION = "C4U4" &SEC = "1" #&CDS_SEC = "1";
"A":   PN = "1"  !CDS_PN = "1";
"B":   PN = "2"  !CDS_PN = "2";
BODY = "CAP","I148": #LOCATION = "C4U3" !CDS_LOCATION = "C4U3" &SEC = "1" #&CDS_SEC = "1";
"A":   PN = "1"  !CDS_PN = "1";
"B":   PN = "2"  !CDS_PN = "2";
BODY = "CAP","I149": #LOCATION = "C6F5" !CDS_LOCATION = "C6F5" #SEC = "1" !CDS_SEC = "1";
"A":   PN = "1"  !CDS_PN = "1";
"B":   PN = "2"  !CDS_PN = "2";
BODY = "CAP","I159": #LOCATION = "C7F4" !CDS_LOCATION = "C7F4" &SEC = "1" #&CDS_SEC = "1";
"A":   PN = "1"  !CDS_PN = "1";
"B":   PN = "2"  !CDS_PN = "2";
BODY = "CAP","I161": #LOCATION = "C3T10" !CDS_LOCATION = "C3T10" &SEC = "1" #&CDS_SEC = "1";
"A":   PN = "1"  !CDS_PN = "1";
"B":   PN = "2"  !CDS_PN = "2";
BODY = "FERRITE","I162": #LOCATION = "FB7F1" !CDS_LOCATION = "FB7F1" #SEC = "1" !CDS_SEC = "1";
"A":   PN = "1"  !CDS_PN = "1";
"B":   PN = "2"  !CDS_PN = "2";
BODY = "RES","I167": #LOCATION = "R7F13" !CDS_LOCATION = "R7F13" &SEC = "1" #&CDS_SEC = "1";
"A":   PN = "1"  !CDS_PN = "1";
"B":   PN = "2"  !CDS_PN = "2";
BODY = "RES","I168": #LOCATION = "R7F12" !CDS_LOCATION = "R7F12" #SEC = "1" !CDS_SEC = "1";
"A":   PN = "1"  !CDS_PN = "1";
"B":   PN = "2"  !CDS_PN = "2";
BODY = "RES","I170": #LOCATION = "R7F35" !CDS_LOCATION = "R7F35" &SEC = "1" #&CDS_SEC = "1";
"A":   PN = "1"  !CDS_PN = "1";
"B":   PN = "2"  !CDS_PN = "2";
BODY = "RES","I174": #LOCATION = "R7F7" !CDS_LOCATION = "R7F7" &SEC = "1" #&CDS_SEC = "1";
"A":   PN = "1"  !CDS_PN = "1";
"B":   PN = "2"  !CDS_PN = "2";
BODY = "CAP","I175": #LOCATION = "C7F3" !CDS_LOCATION = "C7F3" &SEC = "1" #&CDS_SEC = "1";
"A":   PN = "1"  !CDS_PN = "1";
"B":   PN = "2"  !CDS_PN = "2";
BODY = "RES","I177": #LOCATION = "R7F10" !CDS_LOCATION = "R7F10" #SEC = "1" !CDS_SEC = "1";
"A":   PN = "1"  !CDS_PN = "1";
"B":   PN = "2"  !CDS_PN = "2";
BODY = "INDUCTOR","I178": #LOCATION = "L7F1" !CDS_LOCATION = "L7F1" &SEC = "1" #&CDS_SEC = "1";
"INA":   PN = "1"  !CDS_PN = "1";
"INB":   PN = "2"  !CDS_PN = "2";
BODY = "CAPP","I180": #LOCATION = "C6F4" !CDS_LOCATION = "C6F4" &SEC = "1" #&CDS_SEC = "1";
"A":   PN = "1"  !CDS_PN = "1";
"B":   PN = "2"  !CDS_PN = "2";
BODY = "CAP","I184": #LOCATION = "C3T7" !CDS_LOCATION = "C3T7" &SEC = "1" #&CDS_SEC = "1";
"A":   PN = "1"  !CDS_PN = "1";
"B":   PN = "2"  !CDS_PN = "2";
BODY = "CAP","I186": #LOCATION = "C3T9" !CDS_LOCATION = "C3T9" &SEC = "1" #&CDS_SEC = "1";
"A":   PN = "1"  !CDS_PN = "1";
"B":   PN = "2"  !CDS_PN = "2";
BODY = "NCP3232L","I193": #LOCATION = "EU7F1" !CDS_LOCATION = "EU7F1" #SEC = "1" !CDS_SEC = "1";
"AGND":   PN = "5"  !CDS_PN = "5";
"BST":   PN = "36"  !CDS_PN = "36";
"COMP":   PN = "3"  !CDS_PN = "3";
"EN":   PN = "40"  !CDS_PN = "40";
"FB":   PN = "2"  !CDS_PN = "2";
"GND":   PN = "41"  !CDS_PN = "41";
"ISET":   PN = "4"  !CDS_PN = "4";
"OTS":   PN = "6"  !CDS_PN = "6";
"PG":   PN = "7"  !CDS_PN = "7";
"PGND<0>":   PN = "16"  !CDS_PN = "16";
"PGND<1>":   PN = "17"  !CDS_PN = "17";
"PGND<2>":   PN = "18"  !CDS_PN = "18";
"PGND<3>":   PN = "19"  !CDS_PN = "19";
"PGND<4>":   PN = "20"  !CDS_PN = "20";
"PGND<5>":   PN = "21"  !CDS_PN = "21";
"PGND<6>":   PN = "22"  !CDS_PN = "22";
"PGND<7>":   PN = "23"  !CDS_PN = "23";
"PGND<8>":   PN = "24"  !CDS_PN = "24";
"PGND<9>":   PN = "25"  !CDS_PN = "25";
"PGND<10>":   PN = "26"  !CDS_PN = "26";
"PGND<11>":   PN = "27"  !CDS_PN = "27";
"PGND<12>":   PN = "28"  !CDS_PN = "28";
"PGND<13>":   PN = "37"  !CDS_PN = "37";
"SS":   PN = "1"  !CDS_PN = "1";
"VB":   PN = "38"  !CDS_PN = "38";
"VCC":   PN = "39"  !CDS_PN = "39";
"VIN<0>":   PN = "8"  !CDS_PN = "8";
"VIN<1>":   PN = "9"  !CDS_PN = "9";
"VIN<2>":   PN = "10"  !CDS_PN = "10";
"VIN<3>":   PN = "11"  !CDS_PN = "11";
"VIN<4>":   PN = "12"  !CDS_PN = "12";
"VIN<5>":   PN = "13"  !CDS_PN = "13";
"VIN<6>":   PN = "14"  !CDS_PN = "14";
"VIN<7>":   PN = "42"  !CDS_PN = "42";
"VSW":   PN = "35"  !CDS_PN = "35";
"VSWH<0>":   PN = "15"  !CDS_PN = "15";
"VSWH<1>":   PN = "29"  !CDS_PN = "29";
"VSWH<2>":   PN = "30"  !CDS_PN = "30";
"VSWH<3>":   PN = "31"  !CDS_PN = "31";
"VSWH<4>":   PN = "32"  !CDS_PN = "32";
"VSWH<5>":   PN = "33"  !CDS_PN = "33";
"VSWH<6>":   PN = "34"  !CDS_PN = "34";
"VSWH<7>":   PN = "43"  !CDS_PN = "43";
BODY = "CAP","I194": #LOCATION = "C7F10" !CDS_LOCATION = "C7F10" #SEC = "1" !CDS_SEC = "1";
"A":   PN = "1"  !CDS_PN = "1";
"B":   PN = "2"  !CDS_PN = "2";
BODY = "CAP","I199": #LOCATION = "C7F9" !CDS_LOCATION = "C7F9" #SEC = "1" !CDS_SEC = "1";
"A":   PN = "1"  !CDS_PN = "1";
"B":   PN = "2"  !CDS_PN = "2";
BODY = "CAP","I200": #LOCATION = "C7F12" !CDS_LOCATION = "C7F12" #SEC = "1" !CDS_SEC = "1";
"A":   PN = "1"  !CDS_PN = "1";
"B":   PN = "2"  !CDS_PN = "2";
BODY = "RES","I201": #LOCATION = "R7F18" !CDS_LOCATION = "R7F18" #SEC = "1" !CDS_SEC = "1";
"A":   PN = "1"  !CDS_PN = "1";
"B":   PN = "2"  !CDS_PN = "2";
BODY = "CAP","I202": #LOCATION = "C3T11" !CDS_LOCATION = "C3T11" #SEC = "1" !CDS_SEC = "1";
"A":   PN = "1"  !CDS_PN = "1";
"B":   PN = "2"  !CDS_PN = "2";
BODY = "CAP_A","I205": #LOCATION = "C7F6" !CDS_LOCATION = "C7F6" #SEC = "1" !CDS_SEC = "1";
"A":   PN = "1"  !CDS_PN = "1";
"B":   PN = "2"  !CDS_PN = "2";
BODY = "RES","I208": #LOCATION = "R7F16" !CDS_LOCATION = "R7F16" #SEC = "1" !CDS_SEC = "1";
"A":   PN = "1"  !CDS_PN = "1";
"B":   PN = "2"  !CDS_PN = "2";
BODY = "CAP","I209": #LOCATION = "C7F5" !CDS_LOCATION = "C7F5" #SEC = "1" !CDS_SEC = "1";
"A":   PN = "1"  !CDS_PN = "1";
"B":   PN = "2"  !CDS_PN = "2";
BODY = "CAP","I210": #LOCATION = "C3T8" !CDS_LOCATION = "C3T8" #SEC = "1" !CDS_SEC = "1";
"A":   PN = "1"  !CDS_PN = "1";
"B":   PN = "2"  !CDS_PN = "2";
BODY = "CAP","I211": #LOCATION = "C3T14" !CDS_LOCATION = "C3T14" #SEC = "1" !CDS_SEC = "1";
"A":   PN = "1"  !CDS_PN = "1";
"B":   PN = "2"  !CDS_PN = "2";
BODY = "CAP","I215": #LOCATION = "C3T12" !CDS_LOCATION = "C3T12" #SEC = "1" !CDS_SEC = "1";
"A":   PN = "1"  !CDS_PN = "1";
"B":   PN = "2"  !CDS_PN = "2";
BODY = "CAPP","I217": #LOCATION = "C4T3" !CDS_LOCATION = "C4T3" #SEC = "1" !CDS_SEC = "1";
"A":   PN = "1"  !CDS_PN = "1";
"B":   PN = "2"  !CDS_PN = "2";
BODY = "RES","I218": #LOCATION = "R7F17" !CDS_LOCATION = "R7F17" #SEC = "1" !CDS_SEC = "1";
"A":   PN = "1"  !CDS_PN = "1";
"B":   PN = "2"  !CDS_PN = "2";
BODY = "CAP","I219": #LOCATION = "C7F13" !CDS_LOCATION = "C7F13" #SEC = "1" !CDS_SEC = "1";
"A":   PN = "1"  !CDS_PN = "1";
"B":   PN = "2"  !CDS_PN = "2";
BODY = "RES","I220": #LOCATION = "R7F9" !CDS_LOCATION = "R7F9" #SEC = "1" !CDS_SEC = "1";
"A":   PN = "1"  !CDS_PN = "1";
"B":   PN = "2"  !CDS_PN = "2";
BODY = "SC22U16V5MX-4-GP","I225": #LOCATION = "C22W10" !CDS_LOCATION = "C22W10" #SEC = "1" !CDS_SEC = "1";
"1":   PN = "1"  !CDS_PN = "1";
"2":   PN = "2"  !CDS_PN = "2";
BODY = "SC22U16V5MX-4-GP","I226": #LOCATION = "C7F7" !CDS_LOCATION = "C7F7" #SEC = "1" !CDS_SEC = "1";
"1":   PN = "1"  !CDS_PN = "1";
"2":   PN = "2"  !CDS_PN = "2";
BODY = "RES","I229": #LOCATION = "R7F8" !CDS_LOCATION = "R7F8" #SEC = "1" !CDS_SEC = "1";
"A":   PN = "1"  !CDS_PN = "1";
"B":   PN = "2"  !CDS_PN = "2";
BODY = "RES","I230": #LOCATION = "R7F11" !CDS_LOCATION = "R7F11" #SEC = "1" !CDS_SEC = "1";
"A":   PN = "1"  !CDS_PN = "1";
"B":   PN = "2"  !CDS_PN = "2";
DRAWING = "@baseboard_fab2_lib.baseboard_fab2(sch_1):page232";
BODY = "CAP","I102": #LOCATION = "C4L2" !CDS_LOCATION = "C4L2" &SEC = "1" #&CDS_SEC = "1";
"A":   PN = "1"  !CDS_PN = "1";
"B":   PN = "2"  !CDS_PN = "2";
BODY = "CAP","I104": #LOCATION = "C6A3" !CDS_LOCATION = "C6A3" &SEC = "1" #&CDS_SEC = "1";
"A":   PN = "1"  !CDS_PN = "1";
"B":   PN = "2"  !CDS_PN = "2";
BODY = "CAP","I105": #LOCATION = "C6A2" !CDS_LOCATION = "C6A2" &SEC = "1" #&CDS_SEC = "1";
"A":   PN = "1"  !CDS_PN = "1";
"B":   PN = "2"  !CDS_PN = "2";
BODY = "CAP","I106": #LOCATION = "C4L3" !CDS_LOCATION = "C4L3" &SEC = "1" #&CDS_SEC = "1";
"A":   PN = "1"  !CDS_PN = "1";
"B":   PN = "2"  !CDS_PN = "2";
BODY = "CAP","I108": #LOCATION = "C4L4" !CDS_LOCATION = "C4L4" &SEC = "1" #&CDS_SEC = "1";
"A":   PN = "1"  !CDS_PN = "1";
"B":   PN = "2"  !CDS_PN = "2";
BODY = "CAP","I109": #LOCATION = "C6A7" !CDS_LOCATION = "C6A7" &SEC = "1" #&CDS_SEC = "1";
"A":   PN = "1"  !CDS_PN = "1";
"B":   PN = "2"  !CDS_PN = "2";
BODY = "CAP","I110": #LOCATION = "C6A6" !CDS_LOCATION = "C6A6" &SEC = "1" #&CDS_SEC = "1";
"A":   PN = "1"  !CDS_PN = "1";
"B":   PN = "2"  !CDS_PN = "2";
BODY = "CAP","I111": #LOCATION = "C4M3" !CDS_LOCATION = "C4M3" &SEC = "1" #&CDS_SEC = "1";
"A":   PN = "1"  !CDS_PN = "1";
"B":   PN = "2"  !CDS_PN = "2";
BODY = "CAP","I125": #LOCATION = "C4M4" !CDS_LOCATION = "C4M4" &SEC = "1" #&CDS_SEC = "1";
"A":   PN = "1"  !CDS_PN = "1";
"B":   PN = "2"  !CDS_PN = "2";
BODY = "CAP","I126": #LOCATION = "C6B2" !CDS_LOCATION = "C6B2" &SEC = "1" #&CDS_SEC = "1";
"A":   PN = "1"  !CDS_PN = "1";
"B":   PN = "2"  !CDS_PN = "2";
BODY = "CAP","I128": #LOCATION = "C6B1" !CDS_LOCATION = "C6B1" &SEC = "1" #&CDS_SEC = "1";
"A":   PN = "1"  !CDS_PN = "1";
"B":   PN = "2"  !CDS_PN = "2";
BODY = "CAP","I129": #LOCATION = "C4L1" !CDS_LOCATION = "C4L1" #SEC = "1" !CDS_SEC = "1";
"A":   PN = "1"  !CDS_PN = "1";
"B":   PN = "2"  !CDS_PN = "2";
BODY = "RES","I150": #LOCATION = "R7B20" !CDS_LOCATION = "R7B20" &SEC = "1" #&CDS_SEC = "1";
"A":   PN = "1"  !CDS_PN = "1";
"B":   PN = "2"  !CDS_PN = "2";
BODY = "CAP","I185": #LOCATION = "C7B9" !CDS_LOCATION = "C7B9" &SEC = "1" #&CDS_SEC = "1";
"A":   PN = "1"  !CDS_PN = "1";
"B":   PN = "2"  !CDS_PN = "2";
BODY = "CAP","I197": #LOCATION = "C7B11" !CDS_LOCATION = "C7B11" #SEC = "1" !CDS_SEC = "1";
"A":   PN = "1"  !CDS_PN = "1";
"B":   PN = "2"  !CDS_PN = "2";
BODY = "FERRITE","I200": #LOCATION = "FB7B1" !CDS_LOCATION = "FB7B1" #SEC = "1" !CDS_SEC = "1";
"A":   PN = "1"  !CDS_PN = "1";
"B":   PN = "2"  !CDS_PN = "2";
BODY = "CAP","I207": #LOCATION = "C3M9" !CDS_LOCATION = "C3M9" &SEC = "1" #&CDS_SEC = "1";
"A":   PN = "1"  !CDS_PN = "1";
"B":   PN = "2"  !CDS_PN = "2";
BODY = "CAP","I209": #LOCATION = "C7B12" !CDS_LOCATION = "C7B12" &SEC = "1" #&CDS_SEC = "1";
"A":   PN = "1"  !CDS_PN = "1";
"B":   PN = "2"  !CDS_PN = "2";
BODY = "RES","I210": #LOCATION = "R7B17" !CDS_LOCATION = "R7B17" #SEC = "1" !CDS_SEC = "1";
"A":   PN = "1"  !CDS_PN = "1";
"B":   PN = "2"  !CDS_PN = "2";
BODY = "NCP3232L","I214": #LOCATION = "EU7B1" !CDS_LOCATION = "EU7B1" #SEC = "1" !CDS_SEC = "1";
"AGND":   PN = "5"  !CDS_PN = "5";
"BST":   PN = "36"  !CDS_PN = "36";
"COMP":   PN = "3"  !CDS_PN = "3";
"EN":   PN = "40"  !CDS_PN = "40";
"FB":   PN = "2"  !CDS_PN = "2";
"GND":   PN = "41"  !CDS_PN = "41";
"ISET":   PN = "4"  !CDS_PN = "4";
"OTS":   PN = "6"  !CDS_PN = "6";
"PG":   PN = "7"  !CDS_PN = "7";
"PGND<0>":   PN = "16"  !CDS_PN = "16";
"PGND<1>":   PN = "17"  !CDS_PN = "17";
"PGND<2>":   PN = "18"  !CDS_PN = "18";
"PGND<3>":   PN = "19"  !CDS_PN = "19";
"PGND<4>":   PN = "20"  !CDS_PN = "20";
"PGND<5>":   PN = "21"  !CDS_PN = "21";
"PGND<6>":   PN = "22"  !CDS_PN = "22";
"PGND<7>":   PN = "23"  !CDS_PN = "23";
"PGND<8>":   PN = "24"  !CDS_PN = "24";
"PGND<9>":   PN = "25"  !CDS_PN = "25";
"PGND<10>":   PN = "26"  !CDS_PN = "26";
"PGND<11>":   PN = "27"  !CDS_PN = "27";
"PGND<12>":   PN = "28"  !CDS_PN = "28";
"PGND<13>":   PN = "37"  !CDS_PN = "37";
"SS":   PN = "1"  !CDS_PN = "1";
"VB":   PN = "38"  !CDS_PN = "38";
"VCC":   PN = "39"  !CDS_PN = "39";
"VIN<0>":   PN = "8"  !CDS_PN = "8";
"VIN<1>":   PN = "9"  !CDS_PN = "9";
"VIN<2>":   PN = "10"  !CDS_PN = "10";
"VIN<3>":   PN = "11"  !CDS_PN = "11";
"VIN<4>":   PN = "12"  !CDS_PN = "12";
"VIN<5>":   PN = "13"  !CDS_PN = "13";
"VIN<6>":   PN = "14"  !CDS_PN = "14";
"VIN<7>":   PN = "42"  !CDS_PN = "42";
"VSW":   PN = "35"  !CDS_PN = "35";
"VSWH<0>":   PN = "15"  !CDS_PN = "15";
"VSWH<1>":   PN = "29"  !CDS_PN = "29";
"VSWH<2>":   PN = "30"  !CDS_PN = "30";
"VSWH<3>":   PN = "31"  !CDS_PN = "31";
"VSWH<4>":   PN = "32"  !CDS_PN = "32";
"VSWH<5>":   PN = "33"  !CDS_PN = "33";
"VSWH<6>":   PN = "34"  !CDS_PN = "34";
"VSWH<7>":   PN = "43"  !CDS_PN = "43";
BODY = "RES","I218": #LOCATION = "R7A15" !CDS_LOCATION = "R7A15" #SEC = "1" !CDS_SEC = "1";
"A":   PN = "1"  !CDS_PN = "1";
"B":   PN = "2"  !CDS_PN = "2";
BODY = "CAP","I220": #LOCATION = "C7A34" !CDS_LOCATION = "C7A34" #SEC = "1" !CDS_SEC = "1";
"A":   PN = "1"  !CDS_PN = "1";
"B":   PN = "2"  !CDS_PN = "2";
BODY = "RES","I227": #LOCATION = "R7B10" !CDS_LOCATION = "R7B10" #SEC = "1" !CDS_SEC = "1";
"A":   PN = "1"  !CDS_PN = "1";
"B":   PN = "2"  !CDS_PN = "2";
BODY = "CAPP","I229": #LOCATION = "C6B7" !CDS_LOCATION = "C6B7" &SEC = "1" #&CDS_SEC = "1";
"A":   PN = "1"  !CDS_PN = "1";
"B":   PN = "2"  !CDS_PN = "2";
BODY = "CAP","I236": #LOCATION = "C6B3" !CDS_LOCATION = "C6B3" &SEC = "1" #&CDS_SEC = "1";
"A":   PN = "1"  !CDS_PN = "1";
"B":   PN = "2"  !CDS_PN = "2";
BODY = "CAP","I238": #LOCATION = "C7B7" !CDS_LOCATION = "C7B7" &SEC = "1" #&CDS_SEC = "1";
"A":   PN = "1"  !CDS_PN = "1";
"B":   PN = "2"  !CDS_PN = "2";
BODY = "INDUCTOR","I239": #LOCATION = "L7B1" !CDS_LOCATION = "L7B1" &SEC = "1" #&CDS_SEC = "1";
"INA":   PN = "1"  !CDS_PN = "1";
"INB":   PN = "2"  !CDS_PN = "2";
BODY = "CAP","I241": #LOCATION = "C7B30" !CDS_LOCATION = "C7B30" &SEC = "1" #&CDS_SEC = "1";
"A":   PN = "1"  !CDS_PN = "1";
"B":   PN = "2"  !CDS_PN = "2";
BODY = "CAP_A","I252": #LOCATION = "C7B6" !CDS_LOCATION = "C7B6" #SEC = "1" !CDS_SEC = "1";
"A":   PN = "1"  !CDS_PN = "1";
"B":   PN = "2"  !CDS_PN = "2";
BODY = "CAP","I253": #LOCATION = "C3M10" !CDS_LOCATION = "C3M10" #SEC = "1" !CDS_SEC = "1";
"A":   PN = "1"  !CDS_PN = "1";
"B":   PN = "2"  !CDS_PN = "2";
BODY = "RES","I257": #LOCATION = "R7B12" !CDS_LOCATION = "R7B12" #SEC = "1" !CDS_SEC = "1";
"A":   PN = "1"  !CDS_PN = "1";
"B":   PN = "2"  !CDS_PN = "2";
BODY = "CAP","I259": #LOCATION = "C3M8" !CDS_LOCATION = "C3M8" #SEC = "1" !CDS_SEC = "1";
"A":   PN = "1"  !CDS_PN = "1";
"B":   PN = "2"  !CDS_PN = "2";
BODY = "CAP","I260": #LOCATION = "C3M15" !CDS_LOCATION = "C3M15" #SEC = "1" !CDS_SEC = "1";
"A":   PN = "1"  !CDS_PN = "1";
"B":   PN = "2"  !CDS_PN = "2";
BODY = "CAP","I261": #LOCATION = "C3M16" !CDS_LOCATION = "C3M16" #SEC = "1" !CDS_SEC = "1";
"A":   PN = "1"  !CDS_PN = "1";
"B":   PN = "2"  !CDS_PN = "2";
BODY = "CAP","I262": #LOCATION = "C7B5" !CDS_LOCATION = "C7B5" #SEC = "1" !CDS_SEC = "1";
"A":   PN = "1"  !CDS_PN = "1";
"B":   PN = "2"  !CDS_PN = "2";
BODY = "CAPP","I267": #LOCATION = "C4M1" !CDS_LOCATION = "C4M1" #SEC = "1" !CDS_SEC = "1";
"A":   PN = "1"  !CDS_PN = "1";
"B":   PN = "2"  !CDS_PN = "2";
BODY = "RES","I298": #LOCATION = "R7B18" !CDS_LOCATION = "R7B18" #SEC = "1" !CDS_SEC = "1";
"A":   PN = "1"  !CDS_PN = "1";
"B":   PN = "2"  !CDS_PN = "2";
BODY = "RES","I299": #LOCATION = "R7B11" !CDS_LOCATION = "R7B11" #SEC = "1" !CDS_SEC = "1";
"A":   PN = "1"  !CDS_PN = "1";
"B":   PN = "2"  !CDS_PN = "2";
BODY = "RES","I300": #LOCATION = "R7B16" !CDS_LOCATION = "R7B16" #SEC = "1" !CDS_SEC = "1";
"A":   PN = "1"  !CDS_PN = "1";
"B":   PN = "2"  !CDS_PN = "2";
BODY = "CAP","I301": #LOCATION = "C7B10" !CDS_LOCATION = "C7B10" #SEC = "1" !CDS_SEC = "1";
"A":   PN = "1"  !CDS_PN = "1";
"B":   PN = "2"  !CDS_PN = "2";
BODY = "CAP","I302": #LOCATION = "C7B13" !CDS_LOCATION = "C7B13" #SEC = "1" !CDS_SEC = "1";
"A":   PN = "1"  !CDS_PN = "1";
"B":   PN = "2"  !CDS_PN = "2";
BODY = "RES","I303": #LOCATION = "R7B15" !CDS_LOCATION = "R7B15" &SEC = "1" #&CDS_SEC = "1";
"A":   PN = "1"  !CDS_PN = "1";
"B":   PN = "2"  !CDS_PN = "2";
BODY = "CAP","I306": #LOCATION = "C7B14" !CDS_LOCATION = "C7B14" #SEC = "1" !CDS_SEC = "1";
"A":   PN = "1"  !CDS_PN = "1";
"B":   PN = "2"  !CDS_PN = "2";
BODY = "RES","I307": #LOCATION = "R7B9" !CDS_LOCATION = "R7B9" #SEC = "1" !CDS_SEC = "1";
"A":   PN = "1"  !CDS_PN = "1";
"B":   PN = "2"  !CDS_PN = "2";
BODY = "SC22U16V5MX-4-GP","I309": #LOCATION = "C7B8" !CDS_LOCATION = "C7B8" #SEC = "1" !CDS_SEC = "1";
"1":   PN = "1"  !CDS_PN = "1";
"2":   PN = "2"  !CDS_PN = "2";
BODY = "SC22U16V5MX-4-GP","I311": #LOCATION = "C22W7" !CDS_LOCATION = "C22W7" #SEC = "1" !CDS_SEC = "1";
"1":   PN = "1"  !CDS_PN = "1";
"2":   PN = "2"  !CDS_PN = "2";
BODY = "RES","I313": #LOCATION = "R7B19" !CDS_LOCATION = "R7B19" #SEC = "1" !CDS_SEC = "1";
"A":   PN = "1"  !CDS_PN = "1";
"B":   PN = "2"  !CDS_PN = "2";
BODY = "RES","I314": #LOCATION = "R7B13" !CDS_LOCATION = "R7B13" #SEC = "1" !CDS_SEC = "1";
"A":   PN = "1"  !CDS_PN = "1";
"B":   PN = "2"  !CDS_PN = "2";
BODY = "RES","I315": #LOCATION = "R7B14" !CDS_LOCATION = "R7B14" &SEC = "1" #&CDS_SEC = "1";
"A":   PN = "1"  !CDS_PN = "1";
"B":   PN = "2"  !CDS_PN = "2";
DRAWING = "@baseboard_fab2_lib.baseboard_fab2(sch_1):page233";
BODY = "CAP","I109": #LOCATION = "C7U4" !CDS_LOCATION = "C7U4" &SEC = "1" #&CDS_SEC = "1";
"A":   PN = "1"  !CDS_PN = "1";
"B":   PN = "2"  !CDS_PN = "2";
BODY = "CAP","I111": #LOCATION = "C7U5" !CDS_LOCATION = "C7U5" &SEC = "1" #&CDS_SEC = "1";
"A":   PN = "1"  !CDS_PN = "1";
"B":   PN = "2"  !CDS_PN = "2";
BODY = "CAP","I112": #LOCATION = "C7T2" !CDS_LOCATION = "C7T2" &SEC = "1" #&CDS_SEC = "1";
"A":   PN = "1"  !CDS_PN = "1";
"B":   PN = "2"  !CDS_PN = "2";
BODY = "CAP","I113": #LOCATION = "C7T3" !CDS_LOCATION = "C7T3" &SEC = "1" #&CDS_SEC = "1";
"A":   PN = "1"  !CDS_PN = "1";
"B":   PN = "2"  !CDS_PN = "2";
BODY = "CAP","I115": #LOCATION = "C7U6" !CDS_LOCATION = "C7U6" &SEC = "1" #&CDS_SEC = "1";
"A":   PN = "1"  !CDS_PN = "1";
"B":   PN = "2"  !CDS_PN = "2";
BODY = "CAP","I116": #LOCATION = "C3F3" !CDS_LOCATION = "C3F3" &SEC = "1" #&CDS_SEC = "1";
"A":   PN = "1"  !CDS_PN = "1";
"B":   PN = "2"  !CDS_PN = "2";
BODY = "CAP","I117": #LOCATION = "C3F4" !CDS_LOCATION = "C3F4" &SEC = "1" #&CDS_SEC = "1";
"A":   PN = "1"  !CDS_PN = "1";
"B":   PN = "2"  !CDS_PN = "2";
BODY = "CAP","I118": #LOCATION = "C3G3" !CDS_LOCATION = "C3G3" &SEC = "1" #&CDS_SEC = "1";
"A":   PN = "1"  !CDS_PN = "1";
"B":   PN = "2"  !CDS_PN = "2";
BODY = "CAP","I132": #LOCATION = "C3G7" !CDS_LOCATION = "C3G7" &SEC = "1" #&CDS_SEC = "1";
"A":   PN = "1"  !CDS_PN = "1";
"B":   PN = "2"  !CDS_PN = "2";
BODY = "CAP","I133": #LOCATION = "C3G4" !CDS_LOCATION = "C3G4" &SEC = "1" #&CDS_SEC = "1";
"A":   PN = "1"  !CDS_PN = "1";
"B":   PN = "2"  !CDS_PN = "2";
BODY = "CAP","I135": #LOCATION = "C3G8" !CDS_LOCATION = "C3G8" &SEC = "1" #&CDS_SEC = "1";
"A":   PN = "1"  !CDS_PN = "1";
"B":   PN = "2"  !CDS_PN = "2";
BODY = "CAP","I136": #LOCATION = "C7U3" !CDS_LOCATION = "C7U3" #SEC = "1" !CDS_SEC = "1";
"A":   PN = "1"  !CDS_PN = "1";
"B":   PN = "2"  !CDS_PN = "2";
BODY = "RES","I157": #LOCATION = "R4G25" !CDS_LOCATION = "R4G25" &SEC = "1" #&CDS_SEC = "1";
"A":   PN = "1"  !CDS_PN = "1";
"B":   PN = "2"  !CDS_PN = "2";
BODY = "RES","I182": #LOCATION = "R4G5" !CDS_LOCATION = "R4G5" &SEC = "1" #&CDS_SEC = "1";
"A":   PN = "1"  !CDS_PN = "1";
"B":   PN = "2"  !CDS_PN = "2";
BODY = "CAP","I183": #LOCATION = "C4G7" !CDS_LOCATION = "C4G7" &SEC = "1" #&CDS_SEC = "1";
"A":   PN = "1"  !CDS_PN = "1";
"B":   PN = "2"  !CDS_PN = "2";
BODY = "RES","I185": #LOCATION = "R4G14" !CDS_LOCATION = "R4G14" #SEC = "1" !CDS_SEC = "1";
"A":   PN = "1"  !CDS_PN = "1";
"B":   PN = "2"  !CDS_PN = "2";
BODY = "CAP","I187": #LOCATION = "C6U6" !CDS_LOCATION = "C6U6" #SEC = "1" !CDS_SEC = "1";
"A":   PN = "1"  !CDS_PN = "1";
"B":   PN = "2"  !CDS_PN = "2";
BODY = "CAP","I194": #LOCATION = "C4G8" !CDS_LOCATION = "C4G8" #SEC = "1" !CDS_SEC = "1";
"A":   PN = "1"  !CDS_PN = "1";
"B":   PN = "2"  !CDS_PN = "2";
BODY = "CAP","I196": #LOCATION = "C4G4" !CDS_LOCATION = "C4G4" &SEC = "1" #&CDS_SEC = "1";
"A":   PN = "1"  !CDS_PN = "1";
"B":   PN = "2"  !CDS_PN = "2";
BODY = "FERRITE","I198": #LOCATION = "FB4G1" !CDS_LOCATION = "FB4G1" #SEC = "1" !CDS_SEC = "1";
"A":   PN = "1"  !CDS_PN = "1";
"B":   PN = "2"  !CDS_PN = "2";
BODY = "CAP","I201": #LOCATION = "C4G9" !CDS_LOCATION = "C4G9" &SEC = "1" #&CDS_SEC = "1";
"A":   PN = "1"  !CDS_PN = "1";
"B":   PN = "2"  !CDS_PN = "2";
BODY = "RES","I208": #LOCATION = "R4F6" !CDS_LOCATION = "R4F6" &SEC = "1" #&CDS_SEC = "1";
"A":   PN = "1"  !CDS_PN = "1";
"B":   PN = "2"  !CDS_PN = "2";
BODY = "CAP","I209": #LOCATION = "C4F12" !CDS_LOCATION = "C4F12" &SEC = "1" #&CDS_SEC = "1";
"A":   PN = "1"  !CDS_PN = "1";
"B":   PN = "2"  !CDS_PN = "2";
BODY = "RES","I211": #LOCATION = "R4G6" !CDS_LOCATION = "R4G6" &SEC = "1" #&CDS_SEC = "1";
"A":   PN = "1"  !CDS_PN = "1";
"B":   PN = "2"  !CDS_PN = "2";
BODY = "CAPP","I217": #LOCATION = "C4F7" !CDS_LOCATION = "C4F7" &SEC = "1" #&CDS_SEC = "1";
"A":   PN = "1"  !CDS_PN = "1";
"B":   PN = "2"  !CDS_PN = "2";
BODY = "CAP","I221": #LOCATION = "C6U3" !CDS_LOCATION = "C6U3" &SEC = "1" #&CDS_SEC = "1";
"A":   PN = "1"  !CDS_PN = "1";
"B":   PN = "2"  !CDS_PN = "2";
BODY = "CAP","I223": #LOCATION = "C6U2" !CDS_LOCATION = "C6U2" &SEC = "1" #&CDS_SEC = "1";
"A":   PN = "1"  !CDS_PN = "1";
"B":   PN = "2"  !CDS_PN = "2";
BODY = "CAP","I224": #LOCATION = "C4G26" !CDS_LOCATION = "C4G26" &SEC = "1" #&CDS_SEC = "1";
"A":   PN = "1"  !CDS_PN = "1";
"B":   PN = "2"  !CDS_PN = "2";
BODY = "NCP3232L","I225": #LOCATION = "EU4G1" !CDS_LOCATION = "EU4G1" #SEC = "1" !CDS_SEC = "1";
"AGND":   PN = "5"  !CDS_PN = "5";
"BST":   PN = "36"  !CDS_PN = "36";
"COMP":   PN = "3"  !CDS_PN = "3";
"EN":   PN = "40"  !CDS_PN = "40";
"FB":   PN = "2"  !CDS_PN = "2";
"GND":   PN = "41"  !CDS_PN = "41";
"ISET":   PN = "4"  !CDS_PN = "4";
"OTS":   PN = "6"  !CDS_PN = "6";
"PG":   PN = "7"  !CDS_PN = "7";
"PGND<0>":   PN = "16"  !CDS_PN = "16";
"PGND<1>":   PN = "17"  !CDS_PN = "17";
"PGND<2>":   PN = "18"  !CDS_PN = "18";
"PGND<3>":   PN = "19"  !CDS_PN = "19";
"PGND<4>":   PN = "20"  !CDS_PN = "20";
"PGND<5>":   PN = "21"  !CDS_PN = "21";
"PGND<6>":   PN = "22"  !CDS_PN = "22";
"PGND<7>":   PN = "23"  !CDS_PN = "23";
"PGND<8>":   PN = "24"  !CDS_PN = "24";
"PGND<9>":   PN = "25"  !CDS_PN = "25";
"PGND<10>":   PN = "26"  !CDS_PN = "26";
"PGND<11>":   PN = "27"  !CDS_PN = "27";
"PGND<12>":   PN = "28"  !CDS_PN = "28";
"PGND<13>":   PN = "37"  !CDS_PN = "37";
"SS":   PN = "1"  !CDS_PN = "1";
"VB":   PN = "38"  !CDS_PN = "38";
"VCC":   PN = "39"  !CDS_PN = "39";
"VIN<0>":   PN = "8"  !CDS_PN = "8";
"VIN<1>":   PN = "9"  !CDS_PN = "9";
"VIN<2>":   PN = "10"  !CDS_PN = "10";
"VIN<3>":   PN = "11"  !CDS_PN = "11";
"VIN<4>":   PN = "12"  !CDS_PN = "12";
"VIN<5>":   PN = "13"  !CDS_PN = "13";
"VIN<6>":   PN = "14"  !CDS_PN = "14";
"VIN<7>":   PN = "42"  !CDS_PN = "42";
"VSW":   PN = "35"  !CDS_PN = "35";
"VSWH<0>":   PN = "15"  !CDS_PN = "15";
"VSWH<1>":   PN = "29"  !CDS_PN = "29";
"VSWH<2>":   PN = "30"  !CDS_PN = "30";
"VSWH<3>":   PN = "31"  !CDS_PN = "31";
"VSWH<4>":   PN = "32"  !CDS_PN = "32";
"VSWH<5>":   PN = "33"  !CDS_PN = "33";
"VSWH<6>":   PN = "34"  !CDS_PN = "34";
"VSWH<7>":   PN = "43"  !CDS_PN = "43";
BODY = "CAP_A","I242": #LOCATION = "C6U5" !CDS_LOCATION = "C6U5" #SEC = "1" !CDS_SEC = "1";
"A":   PN = "1"  !CDS_PN = "1";
"B":   PN = "2"  !CDS_PN = "2";
BODY = "RES","I247": #LOCATION = "R4G12" !CDS_LOCATION = "R4G12" #SEC = "1" !CDS_SEC = "1";
"A":   PN = "1"  !CDS_PN = "1";
"B":   PN = "2"  !CDS_PN = "2";
BODY = "CAP","I248": #LOCATION = "C6U4" !CDS_LOCATION = "C6U4" #SEC = "1" !CDS_SEC = "1";
"A":   PN = "1"  !CDS_PN = "1";
"B":   PN = "2"  !CDS_PN = "2";
BODY = "CAP","I253": #LOCATION = "C4G2" !CDS_LOCATION = "C4G2" #SEC = "1" !CDS_SEC = "1";
"A":   PN = "1"  !CDS_PN = "1";
"B":   PN = "2"  !CDS_PN = "2";
BODY = "CAP","I254": #LOCATION = "C6U7" !CDS_LOCATION = "C6U7" #SEC = "1" !CDS_SEC = "1";
"A":   PN = "1"  !CDS_PN = "1";
"B":   PN = "2"  !CDS_PN = "2";
BODY = "CAP","I255": #LOCATION = "C6U8" !CDS_LOCATION = "C6U8" #SEC = "1" !CDS_SEC = "1";
"A":   PN = "1"  !CDS_PN = "1";
"B":   PN = "2"  !CDS_PN = "2";
BODY = "CAPP","I256": #LOCATION = "C4F11" !CDS_LOCATION = "C4F11" #SEC = "1" !CDS_SEC = "1";
"A":   PN = "1"  !CDS_PN = "1";
"B":   PN = "2"  !CDS_PN = "2";
BODY = "RES","I266": #LOCATION = "R4G10" !CDS_LOCATION = "R4G10" #SEC = "1" !CDS_SEC = "1";
"A":   PN = "1"  !CDS_PN = "1";
"B":   PN = "2"  !CDS_PN = "2";
BODY = "CAP","I267": #LOCATION = "C4G11" !CDS_LOCATION = "C4G11" #SEC = "1" !CDS_SEC = "1";
"A":   PN = "1"  !CDS_PN = "1";
"B":   PN = "2"  !CDS_PN = "2";
BODY = "RES","I270": #LOCATION = "R4G7" !CDS_LOCATION = "R4G7" &SEC = "1" #&CDS_SEC = "1";
"A":   PN = "1"  !CDS_PN = "1";
"B":   PN = "2"  !CDS_PN = "2";
BODY = "RES","I271": #LOCATION = "R4G8" !CDS_LOCATION = "R4G8" #SEC = "1" !CDS_SEC = "1";
"A":   PN = "1"  !CDS_PN = "1";
"B":   PN = "2"  !CDS_PN = "2";
BODY = "RES","I272": #LOCATION = "R4G13" !CDS_LOCATION = "R4G13" #SEC = "1" !CDS_SEC = "1";
"A":   PN = "1"  !CDS_PN = "1";
"B":   PN = "2"  !CDS_PN = "2";
BODY = "CAP","I273": #LOCATION = "C4G6" !CDS_LOCATION = "C4G6" #SEC = "1" !CDS_SEC = "1";
"A":   PN = "1"  !CDS_PN = "1";
"B":   PN = "2"  !CDS_PN = "2";
BODY = "CAP","I274": #LOCATION = "C4G10" !CDS_LOCATION = "C4G10" #SEC = "1" !CDS_SEC = "1";
"A":   PN = "1"  !CDS_PN = "1";
"B":   PN = "2"  !CDS_PN = "2";
BODY = "RES","I275": #LOCATION = "R4G4" !CDS_LOCATION = "R4G4" #SEC = "1" !CDS_SEC = "1";
"A":   PN = "1"  !CDS_PN = "1";
"B":   PN = "2"  !CDS_PN = "2";
BODY = "INDUCTOR","I277": #LOCATION = "L4G1" !CDS_LOCATION = "L4G1" #SEC = "1" !CDS_SEC = "1";
"INA":   PN = "1"  !CDS_PN = "1";
"INB":   PN = "2"  !CDS_PN = "2";
BODY = "SC22U16V5MX-4-GP","I278": #LOCATION = "C22W6" !CDS_LOCATION = "C22W6" #SEC = "1" !CDS_SEC = "1";
"1":   PN = "1"  !CDS_PN = "1";
"2":   PN = "2"  !CDS_PN = "2";
BODY = "SC22U16V5MX-4-GP","I280": #LOCATION = "C4G5" !CDS_LOCATION = "C4G5" #SEC = "1" !CDS_SEC = "1";
"1":   PN = "1"  !CDS_PN = "1";
"2":   PN = "2"  !CDS_PN = "2";
BODY = "RES","I282": #LOCATION = "R4G24" !CDS_LOCATION = "R4G24" #SEC = "1" !CDS_SEC = "1";
"A":   PN = "1"  !CDS_PN = "1";
"B":   PN = "2"  !CDS_PN = "2";
BODY = "RES","I283": #LOCATION = "R4G9" !CDS_LOCATION = "R4G9" #SEC = "1" !CDS_SEC = "1";
"A":   PN = "1"  !CDS_PN = "1";
"B":   PN = "2"  !CDS_PN = "2";
BODY = "RES","I284": #LOCATION = "R4G11" !CDS_LOCATION = "R4G11" &SEC = "1" #&CDS_SEC = "1";
"A":   PN = "1"  !CDS_PN = "1";
"B":   PN = "2"  !CDS_PN = "2";
DRAWING = "@baseboard_fab2_lib.baseboard_fab2(sch_1):page234";
BODY = "RES","I29": #LOCATION = "R4B14" !CDS_LOCATION = "R4B14" &SEC = "1" #&CDS_SEC = "1";
"A":   PN = "1"  !CDS_PN = "1";
"B":   PN = "2"  !CDS_PN = "2";
BODY = "CAP","I84": #LOCATION = "C3B2" !CDS_LOCATION = "C3B2" #SEC = "1" !CDS_SEC = "1";
"A":   PN = "1"  !CDS_PN = "1";
"B":   PN = "2"  !CDS_PN = "2";
BODY = "CAP","I86": #LOCATION = "C3A8" !CDS_LOCATION = "C3A8" &SEC = "1" #&CDS_SEC = "1";
"A":   PN = "1"  !CDS_PN = "1";
"B":   PN = "2"  !CDS_PN = "2";
BODY = "CAP","I87": #LOCATION = "C7L3" !CDS_LOCATION = "C7L3" &SEC = "1" #&CDS_SEC = "1";
"A":   PN = "1"  !CDS_PN = "1";
"B":   PN = "2"  !CDS_PN = "2";
BODY = "CAP","I88": #LOCATION = "C7L2" !CDS_LOCATION = "C7L2" &SEC = "1" #&CDS_SEC = "1";
"A":   PN = "1"  !CDS_PN = "1";
"B":   PN = "2"  !CDS_PN = "2";
BODY = "CAP","I89": #LOCATION = "C7L7" !CDS_LOCATION = "C7L7" &SEC = "1" #&CDS_SEC = "1";
"A":   PN = "1"  !CDS_PN = "1";
"B":   PN = "2"  !CDS_PN = "2";
BODY = "CAP","I90": #LOCATION = "C7L6" !CDS_LOCATION = "C7L6" &SEC = "1" #&CDS_SEC = "1";
"A":   PN = "1"  !CDS_PN = "1";
"B":   PN = "2"  !CDS_PN = "2";
BODY = "CAP","I91": #LOCATION = "C7M4" !CDS_LOCATION = "C7M4" &SEC = "1" #&CDS_SEC = "1";
"A":   PN = "1"  !CDS_PN = "1";
"B":   PN = "2"  !CDS_PN = "2";
BODY = "CAP","I92": #LOCATION = "C7M3" !CDS_LOCATION = "C7M3" &SEC = "1" #&CDS_SEC = "1";
"A":   PN = "1"  !CDS_PN = "1";
"B":   PN = "2"  !CDS_PN = "2";
BODY = "CAP","I93": #LOCATION = "C3A4" !CDS_LOCATION = "C3A4" &SEC = "1" #&CDS_SEC = "1";
"A":   PN = "1"  !CDS_PN = "1";
"B":   PN = "2"  !CDS_PN = "2";
BODY = "CAP","I94": #LOCATION = "C3B1" !CDS_LOCATION = "C3B1" &SEC = "1" #&CDS_SEC = "1";
"A":   PN = "1"  !CDS_PN = "1";
"B":   PN = "2"  !CDS_PN = "2";
BODY = "CAP","I95": #LOCATION = "C3A7" !CDS_LOCATION = "C3A7" &SEC = "1" #&CDS_SEC = "1";
"A":   PN = "1"  !CDS_PN = "1";
"B":   PN = "2"  !CDS_PN = "2";
BODY = "CAP","I97": #LOCATION = "C3A3" !CDS_LOCATION = "C3A3" &SEC = "1" #&CDS_SEC = "1";
"A":   PN = "1"  !CDS_PN = "1";
"B":   PN = "2"  !CDS_PN = "2";
BODY = "CAP","I129": #LOCATION = "C4B5" !CDS_LOCATION = "C4B5" &SEC = "1" #&CDS_SEC = "1";
"A":   PN = "1"  !CDS_PN = "1";
"B":   PN = "2"  !CDS_PN = "2";
BODY = "CAP","I139": #LOCATION = "C4B8" !CDS_LOCATION = "C4B8" &SEC = "1" #&CDS_SEC = "1";
"A":   PN = "1"  !CDS_PN = "1";
"B":   PN = "2"  !CDS_PN = "2";
BODY = "RES","I143": #LOCATION = "R4B10" !CDS_LOCATION = "R4B10" #SEC = "1" !CDS_SEC = "1";
"A":   PN = "1"  !CDS_PN = "1";
"B":   PN = "2"  !CDS_PN = "2";
BODY = "CAP","I144": #LOCATION = "C6L12" !CDS_LOCATION = "C6L12" #SEC = "1" !CDS_SEC = "1";
"A":   PN = "1"  !CDS_PN = "1";
"B":   PN = "2"  !CDS_PN = "2";
BODY = "CAP","I146": #LOCATION = "C4B6" !CDS_LOCATION = "C4B6" #SEC = "1" !CDS_SEC = "1";
"A":   PN = "1"  !CDS_PN = "1";
"B":   PN = "2"  !CDS_PN = "2";
BODY = "CAP","I152": #LOCATION = "C6L11" !CDS_LOCATION = "C6L11" &SEC = "1" #&CDS_SEC = "1";
"A":   PN = "1"  !CDS_PN = "1";
"B":   PN = "2"  !CDS_PN = "2";
BODY = "FERRITE","I154": #LOCATION = "FB4A1" !CDS_LOCATION = "FB4A1" #SEC = "1" !CDS_SEC = "1";
"A":   PN = "1"  !CDS_PN = "1";
"B":   PN = "2"  !CDS_PN = "2";
BODY = "RES","I162": #LOCATION = "R4A7" !CDS_LOCATION = "R4A7" &SEC = "1" #&CDS_SEC = "1";
"A":   PN = "1"  !CDS_PN = "1";
"B":   PN = "2"  !CDS_PN = "2";
BODY = "CAP","I163": #LOCATION = "C4A16" !CDS_LOCATION = "C4A16" &SEC = "1" #&CDS_SEC = "1";
"A":   PN = "1"  !CDS_PN = "1";
"B":   PN = "2"  !CDS_PN = "2";
BODY = "INDUCTOR","I164": #LOCATION = "L4A1" !CDS_LOCATION = "L4A1" &SEC = "1" #&CDS_SEC = "1";
"INA":   PN = "1"  !CDS_PN = "1";
"INB":   PN = "2"  !CDS_PN = "2";
BODY = "CAPP","I167": #LOCATION = "C3B3" !CDS_LOCATION = "C3B3" &SEC = "1" #&CDS_SEC = "1";
"A":   PN = "1"  !CDS_PN = "1";
"B":   PN = "2"  !CDS_PN = "2";
BODY = "CAP","I177": #LOCATION = "C4B3" !CDS_LOCATION = "C4B3" &SEC = "1" #&CDS_SEC = "1";
"A":   PN = "1"  !CDS_PN = "1";
"B":   PN = "2"  !CDS_PN = "2";
BODY = "CAP","I180": #LOCATION = "C4B2" !CDS_LOCATION = "C4B2" &SEC = "1" #&CDS_SEC = "1";
"A":   PN = "1"  !CDS_PN = "1";
"B":   PN = "2"  !CDS_PN = "2";
BODY = "CAP","I182": #LOCATION = "C4B15" !CDS_LOCATION = "C4B15" &SEC = "1" #&CDS_SEC = "1";
"A":   PN = "1"  !CDS_PN = "1";
"B":   PN = "2"  !CDS_PN = "2";
BODY = "RES","I183": #LOCATION = "R4B2" !CDS_LOCATION = "R4B2" &SEC = "1" #&CDS_SEC = "1";
"A":   PN = "1"  !CDS_PN = "1";
"B":   PN = "2"  !CDS_PN = "2";
BODY = "NCP3232L","I184": #LOCATION = "EU4A3" !CDS_LOCATION = "EU4A3" #SEC = "1" !CDS_SEC = "1";
"AGND":   PN = "5"  !CDS_PN = "5";
"BST":   PN = "36"  !CDS_PN = "36";
"COMP":   PN = "3"  !CDS_PN = "3";
"EN":   PN = "40"  !CDS_PN = "40";
"FB":   PN = "2"  !CDS_PN = "2";
"GND":   PN = "41"  !CDS_PN = "41";
"ISET":   PN = "4"  !CDS_PN = "4";
"OTS":   PN = "6"  !CDS_PN = "6";
"PG":   PN = "7"  !CDS_PN = "7";
"PGND<0>":   PN = "16"  !CDS_PN = "16";
"PGND<1>":   PN = "17"  !CDS_PN = "17";
"PGND<2>":   PN = "18"  !CDS_PN = "18";
"PGND<3>":   PN = "19"  !CDS_PN = "19";
"PGND<4>":   PN = "20"  !CDS_PN = "20";
"PGND<5>":   PN = "21"  !CDS_PN = "21";
"PGND<6>":   PN = "22"  !CDS_PN = "22";
"PGND<7>":   PN = "23"  !CDS_PN = "23";
"PGND<8>":   PN = "24"  !CDS_PN = "24";
"PGND<9>":   PN = "25"  !CDS_PN = "25";
"PGND<10>":   PN = "26"  !CDS_PN = "26";
"PGND<11>":   PN = "27"  !CDS_PN = "27";
"PGND<12>":   PN = "28"  !CDS_PN = "28";
"PGND<13>":   PN = "37"  !CDS_PN = "37";
"SS":   PN = "1"  !CDS_PN = "1";
"VB":   PN = "38"  !CDS_PN = "38";
"VCC":   PN = "39"  !CDS_PN = "39";
"VIN<0>":   PN = "8"  !CDS_PN = "8";
"VIN<1>":   PN = "9"  !CDS_PN = "9";
"VIN<2>":   PN = "10"  !CDS_PN = "10";
"VIN<3>":   PN = "11"  !CDS_PN = "11";
"VIN<4>":   PN = "12"  !CDS_PN = "12";
"VIN<5>":   PN = "13"  !CDS_PN = "13";
"VIN<6>":   PN = "14"  !CDS_PN = "14";
"VIN<7>":   PN = "42"  !CDS_PN = "42";
"VSW":   PN = "35"  !CDS_PN = "35";
"VSWH<0>":   PN = "15"  !CDS_PN = "15";
"VSWH<1>":   PN = "29"  !CDS_PN = "29";
"VSWH<2>":   PN = "30"  !CDS_PN = "30";
"VSWH<3>":   PN = "31"  !CDS_PN = "31";
"VSWH<4>":   PN = "32"  !CDS_PN = "32";
"VSWH<5>":   PN = "33"  !CDS_PN = "33";
"VSWH<6>":   PN = "34"  !CDS_PN = "34";
"VSWH<7>":   PN = "43"  !CDS_PN = "43";
BODY = "CAP_A","I199": #LOCATION = "C4A20" !CDS_LOCATION = "C4A20" #SEC = "1" !CDS_SEC = "1";
"A":   PN = "1"  !CDS_PN = "1";
"B":   PN = "2"  !CDS_PN = "2";
BODY = "RES","I201": #LOCATION = "R4B7" !CDS_LOCATION = "R4B7" #SEC = "1" !CDS_SEC = "1";
"A":   PN = "1"  !CDS_PN = "1";
"B":   PN = "2"  !CDS_PN = "2";
BODY = "CAP","I202": #LOCATION = "C6L10" !CDS_LOCATION = "C6L10" #SEC = "1" !CDS_SEC = "1";
"A":   PN = "1"  !CDS_PN = "1";
"B":   PN = "2"  !CDS_PN = "2";
BODY = "CAP","I203": #LOCATION = "C6M3" !CDS_LOCATION = "C6M3" #SEC = "1" !CDS_SEC = "1";
"A":   PN = "1"  !CDS_PN = "1";
"B":   PN = "2"  !CDS_PN = "2";
BODY = "CAP","I204": #LOCATION = "C6M5" !CDS_LOCATION = "C6M5" #SEC = "1" !CDS_SEC = "1";
"A":   PN = "1"  !CDS_PN = "1";
"B":   PN = "2"  !CDS_PN = "2";
BODY = "CAP","I205": #LOCATION = "C4A19" !CDS_LOCATION = "C4A19" #SEC = "1" !CDS_SEC = "1";
"A":   PN = "1"  !CDS_PN = "1";
"B":   PN = "2"  !CDS_PN = "2";
BODY = "CAPP","I210": #LOCATION = "C6L8" !CDS_LOCATION = "C6L8" #SEC = "1" !CDS_SEC = "1";
"A":   PN = "1"  !CDS_PN = "1";
"B":   PN = "2"  !CDS_PN = "2";
BODY = "CAP","I211": #LOCATION = "C4B9" !CDS_LOCATION = "C4B9" #SEC = "1" !CDS_SEC = "1";
"A":   PN = "1"  !CDS_PN = "1";
"B":   PN = "2"  !CDS_PN = "2";
BODY = "CAP","I212": #LOCATION = "C4B4" !CDS_LOCATION = "C4B4" #SEC = "1" !CDS_SEC = "1";
"A":   PN = "1"  !CDS_PN = "1";
"B":   PN = "2"  !CDS_PN = "2";
BODY = "RES","I213": #LOCATION = "R4B8" !CDS_LOCATION = "R4B8" #SEC = "1" !CDS_SEC = "1";
"A":   PN = "1"  !CDS_PN = "1";
"B":   PN = "2"  !CDS_PN = "2";
BODY = "RES","I214": #LOCATION = "R4B3" !CDS_LOCATION = "R4B3" #SEC = "1" !CDS_SEC = "1";
"A":   PN = "1"  !CDS_PN = "1";
"B":   PN = "2"  !CDS_PN = "2";
BODY = "RES","I215": #LOCATION = "R4B5" !CDS_LOCATION = "R4B5" &SEC = "1" #&CDS_SEC = "1";
"A":   PN = "1"  !CDS_PN = "1";
"B":   PN = "2"  !CDS_PN = "2";
BODY = "CAP","I218": #LOCATION = "C4B7" !CDS_LOCATION = "C4B7" #SEC = "1" !CDS_SEC = "1";
"A":   PN = "1"  !CDS_PN = "1";
"B":   PN = "2"  !CDS_PN = "2";
BODY = "RES","I219": #LOCATION = "R4B9" !CDS_LOCATION = "R4B9" #SEC = "1" !CDS_SEC = "1";
"A":   PN = "1"  !CDS_PN = "1";
"B":   PN = "2"  !CDS_PN = "2";
BODY = "RES","I220": #LOCATION = "R4B1" !CDS_LOCATION = "R4B1" #SEC = "1" !CDS_SEC = "1";
"A":   PN = "1"  !CDS_PN = "1";
"B":   PN = "2"  !CDS_PN = "2";
BODY = "SC22U16V5MX-4-GP","I222": #LOCATION = "C22W5" !CDS_LOCATION = "C22W5" #SEC = "1" !CDS_SEC = "1";
"1":   PN = "1"  !CDS_PN = "1";
"2":   PN = "2"  !CDS_PN = "2";
BODY = "SC22U16V5MX-4-GP","I223": #LOCATION = "C4B1" !CDS_LOCATION = "C4B1" #SEC = "1" !CDS_SEC = "1";
"1":   PN = "1"  !CDS_PN = "1";
"2":   PN = "2"  !CDS_PN = "2";
BODY = "RES","I226": #LOCATION = "R4B13" !CDS_LOCATION = "R4B13" #SEC = "1" !CDS_SEC = "1";
"A":   PN = "1"  !CDS_PN = "1";
"B":   PN = "2"  !CDS_PN = "2";
BODY = "RES","I227": #LOCATION = "R4B4" !CDS_LOCATION = "R4B4" #SEC = "1" !CDS_SEC = "1";
"A":   PN = "1"  !CDS_PN = "1";
"B":   PN = "2"  !CDS_PN = "2";
BODY = "RES","I228": #LOCATION = "R4B6" !CDS_LOCATION = "R4B6" &SEC = "1" #&CDS_SEC = "1";
"A":   PN = "1"  !CDS_PN = "1";
"B":   PN = "2"  !CDS_PN = "2";
DRAWING = "@baseboard_fab2_lib.baseboard_fab2(sch_1):page235";
BODY = "CAP_A","I143": #LOCATION = "C8A7" !CDS_LOCATION = "C8A7" #SEC = "1" !CDS_SEC = "1";
"A":   PN = "1"  !CDS_PN = "1";
"B":   PN = "2"  !CDS_PN = "2";
BODY = "CAP_A","I145": #LOCATION = "C8A8" !CDS_LOCATION = "C8A8" #SEC = "1" !CDS_SEC = "1";
"A":   PN = "1"  !CDS_PN = "1";
"B":   PN = "2"  !CDS_PN = "2";
BODY = "RES","I147": #LOCATION = "R2L16" !CDS_LOCATION = "R2L16" #SEC = "1" !CDS_SEC = "1";
"A":   PN = "1"  !CDS_PN = "1";
"B":   PN = "2"  !CDS_PN = "2";
BODY = "RES","I148": #LOCATION = "R2L24" !CDS_LOCATION = "R2L24" #SEC = "1" !CDS_SEC = "1";
"A":   PN = "1"  !CDS_PN = "1";
"B":   PN = "2"  !CDS_PN = "2";
BODY = "RES","I149": #LOCATION = "R8A6" !CDS_LOCATION = "R8A6" #SEC = "1" !CDS_SEC = "1";
"A":   PN = "1"  !CDS_PN = "1";
"B":   PN = "2"  !CDS_PN = "2";
BODY = "CAP_A","I151": #LOCATION = "C2L8" !CDS_LOCATION = "C2L8" #SEC = "1" !CDS_SEC = "1";
"A":   PN = "1"  !CDS_PN = "1";
"B":   PN = "2"  !CDS_PN = "2";
BODY = "CAP","I153": #LOCATION = "C2L2" !CDS_LOCATION = "C2L2" #SEC = "1" !CDS_SEC = "1";
"A":   PN = "1"  !CDS_PN = "1";
"B":   PN = "2"  !CDS_PN = "2";
BODY = "RES","I154": #LOCATION = "R2L8" !CDS_LOCATION = "R2L8" #SEC = "1" !CDS_SEC = "1";
"A":   PN = "1"  !CDS_PN = "1";
"B":   PN = "2"  !CDS_PN = "2";
BODY = "RES","I159": #LOCATION = "R2L14" !CDS_LOCATION = "R2L14" #SEC = "1" !CDS_SEC = "1";
"A":   PN = "1"  !CDS_PN = "1";
"B":   PN = "2"  !CDS_PN = "2";
BODY = "RES","I165": #LOCATION = "R8A4" !CDS_LOCATION = "R8A4" #SEC = "1" !CDS_SEC = "1";
"A":   PN = "1"  !CDS_PN = "1";
"B":   PN = "2"  !CDS_PN = "2";
BODY = "RES","I166": #LOCATION = "R2L10" !CDS_LOCATION = "R2L10" #SEC = "1" !CDS_SEC = "1";
"A":   PN = "1"  !CDS_PN = "1";
"B":   PN = "2"  !CDS_PN = "2";
BODY = "CAP_A","I169": #LOCATION = "C2L11" !CDS_LOCATION = "C2L11" #SEC = "1" !CDS_SEC = "1";
"A":   PN = "1"  !CDS_PN = "1";
"B":   PN = "2"  !CDS_PN = "2";
BODY = "CAP","I209": #LOCATION = "C8A2" !CDS_LOCATION = "C8A2" #SEC = "1" !CDS_SEC = "1";
"A":   PN = "1"  !CDS_PN = "1";
"B":   PN = "2"  !CDS_PN = "2";
BODY = "RES","I210": #LOCATION = "R8A1" !CDS_LOCATION = "R8A1" #SEC = "1" !CDS_SEC = "1";
"A":   PN = "1"  !CDS_PN = "1";
"B":   PN = "2"  !CDS_PN = "2";
BODY = "RES","I216": #LOCATION = "R8A5" !CDS_LOCATION = "R8A5" #SEC = "1" !CDS_SEC = "1";
"A":   PN = "1"  !CDS_PN = "1";
"B":   PN = "2"  !CDS_PN = "2";
BODY = "RES","I217": #LOCATION = "R8A2" !CDS_LOCATION = "R8A2" #SEC = "1" !CDS_SEC = "1";
"A":   PN = "1"  !CDS_PN = "1";
"B":   PN = "2"  !CDS_PN = "2";
BODY = "CAP","I218": #LOCATION = "C8A9" !CDS_LOCATION = "C8A9" #SEC = "1" !CDS_SEC = "1";
"A":   PN = "1"  !CDS_PN = "1";
"B":   PN = "2"  !CDS_PN = "2";
BODY = "RES","I221": #LOCATION = "R2L17" !CDS_LOCATION = "R2L17" #SEC = "1" !CDS_SEC = "1";
"A":   PN = "1"  !CDS_PN = "1";
"B":   PN = "2"  !CDS_PN = "2";
BODY = "RES","I222": #LOCATION = "R8A7" !CDS_LOCATION = "R8A7" #SEC = "1" !CDS_SEC = "1";
"A":   PN = "1"  !CDS_PN = "1";
"B":   PN = "2"  !CDS_PN = "2";
BODY = "PXE1110B","I229": #LOCATION = "EU8A1" !CDS_LOCATION = "EU8A1" #SEC = "1" !CDS_SEC = "1";
"AIREF1":   PN = "21"  !CDS_PN = "21";
"AISEN1":   PN = "22"  !CDS_PN = "22";
"APWM1":   PN = "5"  !CDS_PN = "5";
"ATSEN":   PN = "35"  !CDS_PN = "35";
"AVREF":   PN = "20"  !CDS_PN = "20";
"AVREN":   PN = "10"  !CDS_PN = "10";
"AVRRDY":   PN = "9"  !CDS_PN = "9";
"AVSEN":   PN = "19"  !CDS_PN = "19";
"BIREF1":   PN = "25"  !CDS_PN = "25";
"BISEN1":   PN = "26"  !CDS_PN = "26";
"BPWM1":   PN = "3"  !CDS_PN = "3";
"BTSEN":   PN = "34"  !CDS_PN = "34";
"BVREF":   PN = "30"  !CDS_PN = "30";
"BVSEN":   PN = "29"  !CDS_PN = "29";
"DNC<0>":   PN = "1"  !CDS_PN = "1";
"DNC<1>":   PN = "2"  !CDS_PN = "2";
"DNC<2>":   PN = "4"  !CDS_PN = "4";
"DNC<3>":   PN = "24"  !CDS_PN = "24";
"DNC<4>":   PN = "28"  !CDS_PN = "28";
"GND<0>":   PN = "27"  !CDS_PN = "27";
"GND<1>":   PN = "23"  !CDS_PN = "23";
"IINSEN":   PN = "38"  !CDS_PN = "38";
"MP0":   PN = "13"  !CDS_PN = "13";
"MP1":   PN = "14"  !CDS_PN = "14";
"MP2":   PN = "18"  !CDS_PN = "18";
"MP3":   PN = "31"  !CDS_PN = "31";
"MP4":   PN = "32"  !CDS_PN = "32";
"PINALRT_N":   PN = "12"  !CDS_PN = "12";
"RESET_N":   PN = "8"  !CDS_PN = "8";
"SCL":   PN = "7"  !CDS_PN = "7";
"SDA":   PN = "6"  !CDS_PN = "6";
"THPAD":   PN = "41"  !CDS_PN = "41";
"VALRT_N":   PN = "17"  !CDS_PN = "17";
"VCLK":   PN = "15"  !CDS_PN = "15";
"VD12":   PN = "40"  !CDS_PN = "40";
"VDD":   PN = "39"  !CDS_PN = "39";
"VDIO":   PN = "16"  !CDS_PN = "16";
"VINSEN":   PN = "37"  !CDS_PN = "37";
"VRHOT_N":   PN = "11"  !CDS_PN = "11";
"XADDR1":   PN = "36"  !CDS_PN = "36";
"XADDR2":   PN = "33"  !CDS_PN = "33";
BODY = "SC22P50V2JN-4GP","I239": #LOCATION = "CF23" !CDS_LOCATION = "CF23" &SEC = "1" #&CDS_SEC = "1";
"1":   PN = "1"  !CDS_PN = "1";
"2":   PN = "2"  !CDS_PN = "2";
BODY = "SC22P50V2JN-4GP","I240": #LOCATION = "CF24" !CDS_LOCATION = "CF24" &SEC = "1" #&CDS_SEC = "1";
"1":   PN = "1"  !CDS_PN = "1";
"2":   PN = "2"  !CDS_PN = "2";
BODY = "RES","I241": #LOCATION = "RF23" !CDS_LOCATION = "RF23" #SEC = "1" !CDS_SEC = "1";
"A":   PN = "1"  !CDS_PN = "1";
"B":   PN = "2"  !CDS_PN = "2";
BODY = "RES","I242": #LOCATION = "RF24" !CDS_LOCATION = "RF24" #SEC = "1" !CDS_SEC = "1";
"A":   PN = "1"  !CDS_PN = "1";
"B":   PN = "2"  !CDS_PN = "2";
BODY = "CAP","I244": #LOCATION = "C4W3" !CDS_LOCATION = "C4W3" #SEC = "1" !CDS_SEC = "1";
"A":   PN = "1"  !CDS_PN = "1";
"B":   PN = "2"  !CDS_PN = "2";
BODY = "CAP","I246": #LOCATION = "C4W4" !CDS_LOCATION = "C4W4" #SEC = "1" !CDS_SEC = "1";
"A":   PN = "1"  !CDS_PN = "1";
"B":   PN = "2"  !CDS_PN = "2";
BODY = "RES","I247": #LOCATION = "R8W2" !CDS_LOCATION = "R8W2" #SEC = "1" !CDS_SEC = "1";
"A":   PN = "1"  !CDS_PN = "1";
"B":   PN = "2"  !CDS_PN = "2";
BODY = "RES","I248": #LOCATION = "R8W3" !CDS_LOCATION = "R8W3" #SEC = "1" !CDS_SEC = "1";
"A":   PN = "1"  !CDS_PN = "1";
"B":   PN = "2"  !CDS_PN = "2";
BODY = "RES","I249": #LOCATION = "R8W8" !CDS_LOCATION = "R8W8" #SEC = "1" !CDS_SEC = "1";
"A":   PN = "1"  !CDS_PN = "1";
"B":   PN = "2"  !CDS_PN = "2";
BODY = "RES","I252": #LOCATION = "R2L25" !CDS_LOCATION = "R2L25" #SEC = "1" !CDS_SEC = "1";
"A":   PN = "1"  !CDS_PN = "1";
"B":   PN = "2"  !CDS_PN = "2";
BODY = "RES","I253": #LOCATION = "R2L26" !CDS_LOCATION = "R2L26" #SEC = "1" !CDS_SEC = "1";
"A":   PN = "1"  !CDS_PN = "1";
"B":   PN = "2"  !CDS_PN = "2";
BODY = "RES","I254": #LOCATION = "R2L9" !CDS_LOCATION = "R2L9" #SEC = "1" !CDS_SEC = "1";
"A":   PN = "1"  !CDS_PN = "1";
"B":   PN = "2"  !CDS_PN = "2";
BODY = "CAP_A","I255": #LOCATION = "C8A3" !CDS_LOCATION = "C8A3" #SEC = "1" !CDS_SEC = "1";
"A":   PN = "1"  !CDS_PN = "1";
"B":   PN = "2"  !CDS_PN = "2";
DRAWING = "@baseboard_fab2_lib.baseboard_fab2(sch_1):page236";
BODY = "CAP","I9": #LOCATION = "C7A30" !CDS_LOCATION = "C7A30" #SEC = "1" !CDS_SEC = "1";
"A":   PN = "1"  !CDS_PN = "1";
"B":   PN = "2"  !CDS_PN = "2";
BODY = "CAP","I16": #LOCATION = "C7A8" !CDS_LOCATION = "C7A8" #SEC = "1" !CDS_SEC = "1";
"A":   PN = "1"  !CDS_PN = "1";
"B":   PN = "2"  !CDS_PN = "2";
BODY = "CAP","I19": #LOCATION = "C7A6" !CDS_LOCATION = "C7A6" #SEC = "1" !CDS_SEC = "1";
"A":   PN = "1"  !CDS_PN = "1";
"B":   PN = "2"  !CDS_PN = "2";
BODY = "CAP_A","I20": #LOCATION = "C7A39" !CDS_LOCATION = "C7A39" #SEC = "1" !CDS_SEC = "1";
"A":   PN = "1"  !CDS_PN = "1";
"B":   PN = "2"  !CDS_PN = "2";
BODY = "CAP","I21": #LOCATION = "C7A43" !CDS_LOCATION = "C7A43" #SEC = "1" !CDS_SEC = "1";
"A":   PN = "1"  !CDS_PN = "1";
"B":   PN = "2"  !CDS_PN = "2";
BODY = "CAP","I22": #LOCATION = "C7A7" !CDS_LOCATION = "C7A7" #SEC = "1" !CDS_SEC = "1";
"A":   PN = "1"  !CDS_PN = "1";
"B":   PN = "2"  !CDS_PN = "2";
BODY = "CAP","I23": #LOCATION = "C3L12" !CDS_LOCATION = "C3L12" #SEC = "1" !CDS_SEC = "1";
"A":   PN = "1"  !CDS_PN = "1";
"B":   PN = "2"  !CDS_PN = "2";
BODY = "CAP","I24": #LOCATION = "C3L11" !CDS_LOCATION = "C3L11" #SEC = "1" !CDS_SEC = "1";
"A":   PN = "1"  !CDS_PN = "1";
"B":   PN = "2"  !CDS_PN = "2";
BODY = "CAP","I26": #LOCATION = "C3L8" !CDS_LOCATION = "C3L8" #SEC = "1" !CDS_SEC = "1";
"A":   PN = "1"  !CDS_PN = "1";
"B":   PN = "2"  !CDS_PN = "2";
BODY = "CAP","I29": #LOCATION = "C3L9" !CDS_LOCATION = "C3L9" #SEC = "1" !CDS_SEC = "1";
"A":   PN = "1"  !CDS_PN = "1";
"B":   PN = "2"  !CDS_PN = "2";
BODY = "CAP","I31": #LOCATION = "C3L7" !CDS_LOCATION = "C3L7" #SEC = "1" !CDS_SEC = "1";
"A":   PN = "1"  !CDS_PN = "1";
"B":   PN = "2"  !CDS_PN = "2";
BODY = "CAP","I32": #LOCATION = "C3L10" !CDS_LOCATION = "C3L10" #SEC = "1" !CDS_SEC = "1";
"A":   PN = "1"  !CDS_PN = "1";
"B":   PN = "2"  !CDS_PN = "2";
BODY = "CAP","I33": #LOCATION = "C7A9" !CDS_LOCATION = "C7A9" #SEC = "1" !CDS_SEC = "1";
"A":   PN = "1"  !CDS_PN = "1";
"B":   PN = "2"  !CDS_PN = "2";
BODY = "CAP","I34": #LOCATION = "C7A44" !CDS_LOCATION = "C7A44" #SEC = "1" !CDS_SEC = "1";
"A":   PN = "1"  !CDS_PN = "1";
"B":   PN = "2"  !CDS_PN = "2";
BODY = "CAP_A","I35": #LOCATION = "C7A40" !CDS_LOCATION = "C7A40" #SEC = "1" !CDS_SEC = "1";
"A":   PN = "1"  !CDS_PN = "1";
"B":   PN = "2"  !CDS_PN = "2";
BODY = "CAP","I36": #LOCATION = "C7A10" !CDS_LOCATION = "C7A10" #SEC = "1" !CDS_SEC = "1";
"A":   PN = "1"  !CDS_PN = "1";
"B":   PN = "2"  !CDS_PN = "2";
BODY = "CAP","I39": #LOCATION = "C7A41" !CDS_LOCATION = "C7A41" #SEC = "1" !CDS_SEC = "1";
"A":   PN = "1"  !CDS_PN = "1";
"B":   PN = "2"  !CDS_PN = "2";
BODY = "CAP","I46": #LOCATION = "C7A42" !CDS_LOCATION = "C7A42" #SEC = "1" !CDS_SEC = "1";
"A":   PN = "1"  !CDS_PN = "1";
"B":   PN = "2"  !CDS_PN = "2";
BODY = "RES","I56": #LOCATION = "R8B14" !CDS_LOCATION = "R8B14" #SEC = "1" !CDS_SEC = "1";
"A":   PN = "1"  !CDS_PN = "1";
"B":   PN = "2"  !CDS_PN = "2";
BODY = "RES","I57": #LOCATION = "R8B15" !CDS_LOCATION = "R8B15" #SEC = "1" !CDS_SEC = "1";
"A":   PN = "1"  !CDS_PN = "1";
"B":   PN = "2"  !CDS_PN = "2";
BODY = "RES","I59": #LOCATION = "R8B12" !CDS_LOCATION = "R8B12" #SEC = "1" !CDS_SEC = "1";
"A":   PN = "1"  !CDS_PN = "1";
"B":   PN = "2"  !CDS_PN = "2";
BODY = "CAPP","I71": #LOCATION = "C3L18" !CDS_LOCATION = "C3L18" #SEC = "1" !CDS_SEC = "1";
"A":   PN = "1"  !CDS_PN = "1";
"B":   PN = "2"  !CDS_PN = "2";
BODY = "CAPP","I73": #LOCATION = "C3L20" !CDS_LOCATION = "C3L20" #SEC = "1" !CDS_SEC = "1";
"A":   PN = "1"  !CDS_PN = "1";
"B":   PN = "2"  !CDS_PN = "2";
BODY = "CAPP","I74": #LOCATION = "C3L21" !CDS_LOCATION = "C3L21" #SEC = "1" !CDS_SEC = "1";
"A":   PN = "1"  !CDS_PN = "1";
"B":   PN = "2"  !CDS_PN = "2";
BODY = "CAPP","I75": #LOCATION = "C7A27" !CDS_LOCATION = "C7A27" #SEC = "1" !CDS_SEC = "1";
"A":   PN = "1"  !CDS_PN = "1";
"B":   PN = "2"  !CDS_PN = "2";
BODY = "CAPP","I76": #LOCATION = "C3L19" !CDS_LOCATION = "C3L19" #SEC = "1" !CDS_SEC = "1";
"A":   PN = "1"  !CDS_PN = "1";
"B":   PN = "2"  !CDS_PN = "2";
BODY = "CAPP","I77": #LOCATION = "C2L46" !CDS_LOCATION = "C2L46" #SEC = "1" !CDS_SEC = "1";
"A":   PN = "1"  !CDS_PN = "1";
"B":   PN = "2"  !CDS_PN = "2";
BODY = "CAPP","I78": #LOCATION = "C8A15" !CDS_LOCATION = "C8A15" #SEC = "1" !CDS_SEC = "1";
"A":   PN = "1"  !CDS_PN = "1";
"B":   PN = "2"  !CDS_PN = "2";
BODY = "CAPP","I79": #LOCATION = "C2L25" !CDS_LOCATION = "C2L25" #SEC = "1" !CDS_SEC = "1";
"A":   PN = "1"  !CDS_PN = "1";
"B":   PN = "2"  !CDS_PN = "2";
BODY = "RES","I90": #LOCATION = "R7A13" !CDS_LOCATION = "R7A13" #SEC = "1" !CDS_SEC = "1";
"A":   PN = "1"  !CDS_PN = "1";
"B":   PN = "2"  !CDS_PN = "2";
BODY = "RES","I92": #LOCATION = "R7A18" !CDS_LOCATION = "R7A18" #SEC = "1" !CDS_SEC = "1";
"A":   PN = "1"  !CDS_PN = "1";
"B":   PN = "2"  !CDS_PN = "2";
BODY = "RES","I93": #LOCATION = "R7A19" !CDS_LOCATION = "R7A19" #SEC = "1" !CDS_SEC = "1";
"A":   PN = "1"  !CDS_PN = "1";
"B":   PN = "2"  !CDS_PN = "2";
BODY = "RES","I94": #LOCATION = "R7A14" !CDS_LOCATION = "R7A14" #SEC = "1" !CDS_SEC = "1";
"A":   PN = "1"  !CDS_PN = "1";
"B":   PN = "2"  !CDS_PN = "2";
BODY = "IR354XX","I116": #LOCATION = "EU7A3" !CDS_LOCATION = "EU7A3" #SEC = "1" !CDS_SEC = "1";
"BOOST":   PN = "33"  !CDS_PN = "33";
"EN":   PN = "35"  !CDS_PN = "35";
"GL<0>":   PN = "6"  !CDS_PN = "6";
"GL<1>":   PN = "41"  !CDS_PN = "41";
"IOUT":   PN = "38"  !CDS_PN = "38";
"LGND":   PN = "2"  !CDS_PN = "2";
"NC":   PN = "31"  !CDS_PN = "31";
"OCSET":   PN = "37"  !CDS_PN = "37";
"PGND<0>":   PN = "5"  !CDS_PN = "5";
"PGND<1>":   PN = "7"  !CDS_PN = "7";
"PGND<2>":   PN = "40"  !CDS_PN = "40";
"PHASE":   PN = "32"  !CDS_PN = "32";
"PWM":   PN = "34"  !CDS_PN = "34";
"REFIN":   PN = "39"  !CDS_PN = "39";
"SW":   PN = "10"  !CDS_PN = "10";
"TOUT_FLT":   PN = "36"  !CDS_PN = "36";
"VCC":   PN = "3"  !CDS_PN = "3";
"VDRV":   PN = "4"  !CDS_PN = "4";
"VIN<0>":   PN = "25"  !CDS_PN = "25";
"VIN<1>":   PN = "30"  !CDS_PN = "30";
"VOS":   PN = "1"  !CDS_PN = "1";
BODY = "IR354XX","I117": #LOCATION = "EU7A2" !CDS_LOCATION = "EU7A2" #SEC = "1" !CDS_SEC = "1";
"BOOST":   PN = "33"  !CDS_PN = "33";
"EN":   PN = "35"  !CDS_PN = "35";
"GL<0>":   PN = "6"  !CDS_PN = "6";
"GL<1>":   PN = "41"  !CDS_PN = "41";
"IOUT":   PN = "38"  !CDS_PN = "38";
"LGND":   PN = "2"  !CDS_PN = "2";
"NC":   PN = "31"  !CDS_PN = "31";
"OCSET":   PN = "37"  !CDS_PN = "37";
"PGND<0>":   PN = "5"  !CDS_PN = "5";
"PGND<1>":   PN = "7"  !CDS_PN = "7";
"PGND<2>":   PN = "40"  !CDS_PN = "40";
"PHASE":   PN = "32"  !CDS_PN = "32";
"PWM":   PN = "34"  !CDS_PN = "34";
"REFIN":   PN = "39"  !CDS_PN = "39";
"SW":   PN = "10"  !CDS_PN = "10";
"TOUT_FLT":   PN = "36"  !CDS_PN = "36";
"VCC":   PN = "3"  !CDS_PN = "3";
"VDRV":   PN = "4"  !CDS_PN = "4";
"VIN<0>":   PN = "25"  !CDS_PN = "25";
"VIN<1>":   PN = "30"  !CDS_PN = "30";
"VOS":   PN = "1"  !CDS_PN = "1";
BODY = "RES","I118": #LOCATION = "R3L15" !CDS_LOCATION = "R3L15" #SEC = "1" !CDS_SEC = "1";
"A":   PN = "1"  !CDS_PN = "1";
"B":   PN = "2"  !CDS_PN = "2";
BODY = "RES","I120": #LOCATION = "R3L14" !CDS_LOCATION = "R3L14" #SEC = "1" !CDS_SEC = "1";
"A":   PN = "1"  !CDS_PN = "1";
"B":   PN = "2"  !CDS_PN = "2";
BODY = "CAP_A","I124": #LOCATION = "CT67" !CDS_LOCATION = "CT67" &SEC = "1" #&CDS_SEC = "1";
"A":   PN = "1"  !CDS_PN = "1";
"B":   PN = "2"  !CDS_PN = "2";
BODY = "CAP_A","I127": #LOCATION = "CT66" !CDS_LOCATION = "CT66" #SEC = "1" !CDS_SEC = "1";
"A":   PN = "1"  !CDS_PN = "1";
"B":   PN = "2"  !CDS_PN = "2";
BODY = "CAP","I134": #LOCATION = "CT69" !CDS_LOCATION = "CT69" #SEC = "1" !CDS_SEC = "1";
"A":   PN = "1"  !CDS_PN = "1";
"B":   PN = "2"  !CDS_PN = "2";
BODY = "CAP","I136": #LOCATION = "CT64" !CDS_LOCATION = "CT64" #SEC = "1" !CDS_SEC = "1";
"A":   PN = "1"  !CDS_PN = "1";
"B":   PN = "2"  !CDS_PN = "2";
BODY = "CAP","I149": #LOCATION = "CT65" !CDS_LOCATION = "CT65" #SEC = "1" !CDS_SEC = "1";
"A":   PN = "1"  !CDS_PN = "1";
"B":   PN = "2"  !CDS_PN = "2";
BODY = "CAP","I150": #LOCATION = "CT68" !CDS_LOCATION = "CT68" #SEC = "1" !CDS_SEC = "1";
"A":   PN = "1"  !CDS_PN = "1";
"B":   PN = "2"  !CDS_PN = "2";
BODY = "RES","I153": #LOCATION = "RT44" !CDS_LOCATION = "RT44" #SEC = "1" !CDS_SEC = "1";
"A":   PN = "1"  !CDS_PN = "1";
"B":   PN = "2"  !CDS_PN = "2";
BODY = "RES","I154": #LOCATION = "RT46" !CDS_LOCATION = "RT46" #SEC = "1" !CDS_SEC = "1";
"A":   PN = "1"  !CDS_PN = "1";
"B":   PN = "2"  !CDS_PN = "2";
BODY = "SC22U16V5MX-4-GP","I159": #LOCATION = "C22W23" !CDS_LOCATION = "C22W23" #SEC = "1" !CDS_SEC = "1";
"1":   PN = "1"  !CDS_PN = "1";
"2":   PN = "2"  !CDS_PN = "2";
BODY = "SC22U16V5MX-4-GP","I160": #LOCATION = "C22W24" !CDS_LOCATION = "C22W24" #SEC = "1" !CDS_SEC = "1";
"1":   PN = "1"  !CDS_PN = "1";
"2":   PN = "2"  !CDS_PN = "2";
BODY = "SC22U16V5MX-4-GP","I161": #LOCATION = "C7A13" !CDS_LOCATION = "C7A13" #SEC = "1" !CDS_SEC = "1";
"1":   PN = "1"  !CDS_PN = "1";
"2":   PN = "2"  !CDS_PN = "2";
BODY = "SC22U16V5MX-4-GP","I162": #LOCATION = "C22W25" !CDS_LOCATION = "C22W25" #SEC = "1" !CDS_SEC = "1";
"1":   PN = "1"  !CDS_PN = "1";
"2":   PN = "2"  !CDS_PN = "2";
BODY = "SC22U16V5MX-4-GP","I163": #LOCATION = "C22W27" !CDS_LOCATION = "C22W27" #SEC = "1" !CDS_SEC = "1";
"1":   PN = "1"  !CDS_PN = "1";
"2":   PN = "2"  !CDS_PN = "2";
BODY = "SC22U16V5MX-4-GP","I165": #LOCATION = "C22W26" !CDS_LOCATION = "C22W26" #SEC = "1" !CDS_SEC = "1";
"1":   PN = "1"  !CDS_PN = "1";
"2":   PN = "2"  !CDS_PN = "2";
BODY = "SC22U16V5MX-4-GP","I171": #LOCATION = "C22W22" !CDS_LOCATION = "C22W22" #SEC = "1" !CDS_SEC = "1";
"1":   PN = "1"  !CDS_PN = "1";
"2":   PN = "2"  !CDS_PN = "2";
BODY = "SC22U16V5MX-4-GP","I172": #LOCATION = "C7A14" !CDS_LOCATION = "C7A14" #SEC = "1" !CDS_SEC = "1";
"1":   PN = "1"  !CDS_PN = "1";
"2":   PN = "2"  !CDS_PN = "2";
BODY = "RES","I175": #LOCATION = "R3L1" !CDS_LOCATION = "R3L1" #SEC = "1" !CDS_SEC = "1";
"A":   PN = "1"  !CDS_PN = "1";
"B":   PN = "2"  !CDS_PN = "2";
BODY = "RES","I177": #LOCATION = "R3L4" !CDS_LOCATION = "R3L4" #SEC = "1" !CDS_SEC = "1";
"A":   PN = "1"  !CDS_PN = "1";
"B":   PN = "2"  !CDS_PN = "2";
BODY = "IND-300NH-20-GP","I178": #LOCATION = "L7A2" !CDS_LOCATION = "L7A2" #SEC = "1" !CDS_SEC = "1";
"F":   PN = "2"  !CDS_PN = "2";
"S":   PN = "1"  !CDS_PN = "1";
BODY = "IND-300NH-20-GP","I179": #LOCATION = "L7A4" !CDS_LOCATION = "L7A4" #SEC = "1" !CDS_SEC = "1";
"F":   PN = "2"  !CDS_PN = "2";
"S":   PN = "1"  !CDS_PN = "1";
BODY = "SC1U10V2KX-4-GP","I180": #LOCATION = "C3L1" !CDS_LOCATION = "C3L1" #SEC = "1" !CDS_SEC = "1";
"1":   PN = "1"  !CDS_PN = "1";
"2":   PN = "2"  !CDS_PN = "2";
BODY = "SC1U10V2KX-4-GP","I181": #LOCATION = "C3L29" !CDS_LOCATION = "C3L29" #SEC = "1" !CDS_SEC = "1";
"1":   PN = "1"  !CDS_PN = "1";
"2":   PN = "2"  !CDS_PN = "2";
BODY = "1R3F-GP","I182": #LOCATION = "RT43" !CDS_LOCATION = "RT43" #SEC = "1" !CDS_SEC = "1";
"1":   PN = "1"  !CDS_PN = "1";
"2":   PN = "2"  !CDS_PN = "2";
BODY = "1R3F-GP","I183": #LOCATION = "RT45" !CDS_LOCATION = "RT45" #SEC = "1" !CDS_SEC = "1";
"1":   PN = "1"  !CDS_PN = "1";
"2":   PN = "2"  !CDS_PN = "2";
DRAWING = "@baseboard_fab2_lib.baseboard_fab2(sch_1):page237";
BODY = "RES","I3": #LOCATION = "R8A10" !CDS_LOCATION = "R8A10" &SEC = "1" #&CDS_SEC = "1";
"A":   PN = "1"  !CDS_PN = "1";
"B":   PN = "2"  !CDS_PN = "2";
BODY = "CAP","I5": #LOCATION = "C8A11" !CDS_LOCATION = "C8A11" &SEC = "1" #&CDS_SEC = "1";
"A":   PN = "1"  !CDS_PN = "1";
"B":   PN = "2"  !CDS_PN = "2";
BODY = "CAP","I12": #LOCATION = "C2L45" !CDS_LOCATION = "C2L45" &SEC = "1" #&CDS_SEC = "1";
"A":   PN = "1"  !CDS_PN = "1";
"B":   PN = "2"  !CDS_PN = "2";
BODY = "CAP","I13": #LOCATION = "C8A14" !CDS_LOCATION = "C8A14" #SEC = "1" !CDS_SEC = "1";
"A":   PN = "1"  !CDS_PN = "1";
"B":   PN = "2"  !CDS_PN = "2";
BODY = "RES","I15": #LOCATION = "R8A12" !CDS_LOCATION = "R8A12" #SEC = "1" !CDS_SEC = "1";
"A":   PN = "1"  !CDS_PN = "1";
"B":   PN = "2"  !CDS_PN = "2";
BODY = "CAP","I29": #LOCATION = "C8A6" !CDS_LOCATION = "C8A6" #SEC = "1" !CDS_SEC = "1";
"A":   PN = "1"  !CDS_PN = "1";
"B":   PN = "2"  !CDS_PN = "2";
BODY = "CAP","I31": #LOCATION = "C8A4" !CDS_LOCATION = "C8A4" #SEC = "1" !CDS_SEC = "1";
"A":   PN = "1"  !CDS_PN = "1";
"B":   PN = "2"  !CDS_PN = "2";
BODY = "CAP","I55": #LOCATION = "C8A10" !CDS_LOCATION = "C8A10" &SEC = "1" #&CDS_SEC = "1";
"A":   PN = "1"  !CDS_PN = "1";
"B":   PN = "2"  !CDS_PN = "2";
BODY = "CAP","I77": #LOCATION = "C8A12" !CDS_LOCATION = "C8A12" #SEC = "1" !CDS_SEC = "1";
"A":   PN = "1"  !CDS_PN = "1";
"B":   PN = "2"  !CDS_PN = "2";
BODY = "CAP","I79": #LOCATION = "C2L32" !CDS_LOCATION = "C2L32" #SEC = "1" !CDS_SEC = "1";
"A":   PN = "1"  !CDS_PN = "1";
"B":   PN = "2"  !CDS_PN = "2";
BODY = "RES","I80": #LOCATION = "R2L19" !CDS_LOCATION = "R2L19" #SEC = "1" !CDS_SEC = "1";
"A":   PN = "1"  !CDS_PN = "1";
"B":   PN = "2"  !CDS_PN = "2";
BODY = "RES","I81": #LOCATION = "R2L20" !CDS_LOCATION = "R2L20" #SEC = "1" !CDS_SEC = "1";
"A":   PN = "1"  !CDS_PN = "1";
"B":   PN = "2"  !CDS_PN = "2";
BODY = "RT9059","I86": #LOCATION = "EU8A2" !CDS_LOCATION = "EU8A2" #SEC = "1" !CDS_SEC = "1";
"ADJ_NC":   PN = "4"  !CDS_PN = "4";
"EN":   PN = "6"  !CDS_PN = "6";
"GND":   PN = "11"  !CDS_PN = "11";
"PGOOD":   PN = "5"  !CDS_PN = "5";
"VDD":   PN = "10"  !CDS_PN = "10";
"VIN<0>":   PN = "7"  !CDS_PN = "7";
"VIN<1>":   PN = "8"  !CDS_PN = "8";
"VIN<2>":   PN = "9"  !CDS_PN = "9";
"VOUT<0>":   PN = "1"  !CDS_PN = "1";
"VOUT<1>":   PN = "2"  !CDS_PN = "2";
"VOUT<2>":   PN = "3"  !CDS_PN = "3";
BODY = "RES","I90": #LOCATION = "R8A11" !CDS_LOCATION = "R8A11" #SEC = "1" !CDS_SEC = "1";
"A":   PN = "1"  !CDS_PN = "1";
"B":   PN = "2"  !CDS_PN = "2";
DRAWING = "@baseboard_fab2_lib.baseboard_fab2(sch_1):page238";
BODY = "CAP","I5": #LOCATION = "C9F9" !CDS_LOCATION = "C9F9" &SEC = "1" #&CDS_SEC = "1";
"A":   PN = "1"  !CDS_PN = "1";
"B":   PN = "2"  !CDS_PN = "2";
BODY = "CAP","I7": #LOCATION = "C9F3" !CDS_LOCATION = "C9F3" #SEC = "1" !CDS_SEC = "1";
"A":   PN = "1"  !CDS_PN = "1";
"B":   PN = "2"  !CDS_PN = "2";
BODY = "RES","I14": #LOCATION = "R9F8" !CDS_LOCATION = "R9F8" #SEC = "1" !CDS_SEC = "1";
"A":   PN = "1"  !CDS_PN = "1";
"B":   PN = "2"  !CDS_PN = "2";
BODY = "CAP","I19": #LOCATION = "C9F8" !CDS_LOCATION = "C9F8" &SEC = "1" #&CDS_SEC = "1";
"A":   PN = "1"  !CDS_PN = "1";
"B":   PN = "2"  !CDS_PN = "2";
BODY = "RES","I21": #LOCATION = "R9F13" !CDS_LOCATION = "R9F13" #SEC = "1" !CDS_SEC = "1";
"A":   PN = "1"  !CDS_PN = "1";
"B":   PN = "2"  !CDS_PN = "2";
BODY = "CAP","I23": #LOCATION = "C9E10" !CDS_LOCATION = "C9E10" #SEC = "1" !CDS_SEC = "1";
"A":   PN = "1"  !CDS_PN = "1";
"B":   PN = "2"  !CDS_PN = "2";
BODY = "CAP","I30": #LOCATION = "C9F4" !CDS_LOCATION = "C9F4" #SEC = "1" !CDS_SEC = "1";
"A":   PN = "1"  !CDS_PN = "1";
"B":   PN = "2"  !CDS_PN = "2";
BODY = "CAP","I39": #LOCATION = "C9E11" !CDS_LOCATION = "C9E11" #SEC = "1" !CDS_SEC = "1";
"A":   PN = "1"  !CDS_PN = "1";
"B":   PN = "2"  !CDS_PN = "2";
BODY = "RT9059","I40": #LOCATION = "EU9F1" !CDS_LOCATION = "EU9F1" #SEC = "1" !CDS_SEC = "1";
"ADJ_NC":   PN = "4"  !CDS_PN = "4";
"EN":   PN = "6"  !CDS_PN = "6";
"GND":   PN = "11"  !CDS_PN = "11";
"PGOOD":   PN = "5"  !CDS_PN = "5";
"VDD":   PN = "10"  !CDS_PN = "10";
"VIN<0>":   PN = "7"  !CDS_PN = "7";
"VIN<1>":   PN = "8"  !CDS_PN = "8";
"VIN<2>":   PN = "9"  !CDS_PN = "9";
"VOUT<0>":   PN = "1"  !CDS_PN = "1";
"VOUT<1>":   PN = "2"  !CDS_PN = "2";
"VOUT<2>":   PN = "3"  !CDS_PN = "3";
BODY = "RES","I41": #LOCATION = "R9F11" !CDS_LOCATION = "R9F11" #SEC = "1" !CDS_SEC = "1";
"A":   PN = "1"  !CDS_PN = "1";
"B":   PN = "2"  !CDS_PN = "2";
BODY = "4K42R2F-GP","I45": #LOCATION = "R9F6" !CDS_LOCATION = "R9F6" &SEC = "1" #&CDS_SEC = "1";
"1":   PN = "1"  !CDS_PN = "1";
"2":   PN = "2"  !CDS_PN = "2";
BODY = "CAP","I46": #LOCATION = "C9W14" !CDS_LOCATION = "C9W14" #SEC = "1" !CDS_SEC = "1";
"A":   PN = "1"  !CDS_PN = "1";
"B":   PN = "2"  !CDS_PN = "2";
BODY = "CAP_A","I50": #LOCATION = "C9W16" !CDS_LOCATION = "C9W16" &SEC = "1" #&CDS_SEC = "1";
"A":   PN = "1"  !CDS_PN = "1";
"B":   PN = "2"  !CDS_PN = "2";
DRAWING = "@baseboard_fab2_lib.baseboard_fab2(sch_1):page239";
BODY = "CAP","I4": #LOCATION = "C9F10" !CDS_LOCATION = "C9F10" &SEC = "1" #&CDS_SEC = "1";
"A":   PN = "1"  !CDS_PN = "1";
"B":   PN = "2"  !CDS_PN = "2";
BODY = "RES","I6": #LOCATION = "R9F12" !CDS_LOCATION = "R9F12" #SEC = "1" !CDS_SEC = "1";
"A":   PN = "1"  !CDS_PN = "1";
"B":   PN = "2"  !CDS_PN = "2";
BODY = "CAP","I7": #LOCATION = "C9F13" !CDS_LOCATION = "C9F13" #SEC = "1" !CDS_SEC = "1";
"A":   PN = "1"  !CDS_PN = "1";
"B":   PN = "2"  !CDS_PN = "2";
BODY = "CAP","I12": #LOCATION = "C1T15" !CDS_LOCATION = "C1T15" #SEC = "1" !CDS_SEC = "1";
"A":   PN = "1"  !CDS_PN = "1";
"B":   PN = "2"  !CDS_PN = "2";
BODY = "CAP","I22": #LOCATION = "C1T7" !CDS_LOCATION = "C1T7" #SEC = "1" !CDS_SEC = "1";
"A":   PN = "1"  !CDS_PN = "1";
"B":   PN = "2"  !CDS_PN = "2";
BODY = "CAP","I30": #LOCATION = "C9F6" !CDS_LOCATION = "C9F6" &SEC = "1" #&CDS_SEC = "1";
"A":   PN = "1"  !CDS_PN = "1";
"B":   PN = "2"  !CDS_PN = "2";
BODY = "RT9059","I70": #LOCATION = "EU9F2" !CDS_LOCATION = "EU9F2" #SEC = "1" !CDS_SEC = "1";
"ADJ_NC":   PN = "4"  !CDS_PN = "4";
"EN":   PN = "6"  !CDS_PN = "6";
"GND":   PN = "11"  !CDS_PN = "11";
"PGOOD":   PN = "5"  !CDS_PN = "5";
"VDD":   PN = "10"  !CDS_PN = "10";
"VIN<0>":   PN = "7"  !CDS_PN = "7";
"VIN<1>":   PN = "8"  !CDS_PN = "8";
"VIN<2>":   PN = "9"  !CDS_PN = "9";
"VOUT<0>":   PN = "1"  !CDS_PN = "1";
"VOUT<1>":   PN = "2"  !CDS_PN = "2";
"VOUT<2>":   PN = "3"  !CDS_PN = "3";
BODY = "CAP_A","I71": #LOCATION = "C9F5" !CDS_LOCATION = "C9F5" #SEC = "1" !CDS_SEC = "1";
"A":   PN = "1"  !CDS_PN = "1";
"B":   PN = "2"  !CDS_PN = "2";
BODY = "RES","I72": #LOCATION = "R1T9" !CDS_LOCATION = "R1T9" #SEC = "1" !CDS_SEC = "1";
"A":   PN = "1"  !CDS_PN = "1";
"B":   PN = "2"  !CDS_PN = "2";
BODY = "RT9059","I73": #LOCATION = "EU25F2" !CDS_LOCATION = "EU25F2" &SEC = "1" #&CDS_SEC = "1";
"ADJ_NC":   PN = "4"  !CDS_PN = "4";
"EN":   PN = "6"  !CDS_PN = "6";
"GND":   PN = "11"  !CDS_PN = "11";
"PGOOD":   PN = "5"  !CDS_PN = "5";
"VDD":   PN = "10"  !CDS_PN = "10";
"VIN<0>":   PN = "7"  !CDS_PN = "7";
"VIN<1>":   PN = "8"  !CDS_PN = "8";
"VIN<2>":   PN = "9"  !CDS_PN = "9";
"VOUT<0>":   PN = "1"  !CDS_PN = "1";
"VOUT<1>":   PN = "2"  !CDS_PN = "2";
"VOUT<2>":   PN = "3"  !CDS_PN = "3";
BODY = "RES","I77": #LOCATION = "R1W9" !CDS_LOCATION = "R1W9" #SEC = "1" !CDS_SEC = "1";
"A":   PN = "1"  !CDS_PN = "1";
"B":   PN = "2"  !CDS_PN = "2";
BODY = "RES","I79": #LOCATION = "R9W12" !CDS_LOCATION = "R9W12" #SEC = "1" !CDS_SEC = "1";
"A":   PN = "1"  !CDS_PN = "1";
"B":   PN = "2"  !CDS_PN = "2";
BODY = "CAP","I81": #LOCATION = "C9W13" !CDS_LOCATION = "C9W13" #SEC = "1" !CDS_SEC = "1";
"A":   PN = "1"  !CDS_PN = "1";
"B":   PN = "2"  !CDS_PN = "2";
BODY = "CAP","I83": #LOCATION = "C1W15" !CDS_LOCATION = "C1W15" #SEC = "1" !CDS_SEC = "1";
"A":   PN = "1"  !CDS_PN = "1";
"B":   PN = "2"  !CDS_PN = "2";
BODY = "CAP","I84": #LOCATION = "C9W10" !CDS_LOCATION = "C9W10" #SEC = "1" !CDS_SEC = "1";
"A":   PN = "1"  !CDS_PN = "1";
"B":   PN = "2"  !CDS_PN = "2";
BODY = "CAP_A","I90": #LOCATION = "C9W5" !CDS_LOCATION = "C9W5" #SEC = "1" !CDS_SEC = "1";
"A":   PN = "1"  !CDS_PN = "1";
"B":   PN = "2"  !CDS_PN = "2";
BODY = "CAP","I91": #LOCATION = "C9W6" !CDS_LOCATION = "C9W6" #SEC = "1" !CDS_SEC = "1";
"A":   PN = "1"  !CDS_PN = "1";
"B":   PN = "2"  !CDS_PN = "2";
BODY = "CAP","I92": #LOCATION = "C1W7" !CDS_LOCATION = "C1W7" #SEC = "1" !CDS_SEC = "1";
"A":   PN = "1"  !CDS_PN = "1";
"B":   PN = "2"  !CDS_PN = "2";
BODY = "5K1R2F-2-GP","I98": #LOCATION = "R9F31" !CDS_LOCATION = "R9F31" &SEC = "1" #&CDS_SEC = "1";
"1":   PN = "1"  !CDS_PN = "1";
"2":   PN = "2"  !CDS_PN = "2";
BODY = "RES","I100": #LOCATION = "R9F32" !CDS_LOCATION = "R9F32" #SEC = "1" !CDS_SEC = "1";
"A":   PN = "1"  !CDS_PN = "1";
"B":   PN = "2"  !CDS_PN = "2";
BODY = "RES","I101": #LOCATION = "R9W32" !CDS_LOCATION = "R9W32" #SEC = "1" !CDS_SEC = "1";
"A":   PN = "1"  !CDS_PN = "1";
"B":   PN = "2"  !CDS_PN = "2";
BODY = "21K5R2F-GP","I102": #LOCATION = "R9W31" !CDS_LOCATION = "R9W31" #SEC = "1" !CDS_SEC = "1";
"1":   PN = "1"  !CDS_PN = "1";
"2":   PN = "2"  !CDS_PN = "2";
BODY = "CAP","I104": #LOCATION = "C9W17" !CDS_LOCATION = "C9W17" #SEC = "1" !CDS_SEC = "1";
"A":   PN = "1"  !CDS_PN = "1";
"B":   PN = "2"  !CDS_PN = "2";
BODY = "CAP_A","I111": #LOCATION = "C9W19" !CDS_LOCATION = "C9W19" &SEC = "1" #&CDS_SEC = "1";
"A":   PN = "1"  !CDS_PN = "1";
"B":   PN = "2"  !CDS_PN = "2";
DRAWING = "@baseboard_fab2_lib.baseboard_fab2(sch_1):page240";
BODY = "RES","I111": #LOCATION = "R8F1" !CDS_LOCATION = "R8F1" &SEC = "1" #&CDS_SEC = "1";
"A":   PN = "1"  !CDS_PN = "1";
"B":   PN = "2"  !CDS_PN = "2";
BODY = "CAP","I113": #LOCATION = "C8E17" !CDS_LOCATION = "C8E17" &SEC = "1" #&CDS_SEC = "1";
"A":   PN = "1"  !CDS_PN = "1";
"B":   PN = "2"  !CDS_PN = "2";
BODY = "CAP","I116": #LOCATION = "C8F2" !CDS_LOCATION = "C8F2" &SEC = "1" #&CDS_SEC = "1";
"A":   PN = "1"  !CDS_PN = "1";
"B":   PN = "2"  !CDS_PN = "2";
BODY = "RES","I117": #LOCATION = "R8F5" !CDS_LOCATION = "R8F5" #SEC = "1" !CDS_SEC = "1";
"A":   PN = "1"  !CDS_PN = "1";
"B":   PN = "2"  !CDS_PN = "2";
BODY = "RT8240","I125": #LOCATION = "EU8F1" !CDS_LOCATION = "EU8F1" #SEC = "1" !CDS_SEC = "1";
"BOOT":   PN = "4"  !CDS_PN = "4";
"CS":   PN = "10"  !CDS_PN = "10";
"EN":   PN = "8"  !CDS_PN = "8";
"G0":   PN = "11"  !CDS_PN = "11";
"GND<0>":   PN = "12"  !CDS_PN = "12";
"GND<1>":   PN = "13"  !CDS_PN = "13";
"LGATE":   PN = "1"  !CDS_PN = "1";
"PGOOD":   PN = "9"  !CDS_PN = "9";
"PHASE":   PN = "2"  !CDS_PN = "2";
"RGND":   PN = "7"  !CDS_PN = "7";
"UGATE":   PN = "3"  !CDS_PN = "3";
"VCC":   PN = "5"  !CDS_PN = "5";
"VOUT":   PN = "6"  !CDS_PN = "6";
BODY = "RES","I127": #LOCATION = "R8E35" !CDS_LOCATION = "R8E35" &SEC = "1" #&CDS_SEC = "1";
"A":   PN = "1"  !CDS_PN = "1";
"B":   PN = "2"  !CDS_PN = "2";
BODY = "CAP","I129": #LOCATION = "C8E12" !CDS_LOCATION = "C8E12" &SEC = "1" #&CDS_SEC = "1";
"A":   PN = "1"  !CDS_PN = "1";
"B":   PN = "2"  !CDS_PN = "2";
BODY = "CAP","I137": #LOCATION = "C8E10" !CDS_LOCATION = "C8E10" &SEC = "1" #&CDS_SEC = "1";
"A":   PN = "1"  !CDS_PN = "1";
"B":   PN = "2"  !CDS_PN = "2";
BODY = "CAP","I139": #LOCATION = "C8E14" !CDS_LOCATION = "C8E14" &SEC = "1" #&CDS_SEC = "1";
"A":   PN = "1"  !CDS_PN = "1";
"B":   PN = "2"  !CDS_PN = "2";
BODY = "RES","I140": #LOCATION = "R8E38" !CDS_LOCATION = "R8E38" &SEC = "1" #&CDS_SEC = "1";
"A":   PN = "1"  !CDS_PN = "1";
"B":   PN = "2"  !CDS_PN = "2";
BODY = "RES","I142": #LOCATION = "R8E34" !CDS_LOCATION = "R8E34" &SEC = "1" #&CDS_SEC = "1";
"A":   PN = "1"  !CDS_PN = "1";
"B":   PN = "2"  !CDS_PN = "2";
BODY = "RES","I143": #LOCATION = "R8E31" !CDS_LOCATION = "R8E31" &SEC = "1" #&CDS_SEC = "1";
"A":   PN = "1"  !CDS_PN = "1";
"B":   PN = "2"  !CDS_PN = "2";
BODY = "RES","I144": #LOCATION = "R8E25" !CDS_LOCATION = "R8E25" #SEC = "1" !CDS_SEC = "1";
"A":   PN = "1"  !CDS_PN = "1";
"B":   PN = "2"  !CDS_PN = "2";
BODY = "RES","I146": #LOCATION = "R8F11" !CDS_LOCATION = "R8F11" &SEC = "1" #&CDS_SEC = "1";
"A":   PN = "1"  !CDS_PN = "1";
"B":   PN = "2"  !CDS_PN = "2";
BODY = "RES","I148": #LOCATION = "R8F3" !CDS_LOCATION = "R8F3" &SEC = "1" #&CDS_SEC = "1";
"A":   PN = "1"  !CDS_PN = "1";
"B":   PN = "2"  !CDS_PN = "2";
BODY = "RES","I152": #LOCATION = "R2T4" !CDS_LOCATION = "R2T4" &SEC = "1" #&CDS_SEC = "1";
"A":   PN = "1"  !CDS_PN = "1";
"B":   PN = "2"  !CDS_PN = "2";
BODY = "CAP","I158": #LOCATION = "C2T7" !CDS_LOCATION = "C2T7" &SEC = "1" #&CDS_SEC = "1";
"A":   PN = "1"  !CDS_PN = "1";
"B":   PN = "2"  !CDS_PN = "2";
BODY = "CAP","I160": #LOCATION = "C2T6" !CDS_LOCATION = "C2T6" &SEC = "1" #&CDS_SEC = "1";
"A":   PN = "1"  !CDS_PN = "1";
"B":   PN = "2"  !CDS_PN = "2";
BODY = "CAP","I163": #LOCATION = "C8F3" !CDS_LOCATION = "C8F3" &SEC = "1" #&CDS_SEC = "1";
"A":   PN = "1"  !CDS_PN = "1";
"B":   PN = "2"  !CDS_PN = "2";
BODY = "CSD87384M","I170": #LOCATION = "EU8E1" !CDS_LOCATION = "EU8E1" #SEC = "1" !CDS_SEC = "1";
"BG":   PN = "4"  !CDS_PN = "4";
"PGND":   PN = "3"  !CDS_PN = "3";
"TG":   PN = "1"  !CDS_PN = "1";
"VIN":   PN = "2"  !CDS_PN = "2";
"VSW":   PN = "5"  !CDS_PN = "5";
BODY = "RES","I171": #LOCATION = "R8F10" !CDS_LOCATION = "R8F10" #SEC = "1" !CDS_SEC = "1";
"A":   PN = "1"  !CDS_PN = "1";
"B":   PN = "2"  !CDS_PN = "2";
BODY = "CAP","I174": #LOCATION = "C2T9" !CDS_LOCATION = "C2T9" #SEC = "1" !CDS_SEC = "1";
"A":   PN = "1"  !CDS_PN = "1";
"B":   PN = "2"  !CDS_PN = "2";
BODY = "RES","I176": #LOCATION = "R8F2" !CDS_LOCATION = "R8F2" #SEC = "1" !CDS_SEC = "1";
"A":   PN = "1"  !CDS_PN = "1";
"B":   PN = "2"  !CDS_PN = "2";
BODY = "RES","I177": #LOCATION = "R8E40" !CDS_LOCATION = "R8E40" #SEC = "1" !CDS_SEC = "1";
"A":   PN = "1"  !CDS_PN = "1";
"B":   PN = "2"  !CDS_PN = "2";
BODY = "SC22U16V5MX-4-GP","I181": #LOCATION = "C9F1" !CDS_LOCATION = "C9F1" #SEC = "1" !CDS_SEC = "1";
"1":   PN = "1"  !CDS_PN = "1";
"2":   PN = "2"  !CDS_PN = "2";
BODY = "SC22U16V5MX-4-GP","I182": #LOCATION = "C22W11" !CDS_LOCATION = "C22W11" #SEC = "1" !CDS_SEC = "1";
"1":   PN = "1"  !CDS_PN = "1";
"2":   PN = "2"  !CDS_PN = "2";
BODY = "SC22U16V5MX-4-GP","I183": #LOCATION = "C8E11" !CDS_LOCATION = "C8E11" #SEC = "1" !CDS_SEC = "1";
"1":   PN = "1"  !CDS_PN = "1";
"2":   PN = "2"  !CDS_PN = "2";
BODY = "SC22U16V5MX-4-GP","I186": #LOCATION = "C22W12" !CDS_LOCATION = "C22W12" #SEC = "1" !CDS_SEC = "1";
"1":   PN = "1"  !CDS_PN = "1";
"2":   PN = "2"  !CDS_PN = "2";
BODY = "IND-1UH-361-GP","I188": #LOCATION = "L8F1" !CDS_LOCATION = "L8F1" #SEC = "1" !CDS_SEC = "1";
"1":   PN = "1"  !CDS_PN = "1";
"2":   PN = "2"  !CDS_PN = "2";
BODY = "ST470U6D3VDM-7-GP","I189": #LOCATION = "C8F14" !CDS_LOCATION = "C8F14" #SEC = "1" !CDS_SEC = "1";
"1":   PN = "1"  !CDS_PN = "1";
"2":   PN = "2"  !CDS_PN = "2";
BODY = "ST470U6D3VDM-7-GP","I190": #LOCATION = "C8F8" !CDS_LOCATION = "C8F8" #SEC = "1" !CDS_SEC = "1";
"1":   PN = "1"  !CDS_PN = "1";
"2":   PN = "2"  !CDS_PN = "2";
BODY = "SC4D7U16V3KX-GP","I191": #LOCATION = "C2R11" !CDS_LOCATION = "C2R11" #SEC = "1" !CDS_SEC = "1";
"1":   PN = "1"  !CDS_PN = "1";
"2":   PN = "2"  !CDS_PN = "2";
BODY = "BLM31SN500SN1L-GP","I193": #LOCATION = "FB9E1" !CDS_LOCATION = "FB9E1" #SEC = "1" !CDS_SEC = "1";
"1":   PN = "1"  !CDS_PN = "1";
"2":   PN = "2"  !CDS_PN = "2";
BODY = "RES","I195": #LOCATION = "R8F9" !CDS_LOCATION = "R8F9" #SEC = "1" !CDS_SEC = "1";
"A":   PN = "1"  !CDS_PN = "1";
"B":   PN = "2"  !CDS_PN = "2";
DRAWING = "@baseboard_fab2_lib.baseboard_fab2(sch_1):page241";
BODY = "RES","I9": #LOCATION = "R8E18" !CDS_LOCATION = "R8E18" #SEC = "1" !CDS_SEC = "1";
"A":   PN = "1"  !CDS_PN = "1";
"B":   PN = "2"  !CDS_PN = "2";
BODY = "RES","I11": #LOCATION = "R7E12" !CDS_LOCATION = "R7E12" #SEC = "1" !CDS_SEC = "1";
"A":   PN = "1"  !CDS_PN = "1";
"B":   PN = "2"  !CDS_PN = "2";
BODY = "CAP","I12": #LOCATION = "C8E6" !CDS_LOCATION = "C8E6" #SEC = "1" !CDS_SEC = "1";
"A":   PN = "1"  !CDS_PN = "1";
"B":   PN = "2"  !CDS_PN = "2";
BODY = "CAP","I14": #LOCATION = "C7E10" !CDS_LOCATION = "C7E10" #SEC = "1" !CDS_SEC = "1";
"A":   PN = "1"  !CDS_PN = "1";
"B":   PN = "2"  !CDS_PN = "2";
BODY = "RES","I18": #LOCATION = "R7E14" !CDS_LOCATION = "R7E14" #SEC = "1" !CDS_SEC = "1";
"A":   PN = "1"  !CDS_PN = "1";
"B":   PN = "2"  !CDS_PN = "2";
BODY = "CAP","I30": #LOCATION = "C7E14" !CDS_LOCATION = "C7E14" #SEC = "1" !CDS_SEC = "1";
"A":   PN = "1"  !CDS_PN = "1";
"B":   PN = "2"  !CDS_PN = "2";
BODY = "RES","I37": #LOCATION = "R7E17" !CDS_LOCATION = "R7E17" #SEC = "1" !CDS_SEC = "1";
"A":   PN = "1"  !CDS_PN = "1";
"B":   PN = "2"  !CDS_PN = "2";
BODY = "CAP","I39": #LOCATION = "C7E11" !CDS_LOCATION = "C7E11" #SEC = "1" !CDS_SEC = "1";
"A":   PN = "1"  !CDS_PN = "1";
"B":   PN = "2"  !CDS_PN = "2";
BODY = "CAP","I41": #LOCATION = "C8E13" !CDS_LOCATION = "C8E13" #SEC = "1" !CDS_SEC = "1";
"A":   PN = "1"  !CDS_PN = "1";
"B":   PN = "2"  !CDS_PN = "2";
BODY = "RES","I50": #LOCATION = "R7F1" !CDS_LOCATION = "R7F1" #SEC = "1" !CDS_SEC = "1";
"A":   PN = "1"  !CDS_PN = "1";
"B":   PN = "2"  !CDS_PN = "2";
BODY = "RES","I51": #LOCATION = "R7E16" !CDS_LOCATION = "R7E16" #SEC = "1" !CDS_SEC = "1";
"A":   PN = "1"  !CDS_PN = "1";
"B":   PN = "2"  !CDS_PN = "2";
BODY = "CAP","I53": #LOCATION = "C8E16" !CDS_LOCATION = "C8E16" #SEC = "1" !CDS_SEC = "1";
"A":   PN = "1"  !CDS_PN = "1";
"B":   PN = "2"  !CDS_PN = "2";
BODY = "RES","I54": #LOCATION = "R8E39" !CDS_LOCATION = "R8E39" #SEC = "1" !CDS_SEC = "1";
"A":   PN = "1"  !CDS_PN = "1";
"B":   PN = "2"  !CDS_PN = "2";
BODY = "CAP","I57": #LOCATION = "C8F1" !CDS_LOCATION = "C8F1" #SEC = "1" !CDS_SEC = "1";
"A":   PN = "1"  !CDS_PN = "1";
"B":   PN = "2"  !CDS_PN = "2";
BODY = "RES","I58": #LOCATION = "R7E13" !CDS_LOCATION = "R7E13" #SEC = "1" !CDS_SEC = "1";
"A":   PN = "1"  !CDS_PN = "1";
"B":   PN = "2"  !CDS_PN = "2";
BODY = "CAP","I63": #LOCATION = "C8E15" !CDS_LOCATION = "C8E15" #SEC = "1" !CDS_SEC = "1";
"A":   PN = "1"  !CDS_PN = "1";
"B":   PN = "2"  !CDS_PN = "2";
BODY = "RES","I78": #LOCATION = "R8E37" !CDS_LOCATION = "R8E37" #SEC = "1" !CDS_SEC = "1";
"A":   PN = "1"  !CDS_PN = "1";
"B":   PN = "2"  !CDS_PN = "2";
BODY = "FERRITE","I82": #LOCATION = "FB7E1" !CDS_LOCATION = "FB7E1" #SEC = "1" !CDS_SEC = "1";
"A":   PN = "1"  !CDS_PN = "1";
"B":   PN = "2"  !CDS_PN = "2";
BODY = "TPS54821","I83": #LOCATION = "EU7E2" !CDS_LOCATION = "EU7E2" #SEC = "1" !CDS_SEC = "1";
"BOOT":   PN = "13"  !CDS_PN = "13";
"COMP":   PN = "8"  !CDS_PN = "8";
"EN":   PN = "10"  !CDS_PN = "10";
"GND<0>":   PN = "2"  !CDS_PN = "2";
"GND<1>":   PN = "3"  !CDS_PN = "3";
"PH<0>":   PN = "11"  !CDS_PN = "11";
"PH<1>":   PN = "12"  !CDS_PN = "12";
"PVIN<0>":   PN = "4"  !CDS_PN = "4";
"PVIN<1>":   PN = "5"  !CDS_PN = "5";
"PWRGD":   PN = "14"  !CDS_PN = "14";
"RT_CLK":   PN = "1"  !CDS_PN = "1";
"SS_TR":   PN = "9"  !CDS_PN = "9";
"THPAD":   PN = "15"  !CDS_PN = "15";
"VIN":   PN = "6"  !CDS_PN = "6";
"VSENSE":   PN = "7"  !CDS_PN = "7";
BODY = "RES","I89": #LOCATION = "R7E15" !CDS_LOCATION = "R7E15" #SEC = "1" !CDS_SEC = "1";
"A":   PN = "1"  !CDS_PN = "1";
"B":   PN = "2"  !CDS_PN = "2";
BODY = "INDUCTOR","I90": #LOCATION = "L8E1" !CDS_LOCATION = "L8E1" &SEC = "1" #&CDS_SEC = "1";
"INA":   PN = "1"  !CDS_PN = "1";
"INB":   PN = "2"  !CDS_PN = "2";
BODY = "RES","I91": #LOCATION = "R8E33" !CDS_LOCATION = "R8E33" #SEC = "1" !CDS_SEC = "1";
"A":   PN = "1"  !CDS_PN = "1";
"B":   PN = "2"  !CDS_PN = "2";
BODY = "SC22U16V5MX-4-GP","I92": #LOCATION = "C7E13" !CDS_LOCATION = "C7E13" #SEC = "1" !CDS_SEC = "1";
"1":   PN = "1"  !CDS_PN = "1";
"2":   PN = "2"  !CDS_PN = "2";
BODY = "SC22U16V5MX-4-GP","I95": #LOCATION = "C22W9" !CDS_LOCATION = "C22W9" #SEC = "1" !CDS_SEC = "1";
"1":   PN = "1"  !CDS_PN = "1";
"2":   PN = "2"  !CDS_PN = "2";
BODY = "SC22U16V5MX-4-GP","I96": #LOCATION = "C22W8" !CDS_LOCATION = "C22W8" #SEC = "1" !CDS_SEC = "1";
"1":   PN = "1"  !CDS_PN = "1";
"2":   PN = "2"  !CDS_PN = "2";
BODY = "SC22U16V5MX-4-GP","I98": #LOCATION = "C7E12" !CDS_LOCATION = "C7E12" #SEC = "1" !CDS_SEC = "1";
"1":   PN = "1"  !CDS_PN = "1";
"2":   PN = "2"  !CDS_PN = "2";
BODY = "ST220U10VDM-LGP","I100": #LOCATION = "C8E4" !CDS_LOCATION = "C8E4" #SEC = "1" !CDS_SEC = "1";
"1":   PN = "1"  !CDS_PN = "1";
"2":   PN = "2"  !CDS_PN = "2";
BODY = "SC22U16V5MX-4-GP","I103": #LOCATION = "C8E7" !CDS_LOCATION = "C8E7" #SEC = "1" !CDS_SEC = "1";
"1":   PN = "1"  !CDS_PN = "1";
"2":   PN = "2"  !CDS_PN = "2";
BODY = "SC22U16V5MX-4-GP","I104": #LOCATION = "C8E9" !CDS_LOCATION = "C8E9" #SEC = "1" !CDS_SEC = "1";
"1":   PN = "1"  !CDS_PN = "1";
"2":   PN = "2"  !CDS_PN = "2";
DRAWING = "@baseboard_fab2_lib.baseboard_fab2(sch_1):page242";
BODY = "CAP_A","I53": #LOCATION = "C5G41" !CDS_LOCATION = "C5G41" #SEC = "1" !CDS_SEC = "1";
"A":   PN = "1"  !CDS_PN = "1";
"B":   PN = "2"  !CDS_PN = "2";
BODY = "CAP_A","I54": #LOCATION = "C5G42" !CDS_LOCATION = "C5G42" #SEC = "1" !CDS_SEC = "1";
"A":   PN = "1"  !CDS_PN = "1";
"B":   PN = "2"  !CDS_PN = "2";
BODY = "CAP_A","I55": #LOCATION = "C5G44" !CDS_LOCATION = "C5G44" #SEC = "1" !CDS_SEC = "1";
"A":   PN = "1"  !CDS_PN = "1";
"B":   PN = "2"  !CDS_PN = "2";
BODY = "CAP_A","I56": #LOCATION = "C5G43" !CDS_LOCATION = "C5G43" #SEC = "1" !CDS_SEC = "1";
"A":   PN = "1"  !CDS_PN = "1";
"B":   PN = "2"  !CDS_PN = "2";
BODY = "CAP_A","I57": #LOCATION = "C5G48" !CDS_LOCATION = "C5G48" #SEC = "1" !CDS_SEC = "1";
"A":   PN = "1"  !CDS_PN = "1";
"B":   PN = "2"  !CDS_PN = "2";
BODY = "CAP_A","I58": #LOCATION = "C5G47" !CDS_LOCATION = "C5G47" #SEC = "1" !CDS_SEC = "1";
"A":   PN = "1"  !CDS_PN = "1";
"B":   PN = "2"  !CDS_PN = "2";
BODY = "CAP_A","I59": #LOCATION = "C5G46" !CDS_LOCATION = "C5G46" #SEC = "1" !CDS_SEC = "1";
"A":   PN = "1"  !CDS_PN = "1";
"B":   PN = "2"  !CDS_PN = "2";
BODY = "CAP_A","I60": #LOCATION = "C5G45" !CDS_LOCATION = "C5G45" #SEC = "1" !CDS_SEC = "1";
"A":   PN = "1"  !CDS_PN = "1";
"B":   PN = "2"  !CDS_PN = "2";
BODY = "CAP_A","I61": #LOCATION = "C5G49" !CDS_LOCATION = "C5G49" #SEC = "1" !CDS_SEC = "1";
"A":   PN = "1"  !CDS_PN = "1";
"B":   PN = "2"  !CDS_PN = "2";
BODY = "CAP_A","I62": #LOCATION = "C5G54" !CDS_LOCATION = "C5G54" #SEC = "1" !CDS_SEC = "1";
"A":   PN = "1"  !CDS_PN = "1";
"B":   PN = "2"  !CDS_PN = "2";
BODY = "CAP_A","I63": #LOCATION = "C5G58" !CDS_LOCATION = "C5G58" #SEC = "1" !CDS_SEC = "1";
"A":   PN = "1"  !CDS_PN = "1";
"B":   PN = "2"  !CDS_PN = "2";
BODY = "CAP_A","I64": #LOCATION = "C5G57" !CDS_LOCATION = "C5G57" #SEC = "1" !CDS_SEC = "1";
"A":   PN = "1"  !CDS_PN = "1";
"B":   PN = "2"  !CDS_PN = "2";
BODY = "CAP_A","I65": #LOCATION = "C5G56" !CDS_LOCATION = "C5G56" #SEC = "1" !CDS_SEC = "1";
"A":   PN = "1"  !CDS_PN = "1";
"B":   PN = "2"  !CDS_PN = "2";
BODY = "CAP_A","I66": #LOCATION = "C5G55" !CDS_LOCATION = "C5G55" #SEC = "1" !CDS_SEC = "1";
"A":   PN = "1"  !CDS_PN = "1";
"B":   PN = "2"  !CDS_PN = "2";
BODY = "CAP_A","I67": #LOCATION = "C5G53" !CDS_LOCATION = "C5G53" #SEC = "1" !CDS_SEC = "1";
"A":   PN = "1"  !CDS_PN = "1";
"B":   PN = "2"  !CDS_PN = "2";
BODY = "CAP_A","I68": #LOCATION = "C5G52" !CDS_LOCATION = "C5G52" #SEC = "1" !CDS_SEC = "1";
"A":   PN = "1"  !CDS_PN = "1";
"B":   PN = "2"  !CDS_PN = "2";
BODY = "CAP_A","I69": #LOCATION = "C5G51" !CDS_LOCATION = "C5G51" #SEC = "1" !CDS_SEC = "1";
"A":   PN = "1"  !CDS_PN = "1";
"B":   PN = "2"  !CDS_PN = "2";
BODY = "CAP_A","I70": #LOCATION = "C5G50" !CDS_LOCATION = "C5G50" #SEC = "1" !CDS_SEC = "1";
"A":   PN = "1"  !CDS_PN = "1";
"B":   PN = "2"  !CDS_PN = "2";
BODY = "CAP_A","I71": #LOCATION = "C5G67" !CDS_LOCATION = "C5G67" #SEC = "1" !CDS_SEC = "1";
"A":   PN = "1"  !CDS_PN = "1";
"B":   PN = "2"  !CDS_PN = "2";
BODY = "CAP_A","I72": #LOCATION = "C5G66" !CDS_LOCATION = "C5G66" #SEC = "1" !CDS_SEC = "1";
"A":   PN = "1"  !CDS_PN = "1";
"B":   PN = "2"  !CDS_PN = "2";
BODY = "CAP_A","I73": #LOCATION = "C5G65" !CDS_LOCATION = "C5G65" #SEC = "1" !CDS_SEC = "1";
"A":   PN = "1"  !CDS_PN = "1";
"B":   PN = "2"  !CDS_PN = "2";
BODY = "CAP_A","I74": #LOCATION = "C5G64" !CDS_LOCATION = "C5G64" #SEC = "1" !CDS_SEC = "1";
"A":   PN = "1"  !CDS_PN = "1";
"B":   PN = "2"  !CDS_PN = "2";
BODY = "CAP_A","I75": #LOCATION = "C5G63" !CDS_LOCATION = "C5G63" #SEC = "1" !CDS_SEC = "1";
"A":   PN = "1"  !CDS_PN = "1";
"B":   PN = "2"  !CDS_PN = "2";
BODY = "CAP_A","I76": #LOCATION = "C5G62" !CDS_LOCATION = "C5G62" #SEC = "1" !CDS_SEC = "1";
"A":   PN = "1"  !CDS_PN = "1";
"B":   PN = "2"  !CDS_PN = "2";
BODY = "CAP_A","I77": #LOCATION = "C5G61" !CDS_LOCATION = "C5G61" #SEC = "1" !CDS_SEC = "1";
"A":   PN = "1"  !CDS_PN = "1";
"B":   PN = "2"  !CDS_PN = "2";
BODY = "CAP_A","I78": #LOCATION = "C5G60" !CDS_LOCATION = "C5G60" #SEC = "1" !CDS_SEC = "1";
"A":   PN = "1"  !CDS_PN = "1";
"B":   PN = "2"  !CDS_PN = "2";
BODY = "CAP_A","I79": #LOCATION = "C5G59" !CDS_LOCATION = "C5G59" #SEC = "1" !CDS_SEC = "1";
"A":   PN = "1"  !CDS_PN = "1";
"B":   PN = "2"  !CDS_PN = "2";
BODY = "CAP_A","I80": #LOCATION = "C5G76" !CDS_LOCATION = "C5G76" #SEC = "1" !CDS_SEC = "1";
"A":   PN = "1"  !CDS_PN = "1";
"B":   PN = "2"  !CDS_PN = "2";
BODY = "CAP_A","I81": #LOCATION = "C5G75" !CDS_LOCATION = "C5G75" #SEC = "1" !CDS_SEC = "1";
"A":   PN = "1"  !CDS_PN = "1";
"B":   PN = "2"  !CDS_PN = "2";
BODY = "CAP_A","I82": #LOCATION = "C5G74" !CDS_LOCATION = "C5G74" #SEC = "1" !CDS_SEC = "1";
"A":   PN = "1"  !CDS_PN = "1";
"B":   PN = "2"  !CDS_PN = "2";
BODY = "CAP_A","I83": #LOCATION = "C5G73" !CDS_LOCATION = "C5G73" #SEC = "1" !CDS_SEC = "1";
"A":   PN = "1"  !CDS_PN = "1";
"B":   PN = "2"  !CDS_PN = "2";
BODY = "CAP_A","I84": #LOCATION = "C5G72" !CDS_LOCATION = "C5G72" #SEC = "1" !CDS_SEC = "1";
"A":   PN = "1"  !CDS_PN = "1";
"B":   PN = "2"  !CDS_PN = "2";
BODY = "CAP_A","I85": #LOCATION = "C5G71" !CDS_LOCATION = "C5G71" #SEC = "1" !CDS_SEC = "1";
"A":   PN = "1"  !CDS_PN = "1";
"B":   PN = "2"  !CDS_PN = "2";
BODY = "CAP_A","I86": #LOCATION = "C5G70" !CDS_LOCATION = "C5G70" #SEC = "1" !CDS_SEC = "1";
"A":   PN = "1"  !CDS_PN = "1";
"B":   PN = "2"  !CDS_PN = "2";
BODY = "CAP_A","I87": #LOCATION = "C5G69" !CDS_LOCATION = "C5G69" #SEC = "1" !CDS_SEC = "1";
"A":   PN = "1"  !CDS_PN = "1";
"B":   PN = "2"  !CDS_PN = "2";
BODY = "CAP_A","I88": #LOCATION = "C5G68" !CDS_LOCATION = "C5G68" #SEC = "1" !CDS_SEC = "1";
"A":   PN = "1"  !CDS_PN = "1";
"B":   PN = "2"  !CDS_PN = "2";
BODY = "CAP","I89": #LOCATION = "C5G77" !CDS_LOCATION = "C5G77" #SEC = "1" !CDS_SEC = "1";
"A":   PN = "1"  !CDS_PN = "1";
"B":   PN = "2"  !CDS_PN = "2";
BODY = "CAP","I90": #LOCATION = "C5G22" !CDS_LOCATION = "C5G22" #SEC = "1" !CDS_SEC = "1";
"A":   PN = "1"  !CDS_PN = "1";
"B":   PN = "2"  !CDS_PN = "2";
BODY = "CAP","I91": #LOCATION = "C5G78" !CDS_LOCATION = "C5G78" #SEC = "1" !CDS_SEC = "1";
"A":   PN = "1"  !CDS_PN = "1";
"B":   PN = "2"  !CDS_PN = "2";
BODY = "CAP","I92": #LOCATION = "C5G21" !CDS_LOCATION = "C5G21" #SEC = "1" !CDS_SEC = "1";
"A":   PN = "1"  !CDS_PN = "1";
"B":   PN = "2"  !CDS_PN = "2";
DRAWING = "@baseboard_fab2_lib.baseboard_fab2(sch_1):page243";
BODY = "CAP_A","I53": #LOCATION = "C5G79" !CDS_LOCATION = "C5G79" #SEC = "1" !CDS_SEC = "1";
"A":   PN = "1"  !CDS_PN = "1";
"B":   PN = "2"  !CDS_PN = "2";
BODY = "CAP_A","I54": #LOCATION = "C5G87" !CDS_LOCATION = "C5G87" #SEC = "1" !CDS_SEC = "1";
"A":   PN = "1"  !CDS_PN = "1";
"B":   PN = "2"  !CDS_PN = "2";
BODY = "CAP_A","I55": #LOCATION = "C5G86" !CDS_LOCATION = "C5G86" #SEC = "1" !CDS_SEC = "1";
"A":   PN = "1"  !CDS_PN = "1";
"B":   PN = "2"  !CDS_PN = "2";
BODY = "CAP_A","I56": #LOCATION = "C5G85" !CDS_LOCATION = "C5G85" #SEC = "1" !CDS_SEC = "1";
"A":   PN = "1"  !CDS_PN = "1";
"B":   PN = "2"  !CDS_PN = "2";
BODY = "CAP_A","I57": #LOCATION = "C5G84" !CDS_LOCATION = "C5G84" #SEC = "1" !CDS_SEC = "1";
"A":   PN = "1"  !CDS_PN = "1";
"B":   PN = "2"  !CDS_PN = "2";
BODY = "CAP_A","I58": #LOCATION = "C5G83" !CDS_LOCATION = "C5G83" #SEC = "1" !CDS_SEC = "1";
"A":   PN = "1"  !CDS_PN = "1";
"B":   PN = "2"  !CDS_PN = "2";
BODY = "CAP_A","I59": #LOCATION = "C5G82" !CDS_LOCATION = "C5G82" #SEC = "1" !CDS_SEC = "1";
"A":   PN = "1"  !CDS_PN = "1";
"B":   PN = "2"  !CDS_PN = "2";
BODY = "CAP_A","I60": #LOCATION = "C5G81" !CDS_LOCATION = "C5G81" #SEC = "1" !CDS_SEC = "1";
"A":   PN = "1"  !CDS_PN = "1";
"B":   PN = "2"  !CDS_PN = "2";
BODY = "CAP_A","I61": #LOCATION = "C5G80" !CDS_LOCATION = "C5G80" #SEC = "1" !CDS_SEC = "1";
"A":   PN = "1"  !CDS_PN = "1";
"B":   PN = "2"  !CDS_PN = "2";
BODY = "CAP_A","I62": #LOCATION = "C5G96" !CDS_LOCATION = "C5G96" #SEC = "1" !CDS_SEC = "1";
"A":   PN = "1"  !CDS_PN = "1";
"B":   PN = "2"  !CDS_PN = "2";
BODY = "CAP_A","I63": #LOCATION = "C5G95" !CDS_LOCATION = "C5G95" #SEC = "1" !CDS_SEC = "1";
"A":   PN = "1"  !CDS_PN = "1";
"B":   PN = "2"  !CDS_PN = "2";
BODY = "CAP_A","I64": #LOCATION = "C5G94" !CDS_LOCATION = "C5G94" #SEC = "1" !CDS_SEC = "1";
"A":   PN = "1"  !CDS_PN = "1";
"B":   PN = "2"  !CDS_PN = "2";
BODY = "CAP_A","I65": #LOCATION = "C5G93" !CDS_LOCATION = "C5G93" #SEC = "1" !CDS_SEC = "1";
"A":   PN = "1"  !CDS_PN = "1";
"B":   PN = "2"  !CDS_PN = "2";
BODY = "CAP_A","I66": #LOCATION = "C5G92" !CDS_LOCATION = "C5G92" #SEC = "1" !CDS_SEC = "1";
"A":   PN = "1"  !CDS_PN = "1";
"B":   PN = "2"  !CDS_PN = "2";
BODY = "CAP_A","I67": #LOCATION = "C5G91" !CDS_LOCATION = "C5G91" #SEC = "1" !CDS_SEC = "1";
"A":   PN = "1"  !CDS_PN = "1";
"B":   PN = "2"  !CDS_PN = "2";
BODY = "CAP_A","I68": #LOCATION = "C5G90" !CDS_LOCATION = "C5G90" #SEC = "1" !CDS_SEC = "1";
"A":   PN = "1"  !CDS_PN = "1";
"B":   PN = "2"  !CDS_PN = "2";
BODY = "CAP_A","I69": #LOCATION = "C5G89" !CDS_LOCATION = "C5G89" #SEC = "1" !CDS_SEC = "1";
"A":   PN = "1"  !CDS_PN = "1";
"B":   PN = "2"  !CDS_PN = "2";
BODY = "CAP_A","I70": #LOCATION = "C5G88" !CDS_LOCATION = "C5G88" #SEC = "1" !CDS_SEC = "1";
"A":   PN = "1"  !CDS_PN = "1";
"B":   PN = "2"  !CDS_PN = "2";
BODY = "CAP_A","I71": #LOCATION = "C5G103" !CDS_LOCATION = "C5G103" #SEC = "1" !CDS_SEC = "1";
"A":   PN = "1"  !CDS_PN = "1";
"B":   PN = "2"  !CDS_PN = "2";
BODY = "CAP_A","I72": #LOCATION = "C5G104" !CDS_LOCATION = "C5G104" #SEC = "1" !CDS_SEC = "1";
"A":   PN = "1"  !CDS_PN = "1";
"B":   PN = "2"  !CDS_PN = "2";
BODY = "CAP_A","I73": #LOCATION = "C5G105" !CDS_LOCATION = "C5G105" #SEC = "1" !CDS_SEC = "1";
"A":   PN = "1"  !CDS_PN = "1";
"B":   PN = "2"  !CDS_PN = "2";
BODY = "CAP_A","I74": #LOCATION = "C5G102" !CDS_LOCATION = "C5G102" #SEC = "1" !CDS_SEC = "1";
"A":   PN = "1"  !CDS_PN = "1";
"B":   PN = "2"  !CDS_PN = "2";
BODY = "CAP_A","I75": #LOCATION = "C5G101" !CDS_LOCATION = "C5G101" #SEC = "1" !CDS_SEC = "1";
"A":   PN = "1"  !CDS_PN = "1";
"B":   PN = "2"  !CDS_PN = "2";
BODY = "CAP_A","I76": #LOCATION = "C5G100" !CDS_LOCATION = "C5G100" #SEC = "1" !CDS_SEC = "1";
"A":   PN = "1"  !CDS_PN = "1";
"B":   PN = "2"  !CDS_PN = "2";
BODY = "CAP_A","I77": #LOCATION = "C5G99" !CDS_LOCATION = "C5G99" #SEC = "1" !CDS_SEC = "1";
"A":   PN = "1"  !CDS_PN = "1";
"B":   PN = "2"  !CDS_PN = "2";
BODY = "CAP_A","I78": #LOCATION = "C5G98" !CDS_LOCATION = "C5G98" #SEC = "1" !CDS_SEC = "1";
"A":   PN = "1"  !CDS_PN = "1";
"B":   PN = "2"  !CDS_PN = "2";
BODY = "CAP_A","I79": #LOCATION = "C5G97" !CDS_LOCATION = "C5G97" #SEC = "1" !CDS_SEC = "1";
"A":   PN = "1"  !CDS_PN = "1";
"B":   PN = "2"  !CDS_PN = "2";
BODY = "CAP_A","I80": #LOCATION = "C5G114" !CDS_LOCATION = "C5G114" #SEC = "1" !CDS_SEC = "1";
"A":   PN = "1"  !CDS_PN = "1";
"B":   PN = "2"  !CDS_PN = "2";
BODY = "CAP_A","I81": #LOCATION = "C5G113" !CDS_LOCATION = "C5G113" #SEC = "1" !CDS_SEC = "1";
"A":   PN = "1"  !CDS_PN = "1";
"B":   PN = "2"  !CDS_PN = "2";
BODY = "CAP_A","I82": #LOCATION = "C5G112" !CDS_LOCATION = "C5G112" #SEC = "1" !CDS_SEC = "1";
"A":   PN = "1"  !CDS_PN = "1";
"B":   PN = "2"  !CDS_PN = "2";
BODY = "CAP_A","I83": #LOCATION = "C5G111" !CDS_LOCATION = "C5G111" #SEC = "1" !CDS_SEC = "1";
"A":   PN = "1"  !CDS_PN = "1";
"B":   PN = "2"  !CDS_PN = "2";
BODY = "CAP_A","I84": #LOCATION = "C5G110" !CDS_LOCATION = "C5G110" #SEC = "1" !CDS_SEC = "1";
"A":   PN = "1"  !CDS_PN = "1";
"B":   PN = "2"  !CDS_PN = "2";
BODY = "CAP_A","I85": #LOCATION = "C5G109" !CDS_LOCATION = "C5G109" #SEC = "1" !CDS_SEC = "1";
"A":   PN = "1"  !CDS_PN = "1";
"B":   PN = "2"  !CDS_PN = "2";
BODY = "CAP_A","I86": #LOCATION = "C5G108" !CDS_LOCATION = "C5G108" #SEC = "1" !CDS_SEC = "1";
"A":   PN = "1"  !CDS_PN = "1";
"B":   PN = "2"  !CDS_PN = "2";
BODY = "CAP_A","I87": #LOCATION = "C5G107" !CDS_LOCATION = "C5G107" #SEC = "1" !CDS_SEC = "1";
"A":   PN = "1"  !CDS_PN = "1";
"B":   PN = "2"  !CDS_PN = "2";
BODY = "CAP_A","I88": #LOCATION = "C5G106" !CDS_LOCATION = "C5G106" #SEC = "1" !CDS_SEC = "1";
"A":   PN = "1"  !CDS_PN = "1";
"B":   PN = "2"  !CDS_PN = "2";
BODY = "CAP","I89": #LOCATION = "C5G115" !CDS_LOCATION = "C5G115" #SEC = "1" !CDS_SEC = "1";
"A":   PN = "1"  !CDS_PN = "1";
"B":   PN = "2"  !CDS_PN = "2";
BODY = "CAP","I90": #LOCATION = "C5G116" !CDS_LOCATION = "C5G116" #SEC = "1" !CDS_SEC = "1";
"A":   PN = "1"  !CDS_PN = "1";
"B":   PN = "2"  !CDS_PN = "2";
BODY = "CAP","I91": #LOCATION = "C5G118" !CDS_LOCATION = "C5G118" #SEC = "1" !CDS_SEC = "1";
"A":   PN = "1"  !CDS_PN = "1";
"B":   PN = "2"  !CDS_PN = "2";
BODY = "CAP","I92": #LOCATION = "C5G117" !CDS_LOCATION = "C5G117" #SEC = "1" !CDS_SEC = "1";
"A":   PN = "1"  !CDS_PN = "1";
"B":   PN = "2"  !CDS_PN = "2";
DRAWING = "@baseboard_fab2_lib.baseboard_fab2(sch_1):page244";
BODY = "CAP","I2": LOCATION = "C831" #&CDS_LOCATION = "C831" #SEC = "1" !CDS_SEC = "1";
"A":   PN = "1"  !CDS_PN = "1";
"B":   PN = "2"  !CDS_PN = "2";
BODY = "CAP","I5": LOCATION = "C829" #&CDS_LOCATION = "C829" #SEC = "1" !CDS_SEC = "1";
"A":   PN = "1"  !CDS_PN = "1";
"B":   PN = "2"  !CDS_PN = "2";
BODY = "CAP","I8": LOCATION = "C833" #&CDS_LOCATION = "C833" #SEC = "1" !CDS_SEC = "1";
"A":   PN = "1"  !CDS_PN = "1";
"B":   PN = "2"  !CDS_PN = "2";
BODY = "CAP","I12": LOCATION = "C827" #&CDS_LOCATION = "C827" #SEC = "1" !CDS_SEC = "1";
"A":   PN = "1"  !CDS_PN = "1";
"B":   PN = "2"  !CDS_PN = "2";
BODY = "CAP","I17": LOCATION = "C841" #&CDS_LOCATION = "C841" #SEC = "1" !CDS_SEC = "1";
"A":   PN = "1"  !CDS_PN = "1";
"B":   PN = "2"  !CDS_PN = "2";
BODY = "CAP","I23": LOCATION = "C830" #&CDS_LOCATION = "C830" #SEC = "1" !CDS_SEC = "1";
"A":   PN = "1"  !CDS_PN = "1";
"B":   PN = "2"  !CDS_PN = "2";
BODY = "CAP","I24": LOCATION = "C826" #&CDS_LOCATION = "C826" #SEC = "1" !CDS_SEC = "1";
"A":   PN = "1"  !CDS_PN = "1";
"B":   PN = "2"  !CDS_PN = "2";
BODY = "CAP","I28": LOCATION = "C828" #&CDS_LOCATION = "C828" #SEC = "1" !CDS_SEC = "1";
"A":   PN = "1"  !CDS_PN = "1";
"B":   PN = "2"  !CDS_PN = "2";
BODY = "CAP","I29": LOCATION = "C840" #&CDS_LOCATION = "C840" #SEC = "1" !CDS_SEC = "1";
"A":   PN = "1"  !CDS_PN = "1";
"B":   PN = "2"  !CDS_PN = "2";
BODY = "CAP","I30": LOCATION = "C832" #&CDS_LOCATION = "C832" #SEC = "1" !CDS_SEC = "1";
"A":   PN = "1"  !CDS_PN = "1";
"B":   PN = "2"  !CDS_PN = "2";
BODY = "CAP","I35": LOCATION = "C845" #&CDS_LOCATION = "C845" #SEC = "1" !CDS_SEC = "1";
"A":   PN = "1"  !CDS_PN = "1";
"B":   PN = "2"  !CDS_PN = "2";
BODY = "RES","I39": LOCATION = "R767" #&CDS_LOCATION = "R767" #SEC = "1" !CDS_SEC = "1";
"A":   PN = "1"  !CDS_PN = "1";
"B":   PN = "2"  !CDS_PN = "2";
BODY = "CAP","I41": LOCATION = "C835" #&CDS_LOCATION = "C835" #SEC = "1" !CDS_SEC = "1";
"A":   PN = "1"  !CDS_PN = "1";
"B":   PN = "2"  !CDS_PN = "2";
BODY = "CAP","I47": LOCATION = "C843" #&CDS_LOCATION = "C843" #SEC = "1" !CDS_SEC = "1";
"A":   PN = "1"  !CDS_PN = "1";
"B":   PN = "2"  !CDS_PN = "2";
BODY = "CAP","I50": LOCATION = "C834" #&CDS_LOCATION = "C834" #SEC = "1" !CDS_SEC = "1";
"A":   PN = "1"  !CDS_PN = "1";
"B":   PN = "2"  !CDS_PN = "2";
BODY = "CAP","I51": LOCATION = "C844" #&CDS_LOCATION = "C844" #SEC = "1" !CDS_SEC = "1";
"A":   PN = "1"  !CDS_PN = "1";
"B":   PN = "2"  !CDS_PN = "2";
BODY = "CAP","I52": LOCATION = "C842" #&CDS_LOCATION = "C842" #SEC = "1" !CDS_SEC = "1";
"A":   PN = "1"  !CDS_PN = "1";
"B":   PN = "2"  !CDS_PN = "2";
BODY = "RES","I58": LOCATION = "R769" #&CDS_LOCATION = "R769" #SEC = "1" !CDS_SEC = "1";
"A":   PN = "1"  !CDS_PN = "1";
"B":   PN = "2"  !CDS_PN = "2";
BODY = "RES","I64": LOCATION = "R760" #&CDS_LOCATION = "R760" #SEC = "1" !CDS_SEC = "1";
"A":   PN = "1"  !CDS_PN = "1";
"B":   PN = "2"  !CDS_PN = "2";
BODY = "RES","I65": LOCATION = "R771" #&CDS_LOCATION = "R771" #SEC = "1" !CDS_SEC = "1";
"A":   PN = "1"  !CDS_PN = "1";
"B":   PN = "2"  !CDS_PN = "2";
BODY = "RES","I66": LOCATION = "R768" #&CDS_LOCATION = "R768" #SEC = "1" !CDS_SEC = "1";
"A":   PN = "1"  !CDS_PN = "1";
"B":   PN = "2"  !CDS_PN = "2";
BODY = "RES","I72": LOCATION = "R774" #&CDS_LOCATION = "R774" #SEC = "1" !CDS_SEC = "1";
"A":   PN = "1"  !CDS_PN = "1";
"B":   PN = "2"  !CDS_PN = "2";
BODY = "RES","I74": LOCATION = "R779" #&CDS_LOCATION = "R779" #SEC = "1" !CDS_SEC = "1";
"A":   PN = "1"  !CDS_PN = "1";
"B":   PN = "2"  !CDS_PN = "2";
BODY = "RES","I77": LOCATION = "R783" #&CDS_LOCATION = "R783" #SEC = "1" !CDS_SEC = "1";
"A":   PN = "1"  !CDS_PN = "1";
"B":   PN = "2"  !CDS_PN = "2";
BODY = "RES","I80": LOCATION = "R777" #&CDS_LOCATION = "R777" #SEC = "1" !CDS_SEC = "1";
"A":   PN = "1"  !CDS_PN = "1";
"B":   PN = "2"  !CDS_PN = "2";
BODY = "RES","I86": LOCATION = "R781" #&CDS_LOCATION = "R781" #SEC = "1" !CDS_SEC = "1";
"A":   PN = "1"  !CDS_PN = "1";
"B":   PN = "2"  !CDS_PN = "2";
BODY = "RES","I93": LOCATION = "R775" #&CDS_LOCATION = "R775" #SEC = "1" !CDS_SEC = "1";
"A":   PN = "1"  !CDS_PN = "1";
"B":   PN = "2"  !CDS_PN = "2";
BODY = "RES","I94": LOCATION = "R778" #&CDS_LOCATION = "R778" #SEC = "1" !CDS_SEC = "1";
"A":   PN = "1"  !CDS_PN = "1";
"B":   PN = "2"  !CDS_PN = "2";
BODY = "RES","I97": LOCATION = "R780" #&CDS_LOCATION = "R780" #SEC = "1" !CDS_SEC = "1";
"A":   PN = "1"  !CDS_PN = "1";
"B":   PN = "2"  !CDS_PN = "2";
BODY = "RES","I98": LOCATION = "R782" #&CDS_LOCATION = "R782" #SEC = "1" !CDS_SEC = "1";
"A":   PN = "1"  !CDS_PN = "1";
"B":   PN = "2"  !CDS_PN = "2";
BODY = "RES","I99": LOCATION = "R784" #&CDS_LOCATION = "R784" #SEC = "1" !CDS_SEC = "1";
"A":   PN = "1"  !CDS_PN = "1";
"B":   PN = "2"  !CDS_PN = "2";
BODY = "RES","I103": LOCATION = "R785" #&CDS_LOCATION = "R785" #SEC = "1" !CDS_SEC = "1";
"A":   PN = "1"  !CDS_PN = "1";
"B":   PN = "2"  !CDS_PN = "2";
DRAWING = "@baseboard_fab2_lib.baseboard_fab2(sch_1):page245";
BODY = "SMC-CONN60A-22-GP","I48": #LOCATION = "CONX8" !CDS_LOCATION = "CONX8" &SEC = "1" #&CDS_SEC = "1";
"1":   PN = "1"  !CDS_PN = "1";
"2":   PN = "2"  !CDS_PN = "2";
"3":   PN = "3"  !CDS_PN = "3";
"4":   PN = "4"  !CDS_PN = "4";
"5":   PN = "5"  !CDS_PN = "5";
"6":   PN = "6"  !CDS_PN = "6";
"7":   PN = "7"  !CDS_PN = "7";
"8":   PN = "8"  !CDS_PN = "8";
"9":   PN = "9"  !CDS_PN = "9";
"10":   PN = "10"  !CDS_PN = "10";
"11":   PN = "11"  !CDS_PN = "11";
"12":   PN = "12"  !CDS_PN = "12";
"13":   PN = "13"  !CDS_PN = "13";
"14":   PN = "14"  !CDS_PN = "14";
"15":   PN = "15"  !CDS_PN = "15";
"16":   PN = "16"  !CDS_PN = "16";
"17":   PN = "17"  !CDS_PN = "17";
"18":   PN = "18"  !CDS_PN = "18";
"19":   PN = "19"  !CDS_PN = "19";
"20":   PN = "20"  !CDS_PN = "20";
"21":   PN = "21"  !CDS_PN = "21";
"22":   PN = "22"  !CDS_PN = "22";
"23":   PN = "23"  !CDS_PN = "23";
"24":   PN = "24"  !CDS_PN = "24";
"25":   PN = "25"  !CDS_PN = "25";
"26":   PN = "26"  !CDS_PN = "26";
"27":   PN = "27"  !CDS_PN = "27";
"28":   PN = "28"  !CDS_PN = "28";
"29":   PN = "29"  !CDS_PN = "29";
"30":   PN = "30"  !CDS_PN = "30";
"31":   PN = "31"  !CDS_PN = "31";
"32":   PN = "32"  !CDS_PN = "32";
"33":   PN = "33"  !CDS_PN = "33";
"34":   PN = "34"  !CDS_PN = "34";
"35":   PN = "35"  !CDS_PN = "35";
"36":   PN = "36"  !CDS_PN = "36";
"37":   PN = "37"  !CDS_PN = "37";
"38":   PN = "38"  !CDS_PN = "38";
"39":   PN = "39"  !CDS_PN = "39";
"40":   PN = "40"  !CDS_PN = "40";
"41":   PN = "41"  !CDS_PN = "41";
"42":   PN = "42"  !CDS_PN = "42";
"43":   PN = "43"  !CDS_PN = "43";
"44":   PN = "44"  !CDS_PN = "44";
"45":   PN = "45"  !CDS_PN = "45";
"46":   PN = "46"  !CDS_PN = "46";
"47":   PN = "47"  !CDS_PN = "47";
"48":   PN = "48"  !CDS_PN = "48";
"49":   PN = "49"  !CDS_PN = "49";
"50":   PN = "50"  !CDS_PN = "50";
"51":   PN = "51"  !CDS_PN = "51";
"52":   PN = "52"  !CDS_PN = "52";
"53":   PN = "53"  !CDS_PN = "53";
"54":   PN = "54"  !CDS_PN = "54";
"55":   PN = "55"  !CDS_PN = "55";
"56":   PN = "56"  !CDS_PN = "56";
"57":   PN = "57"  !CDS_PN = "57";
"58":   PN = "58"  !CDS_PN = "58";
"59":   PN = "59"  !CDS_PN = "59";
"60":   PN = "60"  !CDS_PN = "60";
"NP1":   PN = "NP1"  !CDS_PN = "NP1";
"NP2":   PN = "NP2"  !CDS_PN = "NP2";
"PTH1":   PN = "PTH1"  !CDS_PN = "PTH1";
"PTH2":   PN = "PTH2"  !CDS_PN = "PTH2";
BODY = "RES","I56": #LOCATION = "R8W10" !CDS_LOCATION = "R8W10" #SEC = "1" !CDS_SEC = "1";
"A":   PN = "1"  !CDS_PN = "1";
"B":   PN = "2"  !CDS_PN = "2";
BODY = "RES","I57": #LOCATION = "R8W11" !CDS_LOCATION = "R8W11" #SEC = "1" !CDS_SEC = "1";
"A":   PN = "1"  !CDS_PN = "1";
"B":   PN = "2"  !CDS_PN = "2";
BODY = "RES","I58": #LOCATION = "R8W12" !CDS_LOCATION = "R8W12" #SEC = "1" !CDS_SEC = "1";
"A":   PN = "1"  !CDS_PN = "1";
"B":   PN = "2"  !CDS_PN = "2";
BODY = "RES","I59": #LOCATION = "R8W13" !CDS_LOCATION = "R8W13" #SEC = "1" !CDS_SEC = "1";
"A":   PN = "1"  !CDS_PN = "1";
"B":   PN = "2"  !CDS_PN = "2";
BODY = "RES","I60": #LOCATION = "R8W14" !CDS_LOCATION = "R8W14" #SEC = "1" !CDS_SEC = "1";
"A":   PN = "1"  !CDS_PN = "1";
"B":   PN = "2"  !CDS_PN = "2";
BODY = "74CBTLV1G125","I64": #LOCATION = "U8W1" !CDS_LOCATION = "U8W1" #SEC = "1" !CDS_SEC = "1";
"A":   PN = "2"  !CDS_PN = "2";
"B":   PN = "4"  !CDS_PN = "4";
"OE_N":   PN = "1"  !CDS_PN = "1";
BODY = "NC7SB3157","I66": #LOCATION = "U8W2" !CDS_LOCATION = "U8W2" &SEC = "1" #&CDS_SEC = "1";
"A":   PN = "4"  !CDS_PN = "4";
"B0":   PN = "3"  !CDS_PN = "3";
"B1":   PN = "1"  !CDS_PN = "1";
"GND":   PN = "2"  !CDS_PN = "2";
"S":   PN = "6"  !CDS_PN = "6";
"VCC":   PN = "5"  !CDS_PN = "5";
BODY = "CAP_A","I71": #LOCATION = "C8W6" !CDS_LOCATION = "C8W6" #SEC = "1" !CDS_SEC = "1";
"A":   PN = "1"  !CDS_PN = "1";
"B":   PN = "2"  !CDS_PN = "2";
BODY = "CAP_A","I74": #LOCATION = "C8W5" !CDS_LOCATION = "C8W5" &SEC = "1" #&CDS_SEC = "1";
"A":   PN = "1"  !CDS_PN = "1";
"B":   PN = "2"  !CDS_PN = "2";
BODY = "RES","I78": #LOCATION = "R8W15" !CDS_LOCATION = "R8W15" #SEC = "1" !CDS_SEC = "1";
"A":   PN = "1"  !CDS_PN = "1";
"B":   PN = "2"  !CDS_PN = "2";
DRAWING = "@baseboard_fab2_lib.baseboard_fab2(sch_1):page109";
BODY = "SCONN200_H68296001","I78": #LOCATION = "J8G1" !CDS_LOCATION = "J8G1" #SEC = "2" !CDS_SEC = "2";
"IO101":   PN = "101"  !CDS_PN = "101";
"IO102":   PN = "102"  !CDS_PN = "102";
"IO103":   PN = "103"  !CDS_PN = "103";
"IO104":   PN = "104"  !CDS_PN = "104";
"IO105":   PN = "105"  !CDS_PN = "105";
"IO106":   PN = "106"  !CDS_PN = "106";
"IO107":   PN = "107"  !CDS_PN = "107";
"IO108":   PN = "108"  !CDS_PN = "108";
"IO109":   PN = "109"  !CDS_PN = "109";
"IO110":   PN = "110"  !CDS_PN = "110";
"IO111":   PN = "111"  !CDS_PN = "111";
"IO112":   PN = "112"  !CDS_PN = "112";
"IO113":   PN = "113"  !CDS_PN = "113";
"IO114":   PN = "114"  !CDS_PN = "114";
"IO115":   PN = "115"  !CDS_PN = "115";
"IO116":   PN = "116"  !CDS_PN = "116";
"IO117":   PN = "117"  !CDS_PN = "117";
"IO118":   PN = "118"  !CDS_PN = "118";
"IO119":   PN = "119"  !CDS_PN = "119";
"IO120":   PN = "120"  !CDS_PN = "120";
"IO121":   PN = "121"  !CDS_PN = "121";
"IO122":   PN = "122"  !CDS_PN = "122";
"IO123":   PN = "123"  !CDS_PN = "123";
"IO124":   PN = "124"  !CDS_PN = "124";
"IO125":   PN = "125"  !CDS_PN = "125";
"IO126":   PN = "126"  !CDS_PN = "126";
"IO127":   PN = "127"  !CDS_PN = "127";
"IO128":   PN = "128"  !CDS_PN = "128";
"IO129":   PN = "129"  !CDS_PN = "129";
"IO130":   PN = "130"  !CDS_PN = "130";
"IO131":   PN = "131"  !CDS_PN = "131";
"IO132":   PN = "132"  !CDS_PN = "132";
"IO133":   PN = "133"  !CDS_PN = "133";
"IO134":   PN = "134"  !CDS_PN = "134";
"IO135":   PN = "135"  !CDS_PN = "135";
"IO136":   PN = "136"  !CDS_PN = "136";
"IO137":   PN = "137"  !CDS_PN = "137";
"IO138":   PN = "138"  !CDS_PN = "138";
"IO139":   PN = "139"  !CDS_PN = "139";
"IO140":   PN = "140"  !CDS_PN = "140";
"IO141":   PN = "141"  !CDS_PN = "141";
"IO142":   PN = "142"  !CDS_PN = "142";
"IO143":   PN = "143"  !CDS_PN = "143";
"IO144":   PN = "144"  !CDS_PN = "144";
"IO145":   PN = "145"  !CDS_PN = "145";
"IO146":   PN = "146"  !CDS_PN = "146";
"IO147":   PN = "147"  !CDS_PN = "147";
"IO148":   PN = "148"  !CDS_PN = "148";
"IO149":   PN = "149"  !CDS_PN = "149";
"IO150":   PN = "150"  !CDS_PN = "150";
"IO151":   PN = "151"  !CDS_PN = "151";
"IO152":   PN = "152"  !CDS_PN = "152";
"IO153":   PN = "153"  !CDS_PN = "153";
"IO154":   PN = "154"  !CDS_PN = "154";
"IO155":   PN = "155"  !CDS_PN = "155";
"IO156":   PN = "156"  !CDS_PN = "156";
"IO157":   PN = "157"  !CDS_PN = "157";
"IO158":   PN = "158"  !CDS_PN = "158";
"IO159":   PN = "159"  !CDS_PN = "159";
"IO160":   PN = "160"  !CDS_PN = "160";
"IO161":   PN = "161"  !CDS_PN = "161";
"IO162":   PN = "162"  !CDS_PN = "162";
"IO163":   PN = "163"  !CDS_PN = "163";
"IO164":   PN = "164"  !CDS_PN = "164";
"IO165":   PN = "165"  !CDS_PN = "165";
"IO166":   PN = "166"  !CDS_PN = "166";
"IO167":   PN = "167"  !CDS_PN = "167";
"IO168":   PN = "168"  !CDS_PN = "168";
"IO169":   PN = "169"  !CDS_PN = "169";
"IO170":   PN = "170"  !CDS_PN = "170";
"IO171":   PN = "171"  !CDS_PN = "171";
"IO172":   PN = "172"  !CDS_PN = "172";
"IO173":   PN = "173"  !CDS_PN = "173";
"IO174":   PN = "174"  !CDS_PN = "174";
"IO175":   PN = "175"  !CDS_PN = "175";
"IO176":   PN = "176"  !CDS_PN = "176";
"IO177":   PN = "177"  !CDS_PN = "177";
"IO178":   PN = "178"  !CDS_PN = "178";
"IO179":   PN = "179"  !CDS_PN = "179";
"IO180":   PN = "180"  !CDS_PN = "180";
"IO181":   PN = "181"  !CDS_PN = "181";
"IO182":   PN = "182"  !CDS_PN = "182";
"IO183":   PN = "183"  !CDS_PN = "183";
"IO184":   PN = "184"  !CDS_PN = "184";
"IO185":   PN = "185"  !CDS_PN = "185";
"IO186":   PN = "186"  !CDS_PN = "186";
"IO187":   PN = "187"  !CDS_PN = "187";
"IO188":   PN = "188"  !CDS_PN = "188";
"IO189":   PN = "189"  !CDS_PN = "189";
"IO190":   PN = "190"  !CDS_PN = "190";
"IO191":   PN = "191"  !CDS_PN = "191";
"IO192":   PN = "192"  !CDS_PN = "192";
"IO193":   PN = "193"  !CDS_PN = "193";
"IO194":   PN = "194"  !CDS_PN = "194";
"IO195":   PN = "195"  !CDS_PN = "195";
"IO196":   PN = "196"  !CDS_PN = "196";
"IO197":   PN = "197"  !CDS_PN = "197";
"IO198":   PN = "198"  !CDS_PN = "198";
"IO199":   PN = "199"  !CDS_PN = "199";
"IO200":   PN = "200"  !CDS_PN = "200";
DRAWING = "@baseboard_fab2_lib.baseboard_fab2(sch_1):page246";
BODY = "RES","I9": #LOCATION = "RN8F5" !CDS_LOCATION = "RN8F5" #SEC = "1" !CDS_SEC = "1";
"A":   PN = "1"  !CDS_PN = "1";
"B":   PN = "2"  !CDS_PN = "2";
BODY = "RES","I11": #LOCATION = "RN8F3" !CDS_LOCATION = "RN8F3" #SEC = "1" !CDS_SEC = "1";
"A":   PN = "1"  !CDS_PN = "1";
"B":   PN = "2"  !CDS_PN = "2";
BODY = "RES","I12": #LOCATION = "RN8F4" !CDS_LOCATION = "RN8F4" #SEC = "1" !CDS_SEC = "1";
"A":   PN = "1"  !CDS_PN = "1";
"B":   PN = "2"  !CDS_PN = "2";
BODY = "W25Q256","I17": #LOCATION = "UN8F2" !CDS_LOCATION = "UN8F2" #SEC = "1" !CDS_SEC = "1";
"CLK":   PN = "16"  !CDS_PN = "16";
"CS_N":   PN = "7"  !CDS_PN = "7";
"DI_IO<0>":   PN = "15"  !CDS_PN = "15";
"DO_IO<1>":   PN = "8"  !CDS_PN = "8";
"GND":   PN = "10"  !CDS_PN = "10";
"HOLD_N_IO<3>":   PN = "1"  !CDS_PN = "1";
"NC<0>":   PN = "14"  !CDS_PN = "14";
"NC<1>":   PN = "13"  !CDS_PN = "13";
"NC<2>":   PN = "12"  !CDS_PN = "12";
"NC<3>":   PN = "11"  !CDS_PN = "11";
"NC<4>":   PN = "6"  !CDS_PN = "6";
"NC<5>":   PN = "5"  !CDS_PN = "5";
"NC<6>":   PN = "4"  !CDS_PN = "4";
"RESET_N":   PN = "3"  !CDS_PN = "3";
"VCC":   PN = "2"  !CDS_PN = "2";
"WP_N_IO<2>":   PN = "9"  !CDS_PN = "9";
BODY = "82KR2F-1-GP","I19": #LOCATION = "RN8F6" !CDS_LOCATION = "RN8F6" &SEC = "1" #&CDS_SEC = "1";
"1":   PN = "1"  !CDS_PN = "1";
"2":   PN = "2"  !CDS_PN = "2";
BODY = "RES","I20": #LOCATION = "RN8F2" !CDS_LOCATION = "RN8F2" #SEC = "1" !CDS_SEC = "1";
"A":   PN = "1"  !CDS_PN = "1";
"B":   PN = "2"  !CDS_PN = "2";
BODY = "CAP_A","I21": #LOCATION = "CN8F1" !CDS_LOCATION = "CN8F1" #SEC = "1" !CDS_SEC = "1";
"A":   PN = "1"  !CDS_PN = "1";
"B":   PN = "2"  !CDS_PN = "2";
BODY = "CAP_A","I22": #LOCATION = "CN8F2" !CDS_LOCATION = "CN8F2" #SEC = "1" !CDS_SEC = "1";
"A":   PN = "1"  !CDS_PN = "1";
"B":   PN = "2"  !CDS_PN = "2";
DRAWING = "@baseboard_fab2_lib.baseboard_fab2(sch_1):page247";
BODY = "RES","I1": #LOCATION = "R6W10" !CDS_LOCATION = "R6W10" #SEC = "1" !CDS_SEC = "1";
"A":   PN = "1"  !CDS_PN = "1";
"B":   PN = "2"  !CDS_PN = "2";
BODY = "CAP_A","I85": #LOCATION = "C6W3" !CDS_LOCATION = "C6W3" #SEC = "1" !CDS_SEC = "1";
"A":   PN = "1"  !CDS_PN = "1";
"B":   PN = "2"  !CDS_PN = "2";
BODY = "RES","I87": #LOCATION = "R6W20" !CDS_LOCATION = "R6W20" #SEC = "1" !CDS_SEC = "1";
"A":   PN = "1"  !CDS_PN = "1";
"B":   PN = "2"  !CDS_PN = "2";
BODY = "AT24C64","I89": #LOCATION = "U6W3" !CDS_LOCATION = "U6W3" #SEC = "1" !CDS_SEC = "1";
"A0":   PN = "1"  !CDS_PN = "1";
"A1":   PN = "2"  !CDS_PN = "2";
"A2":   PN = "3"  !CDS_PN = "3";
"SCL":   PN = "6"  !CDS_PN = "6";
"SDA":   PN = "5"  !CDS_PN = "5";
"WP":   PN = "7"  !CDS_PN = "7";
BODY = "RES","I90": #LOCATION = "R6W21" !CDS_LOCATION = "R6W21" #SEC = "1" !CDS_SEC = "1";
"A":   PN = "1"  !CDS_PN = "1";
"B":   PN = "2"  !CDS_PN = "2";
BODY = "RES","I92": #LOCATION = "R6W23" !CDS_LOCATION = "R6W23" #SEC = "1" !CDS_SEC = "1";
"A":   PN = "1"  !CDS_PN = "1";
"B":   PN = "2"  !CDS_PN = "2";
BODY = "RES","I94": #LOCATION = "R6W22" !CDS_LOCATION = "R6W22" #SEC = "1" !CDS_SEC = "1";
"A":   PN = "1"  !CDS_PN = "1";
"B":   PN = "2"  !CDS_PN = "2";
BODY = "RES","I98": #LOCATION = "R6W11" !CDS_LOCATION = "R6W11" #SEC = "1" !CDS_SEC = "1";
"A":   PN = "1"  !CDS_PN = "1";
"B":   PN = "2"  !CDS_PN = "2";
BODY = "RES","I99": #LOCATION = "R6W12" !CDS_LOCATION = "R6W12" #SEC = "1" !CDS_SEC = "1";
"A":   PN = "1"  !CDS_PN = "1";
"B":   PN = "2"  !CDS_PN = "2";
BODY = "RES","I100": #LOCATION = "R6W24" !CDS_LOCATION = "R6W24" #SEC = "1" !CDS_SEC = "1";
"A":   PN = "1"  !CDS_PN = "1";
"B":   PN = "2"  !CDS_PN = "2";
BODY = "RES","I101": #LOCATION = "R6W25" !CDS_LOCATION = "R6W25" #SEC = "1" !CDS_SEC = "1";
"A":   PN = "1"  !CDS_PN = "1";
"B":   PN = "2"  !CDS_PN = "2";
BODY = "CAP_A","I105": #LOCATION = "C6W4" !CDS_LOCATION = "C6W4" #SEC = "1" !CDS_SEC = "1";
"A":   PN = "1"  !CDS_PN = "1";
"B":   PN = "2"  !CDS_PN = "2";
BODY = "CAP_A","I107": #LOCATION = "C6W2" !CDS_LOCATION = "C6W2" #SEC = "1" !CDS_SEC = "1";
"A":   PN = "1"  !CDS_PN = "1";
"B":   PN = "2"  !CDS_PN = "2";
BODY = "RES","I112": #LOCATION = "R6W28" !CDS_LOCATION = "R6W28" #SEC = "1" !CDS_SEC = "1";
"A":   PN = "1"  !CDS_PN = "1";
"B":   PN = "2"  !CDS_PN = "2";
BODY = "TCA9517DGKR-GP","I118": #LOCATION = "U6W2" !CDS_LOCATION = "U6W2" #SEC = "1" !CDS_SEC = "1";
"EN":   PN = "5"  !CDS_PN = "5";
"GND":   PN = "4"  !CDS_PN = "4";
"SCLA":   PN = "2"  !CDS_PN = "2";
"SCLB":   PN = "7"  !CDS_PN = "7";
"SDAA":   PN = "3"  !CDS_PN = "3";
"SDAB":   PN = "6"  !CDS_PN = "6";
"VCCA":   PN = "1"  !CDS_PN = "1";
"VCCB":   PN = "8"  !CDS_PN = "8";
BODY = "TCA9555PWR-GP","I120": #LOCATION = "U6W1" !CDS_LOCATION = "U6W1" #SEC = "1" !CDS_SEC = "1";
"A0":   PN = "21"  !CDS_PN = "21";
"A1":   PN = "2"  !CDS_PN = "2";
"A2":   PN = "3"  !CDS_PN = "3";
"GND":   PN = "12"  !CDS_PN = "12";
"INT#":   PN = "1"  !CDS_PN = "1";
"P00":   PN = "4"  !CDS_PN = "4";
"P01":   PN = "5"  !CDS_PN = "5";
"P02":   PN = "6"  !CDS_PN = "6";
"P03":   PN = "7"  !CDS_PN = "7";
"P04":   PN = "8"  !CDS_PN = "8";
"P05":   PN = "9"  !CDS_PN = "9";
"P06":   PN = "10"  !CDS_PN = "10";
"P07":   PN = "11"  !CDS_PN = "11";
"P10":   PN = "13"  !CDS_PN = "13";
"P11":   PN = "14"  !CDS_PN = "14";
"P12":   PN = "15"  !CDS_PN = "15";
"P13":   PN = "16"  !CDS_PN = "16";
"P14":   PN = "17"  !CDS_PN = "17";
"P15":   PN = "18"  !CDS_PN = "18";
"P16":   PN = "19"  !CDS_PN = "19";
"P17":   PN = "20"  !CDS_PN = "20";
"SCL":   PN = "22"  !CDS_PN = "22";
"SDA":   PN = "23"  !CDS_PN = "23";
"VCC":   PN = "24"  !CDS_PN = "24";
BODY = "CAP_A","I151": #LOCATION = "C6W1" !CDS_LOCATION = "C6W1" #SEC = "1" !CDS_SEC = "1";
"A":   PN = "1"  !CDS_PN = "1";
"B":   PN = "2"  !CDS_PN = "2";
BODY = "DIODE","I157": #LOCATION = "CR6W1" !CDS_LOCATION = "CR6W1" #SEC = "1" !CDS_SEC = "1";
"A":   PN = "2"  !CDS_PN = "2";
"C":   PN = "1"  !CDS_PN = "1";
BODY = "DIODE","I158": #LOCATION = "CR6W2" !CDS_LOCATION = "CR6W2" #SEC = "1" !CDS_SEC = "1";
"A":   PN = "2"  !CDS_PN = "2";
"C":   PN = "1"  !CDS_PN = "1";
BODY = "RES","I159": #LOCATION = "R6W4" !CDS_LOCATION = "R6W4" #SEC = "1" !CDS_SEC = "1";
"A":   PN = "1"  !CDS_PN = "1";
"B":   PN = "2"  !CDS_PN = "2";
BODY = "RES","I160": #LOCATION = "R6W5" !CDS_LOCATION = "R6W5" #SEC = "1" !CDS_SEC = "1";
"A":   PN = "1"  !CDS_PN = "1";
"B":   PN = "2"  !CDS_PN = "2";
BODY = "RES","I161": #LOCATION = "R6W6" !CDS_LOCATION = "R6W6" #SEC = "1" !CDS_SEC = "1";
"A":   PN = "1"  !CDS_PN = "1";
"B":   PN = "2"  !CDS_PN = "2";
BODY = "RES","I162": #LOCATION = "R6W9" !CDS_LOCATION = "R6W9" #SEC = "1" !CDS_SEC = "1";
"A":   PN = "1"  !CDS_PN = "1";
"B":   PN = "2"  !CDS_PN = "2";
BODY = "RES","I163": #LOCATION = "R6W8" !CDS_LOCATION = "R6W8" #SEC = "1" !CDS_SEC = "1";
"A":   PN = "1"  !CDS_PN = "1";
"B":   PN = "2"  !CDS_PN = "2";
BODY = "RES","I164": #LOCATION = "R6W7" !CDS_LOCATION = "R6W7" #SEC = "1" !CDS_SEC = "1";
"A":   PN = "1"  !CDS_PN = "1";
"B":   PN = "2"  !CDS_PN = "2";
BODY = "RES","I165": #LOCATION = "R6W35" !CDS_LOCATION = "R6W35" #SEC = "1" !CDS_SEC = "1";
"A":   PN = "1"  !CDS_PN = "1";
"B":   PN = "2"  !CDS_PN = "2";
DRAWING = "@baseboard_fab2_lib.baseboard_fab2(sch_1):page249";
BODY = "RES","I2": #LOCATION = "R3W1" !CDS_LOCATION = "R3W1" #SEC = "1" !CDS_SEC = "1";
"A":   PN = "1"  !CDS_PN = "1";
"B":   PN = "2"  !CDS_PN = "2";
BODY = "RES","I7": #LOCATION = "R3W9" !CDS_LOCATION = "R3W9" #SEC = "1" !CDS_SEC = "1";
"A":   PN = "1"  !CDS_PN = "1";
"B":   PN = "2"  !CDS_PN = "2";
BODY = "RES","I8": #LOCATION = "R3W7" !CDS_LOCATION = "R3W7" #SEC = "1" !CDS_SEC = "1";
"A":   PN = "1"  !CDS_PN = "1";
"B":   PN = "2"  !CDS_PN = "2";
BODY = "LMV331IDCKRG4-GP","I15": #LOCATION = "Q9W4" !CDS_LOCATION = "Q9W4" &SEC = "1" #&CDS_SEC = "1";
"+IN":   PN = "1"  !CDS_PN = "1";
"-IN":   PN = "3"  !CDS_PN = "3";
"GND":   PN = "2"  !CDS_PN = "2";
"OUT":   PN = "4"  !CDS_PN = "4";
"VCC":   PN = "5"  !CDS_PN = "5";
BODY = "NPN","I29": #LOCATION = "Q9W2" !CDS_LOCATION = "Q9W2" #SEC = "1" !CDS_SEC = "1";
"B":   PN = "1"  !CDS_PN = "1";
"C":   PN = "3"  !CDS_PN = "3";
"E":   PN = "2"  !CDS_PN = "2";
BODY = "FET_N","I30": #LOCATION = "Q9W1" !CDS_LOCATION = "Q9W1" #SEC = "1" !CDS_SEC = "1";
"DRN":   PN = "3"  !CDS_PN = "3";
"GATE":   PN = "1"  !CDS_PN = "1";
"SRC":   PN = "2"  !CDS_PN = "2";
BODY = "47KR2F-GP","I31": #LOCATION = "R3W4" !CDS_LOCATION = "R3W4" &SEC = "1" #&CDS_SEC = "1";
"1":   PN = "1"  !CDS_PN = "1";
"2":   PN = "2"  !CDS_PN = "2";
BODY = "RES","I34": #LOCATION = "R8W1" !CDS_LOCATION = "R8W1" #SEC = "1" !CDS_SEC = "1";
"A":   PN = "1"  !CDS_PN = "1";
"B":   PN = "2"  !CDS_PN = "2";
BODY = "RES","I36": #LOCATION = "R3W3" !CDS_LOCATION = "R3W3" #SEC = "1" !CDS_SEC = "1";
"A":   PN = "1"  !CDS_PN = "1";
"B":   PN = "2"  !CDS_PN = "2";
BODY = "CAP_A","I37": #LOCATION = "C8W2" !CDS_LOCATION = "C8W2" #SEC = "1" !CDS_SEC = "1";
"A":   PN = "1"  !CDS_PN = "1";
"B":   PN = "2"  !CDS_PN = "2";
BODY = "RES","I48": #LOCATION = "R3W6" !CDS_LOCATION = "R3W6" #SEC = "1" !CDS_SEC = "1";
"A":   PN = "1"  !CDS_PN = "1";
"B":   PN = "2"  !CDS_PN = "2";
BODY = "NPN","I49": #LOCATION = "Q9W3" !CDS_LOCATION = "Q9W3" #SEC = "1" !CDS_SEC = "1";
"B":   PN = "1"  !CDS_PN = "1";
"C":   PN = "3"  !CDS_PN = "3";
"E":   PN = "2"  !CDS_PN = "2";
BODY = "SC1U16V3KX-2GP","I52": #LOCATION = "C8W1" !CDS_LOCATION = "C8W1" &SEC = "1" #&CDS_SEC = "1";
"1":   PN = "1"  !CDS_PN = "1";
"2":   PN = "2"  !CDS_PN = "2";
BODY = "DIODE","I55": #LOCATION = "CR3W1" !CDS_LOCATION = "CR3W1" #SEC = "1" !CDS_SEC = "1";
"A":   PN = "2"  !CDS_PN = "2";
"C":   PN = "1"  !CDS_PN = "1";
BODY = "RES","I56": #LOCATION = "R3W2" !CDS_LOCATION = "R3W2" &SEC = "1" #&CDS_SEC = "1";
"A":   PN = "1"  !CDS_PN = "1";
"B":   PN = "2"  !CDS_PN = "2";
BODY = "CAP_A","I57": #LOCATION = "C3W2" !CDS_LOCATION = "C3W2" #SEC = "1" !CDS_SEC = "1";
"A":   PN = "1"  !CDS_PN = "1";
"B":   PN = "2"  !CDS_PN = "2";
BODY = "RES","I58": #LOCATION = "R3W5" !CDS_LOCATION = "R3W5" #SEC = "1" !CDS_SEC = "1";
"A":   PN = "1"  !CDS_PN = "1";
"B":   PN = "2"  !CDS_PN = "2";
DRAWING = "@baseboard_fab2_lib.baseboard_fab2(sch_1):page143";
BODY = "RES","I58": #LOCATION = "R1T27" !CDS_LOCATION = "R1T27" #SEC = "1" !CDS_SEC = "1";
"A":   PN = "1"  !CDS_PN = "1";
"B":   PN = "2"  !CDS_PN = "2";
BODY = "AST2520A1-GP-GP","I63": #LOCATION = "U25W4" !CDS_LOCATION = "U25W4" &SEC = "1" #&CDS_SEC = "1";
"MA0":   PN = "V13"  !CDS_PN = "V13";
"MA1":   PN = "AB14"  !CDS_PN = "AB14";
"MA2":   PN = "W14"  !CDS_PN = "W14";
"MA3":   PN = "U14"  !CDS_PN = "U14";
"MA4":   PN = "W15"  !CDS_PN = "W15";
"MA5":   PN = "V15"  !CDS_PN = "V15";
"MA6":   PN = "AB16"  !CDS_PN = "AB16";
"MA7":   PN = "AA16"  !CDS_PN = "AA16";
"MA8":   PN = "W16"  !CDS_PN = "W16";
"MA9":   PN = "Y16"  !CDS_PN = "Y16";
"MA10":   PN = "U13"  !CDS_PN = "U13";
"MA11":   PN = "AA14"  !CDS_PN = "AA14";
"MA12":   PN = "Y14"  !CDS_PN = "Y14";
"MA13":   PN = "AB15"  !CDS_PN = "AB15";
"MA14_MACT#":   PN = "Y15"  !CDS_PN = "Y15";
"MA15":   PN = "U15"  !CDS_PN = "U15";
"MBA0":   PN = "U12"  !CDS_PN = "U12";
"MBA1":   PN = "Y13"  !CDS_PN = "Y13";
"MBA2_MBG0":   PN = "W13"  !CDS_PN = "W13";
"MCAS#":   PN = "AB13"  !CDS_PN = "AB13";
"MCKE":   PN = "Y11"  !CDS_PN = "Y11";
"MCKN":   PN = "AB12"  !CDS_PN = "AB12";
"MCKP":   PN = "AB11"  !CDS_PN = "AB11";
"MCS#":   PN = "AA12"  !CDS_PN = "AA12";
"MDM0":   PN = "U8"  !CDS_PN = "U8";
"MDM1":   PN = "AB8"  !CDS_PN = "AB8";
"MDQ0":   PN = "U10"  !CDS_PN = "U10";
"MDQ1":   PN = "W10"  !CDS_PN = "W10";
"MDQ2":   PN = "Y10"  !CDS_PN = "Y10";
"MDQ3":   PN = "AA10"  !CDS_PN = "AA10";
"MDQ4":   PN = "U9"  !CDS_PN = "U9";
"MDQ5":   PN = "Y9"  !CDS_PN = "Y9";
"MDQ6":   PN = "W9"  !CDS_PN = "W9";
"MDQ7":   PN = "V9"  !CDS_PN = "V9";
"MDQ8":   PN = "AA8"  !CDS_PN = "AA8";
"MDQ9":   PN = "Y8"  !CDS_PN = "Y8";
"MDQ10":   PN = "Y7"  !CDS_PN = "Y7";
"MDQ11":   PN = "W8"  !CDS_PN = "W8";
"MDQ12":   PN = "AA6"  !CDS_PN = "AA6";
"MDQ13":   PN = "W7"  !CDS_PN = "W7";
"MDQ14":   PN = "V7"  !CDS_PN = "V7";
"MDQ15":   PN = "U7"  !CDS_PN = "U7";
"MDQS0N":   PN = "AB10"  !CDS_PN = "AB10";
"MDQS0P":   PN = "AB9"  !CDS_PN = "AB9";
"MDQS1N":   PN = "AB6"  !CDS_PN = "AB6";
"MDQS1P":   PN = "AB7"  !CDS_PN = "AB7";
"MIOZ":   PN = "W11"  !CDS_PN = "W11";
"MODT":   PN = "V11"  !CDS_PN = "V11";
"MRAS#":   PN = "W12"  !CDS_PN = "W12";
"MVREF":   PN = "T9"  !CDS_PN = "T9";
"MWE#":   PN = "Y12"  !CDS_PN = "Y12";
BODY = "CAP_A","I67": #LOCATION = "C25W22" !CDS_LOCATION = "C25W22" #SEC = "1" !CDS_SEC = "1";
"A":   PN = "1"  !CDS_PN = "1";
"B":   PN = "2"  !CDS_PN = "2";
DRAWING = "@baseboard_fab2_lib.baseboard_fab2(sch_1):page144";
BODY = "RES","I57": #LOCATION = "R1U14" !CDS_LOCATION = "R1U14" #SEC = "1" !CDS_SEC = "1";
"A":   PN = "1"  !CDS_PN = "1";
"B":   PN = "2"  !CDS_PN = "2";
BODY = "RES","I58": #LOCATION = "R1U13" !CDS_LOCATION = "R1U13" #SEC = "1" !CDS_SEC = "1";
"A":   PN = "1"  !CDS_PN = "1";
"B":   PN = "2"  !CDS_PN = "2";
BODY = "RES","I59": #LOCATION = "R1U12" !CDS_LOCATION = "R1U12" #SEC = "1" !CDS_SEC = "1";
"A":   PN = "1"  !CDS_PN = "1";
"B":   PN = "2"  !CDS_PN = "2";
BODY = "AST2520A1-GP-GP","I95": #LOCATION = "U25W4" !CDS_LOCATION = "U25W4" &SEC = "2" #&CDS_SEC = "2";
"DACB":   PN = "J2"  !CDS_PN = "J2";
"DACG":   PN = "J3"  !CDS_PN = "J3";
"DACR":   PN = "J4"  !CDS_PN = "J4";
"DACRSET":   PN = "K4"  !CDS_PN = "K4";
"GPIOA4_TIMER5_SCL9":   PN = "C14"  !CDS_PN = "C14";
"GPIOA5_TIMER6_SDA9":   PN = "A13"  !CDS_PN = "A13";
"GPIOB0":   PN = "K19"  !CDS_PN = "K19";
"GPIOB1":   PN = "L19"  !CDS_PN = "L19";
"GPIOB2":   PN = "L18"  !CDS_PN = "L18";
"GPIOB3":   PN = "K18"  !CDS_PN = "K18";
"GPIOB4_USBCKI":   PN = "J20"  !CDS_PN = "J20";
"GPIOB5_LPCPD#_LPCSMI#":   PN = "H21"  !CDS_PN = "H21";
"GPIOB6_LPCPME#":   PN = "H22"  !CDS_PN = "H22";
"GPIOB7":   PN = "H20"  !CDS_PN = "H20";
"GPIOG0_SGPS1CK":   PN = "A19"  !CDS_PN = "A19";
"GPIOG1_SGPS1LD":   PN = "E19"  !CDS_PN = "E19";
"GPIOG2_SGPS1I0":   PN = "C19"  !CDS_PN = "C19";
"GPIOG3_SGPS1I1":   PN = "E16"  !CDS_PN = "E16";
"GPIOI0_SYSCS#":   PN = "C18"  !CDS_PN = "C18";
"GPIOI1_SYSCK":   PN = "E15"  !CDS_PN = "E15";
"GPIOI2_SYSMOSI":   PN = "B16"  !CDS_PN = "B16";
"GPIOI3_SYSMISO":   PN = "C16"  !CDS_PN = "C16";
"GPIOI4_SPI1CS0#_VBCS#":   PN = "B15"  !CDS_PN = "B15";
"GPIOI5_SPI1CK_VBCK":   PN = "C15"  !CDS_PN = "C15";
"GPIOI6_SPI1MOSI_VBMOSI":   PN = "A14"  !CDS_PN = "A14";
"GPIOI7_SPI1MISO_VBMISO":   PN = "A15"  !CDS_PN = "A15";
"GPIOJ0_SGPMCK":   PN = "R2"  !CDS_PN = "R2";
"GPIOJ1_SGPMLD":   PN = "L2"  !CDS_PN = "L2";
"GPIOJ2_SGPMO":   PN = "N3"  !CDS_PN = "N3";
"GPIOJ3_SGPMI":   PN = "N4"  !CDS_PN = "N4";
"GPIOK0_SCL5":   PN = "L3"  !CDS_PN = "L3";
"GPIOK1_SDA5":   PN = "L4"  !CDS_PN = "L4";
"GPIOK2_SCL6":   PN = "L1"  !CDS_PN = "L1";
"GPIOK3_SDA6":   PN = "N2"  !CDS_PN = "N2";
"GPIOK4_SCL7":   PN = "N1"  !CDS_PN = "N1";
"GPIOK5_SDA7":   PN = "P1"  !CDS_PN = "P1";
"GPIOK6_SCL8":   PN = "P2"  !CDS_PN = "P2";
"GPIOK7_SDA8":   PN = "R1"  !CDS_PN = "R1";
"GPIOQ0_SCL3":   PN = "A11"  !CDS_PN = "A11";
"GPIOQ1_SDA3":   PN = "A10"  !CDS_PN = "A10";
"GPIOQ2_SCL4":   PN = "A9"  !CDS_PN = "A9";
"GPIOQ3_SDA4":   PN = "B9"  !CDS_PN = "B9";
"GPIOQ4_SCL14":   PN = "N21"  !CDS_PN = "N21";
"GPIOQ5_SDA14":   PN = "N22"  !CDS_PN = "N22";
"GPIOY4_SCL1":   PN = "M18"  !CDS_PN = "M18";
"GPIOY5_SDA1":   PN = "M19"  !CDS_PN = "M19";
"GPIOY6_SCL2":   PN = "M20"  !CDS_PN = "M20";
"GPIOY7_SDA2":   PN = "P20"  !CDS_PN = "P20";
"NTRST":   PN = "E11"  !CDS_PN = "E11";
"RTCK":   PN = "C9"  !CDS_PN = "C9";
"TCK":   PN = "C10"  !CDS_PN = "C10";
"TDI":   PN = "D12"  !CDS_PN = "D12";
"TDO":   PN = "D11"  !CDS_PN = "D11";
"TMS":   PN = "C8"  !CDS_PN = "C8";
BODY = "RES","I114": #LOCATION = "R25W70" !CDS_LOCATION = "R25W70" #SEC = "1" !CDS_SEC = "1";
"A":   PN = "1"  !CDS_PN = "1";
"B":   PN = "2"  !CDS_PN = "2";
BODY = "RES","I118": #LOCATION = "R25W75" !CDS_LOCATION = "R25W75" #SEC = "1" !CDS_SEC = "1";
"A":   PN = "1"  !CDS_PN = "1";
"B":   PN = "2"  !CDS_PN = "2";
BODY = "RES","I139": #LOCATION = "R25W123" !CDS_LOCATION = "R25W123" #SEC = "1" !CDS_SEC = "1";
"A":   PN = "1"  !CDS_PN = "1";
"B":   PN = "2"  !CDS_PN = "2";
BODY = "RES","I140": #LOCATION = "R25W124" !CDS_LOCATION = "R25W124" #SEC = "1" !CDS_SEC = "1";
"A":   PN = "1"  !CDS_PN = "1";
"B":   PN = "2"  !CDS_PN = "2";
BODY = "RES","I141": #LOCATION = "R25W125" !CDS_LOCATION = "R25W125" #SEC = "1" !CDS_SEC = "1";
"A":   PN = "1"  !CDS_PN = "1";
"B":   PN = "2"  !CDS_PN = "2";
BODY = "RES","I148": #LOCATION = "R25W140" !CDS_LOCATION = "R25W140" #SEC = "1" !CDS_SEC = "1";
"A":   PN = "1"  !CDS_PN = "1";
"B":   PN = "2"  !CDS_PN = "2";
BODY = "18KR2F-GP","I150": #LOCATION = "R25W58" !CDS_LOCATION = "R25W58" #SEC = "1" !CDS_SEC = "1";
"1":   PN = "1"  !CDS_PN = "1";
"2":   PN = "2"  !CDS_PN = "2";
BODY = "RES","I151": #LOCATION = "R25W182" !CDS_LOCATION = "R25W182" #SEC = "1" !CDS_SEC = "1";
"A":   PN = "1"  !CDS_PN = "1";
"B":   PN = "2"  !CDS_PN = "2";
DRAWING = "@baseboard_fab2_lib.baseboard_fab2(sch_1):page145";
BODY = "OSC_C","I8": #LOCATION = "Y9F2" !CDS_LOCATION = "Y9F2" #SEC = "1" !CDS_SEC = "1";
"ENABLE_CONTROL":   PN = "1"  !CDS_PN = "1";
"GND":   PN = "2"  !CDS_PN = "2";
"OUT":   PN = "3"  !CDS_PN = "3";
"VDD":   PN = "4"  !CDS_PN = "4";
BODY = "RES","I10": #LOCATION = "R9F60" !CDS_LOCATION = "R9F60" #SEC = "1" !CDS_SEC = "1";
"A":   PN = "1"  !CDS_PN = "1";
"B":   PN = "2"  !CDS_PN = "2";
BODY = "RES","I11": #LOCATION = "R9F62" !CDS_LOCATION = "R9F62" #SEC = "1" !CDS_SEC = "1";
"A":   PN = "1"  !CDS_PN = "1";
"B":   PN = "2"  !CDS_PN = "2";
BODY = "RES","I14": #LOCATION = "R9F61" !CDS_LOCATION = "R9F61" #SEC = "1" !CDS_SEC = "1";
"A":   PN = "1"  !CDS_PN = "1";
"B":   PN = "2"  !CDS_PN = "2";
BODY = "CAP_A","I15": #LOCATION = "C9F23" !CDS_LOCATION = "C9F23" #SEC = "1" !CDS_SEC = "1";
"A":   PN = "1"  !CDS_PN = "1";
"B":   PN = "2"  !CDS_PN = "2";
BODY = "RES","I20": #LOCATION = "R9F33" !CDS_LOCATION = "R9F33" #SEC = "1" !CDS_SEC = "1";
"A":   PN = "1"  !CDS_PN = "1";
"B":   PN = "2"  !CDS_PN = "2";
BODY = "RES","I22": #LOCATION = "R9F20" !CDS_LOCATION = "R9F20" #SEC = "1" !CDS_SEC = "1";
"A":   PN = "1"  !CDS_PN = "1";
"B":   PN = "2"  !CDS_PN = "2";
BODY = "RES","I30": #LOCATION = "R25W61" !CDS_LOCATION = "R25W61" #SEC = "1" !CDS_SEC = "1";
"A":   PN = "1"  !CDS_PN = "1";
"B":   PN = "2"  !CDS_PN = "2";
BODY = "RES","I31": #LOCATION = "R25W62" !CDS_LOCATION = "R25W62" #SEC = "1" !CDS_SEC = "1";
"A":   PN = "1"  !CDS_PN = "1";
"B":   PN = "2"  !CDS_PN = "2";
BODY = "RES","I34": #LOCATION = "R25W60" !CDS_LOCATION = "R25W60" #SEC = "1" !CDS_SEC = "1";
"A":   PN = "1"  !CDS_PN = "1";
"B":   PN = "2"  !CDS_PN = "2";
BODY = "RES","I36": #LOCATION = "R25W64" !CDS_LOCATION = "R25W64" #SEC = "1" !CDS_SEC = "1";
"A":   PN = "1"  !CDS_PN = "1";
"B":   PN = "2"  !CDS_PN = "2";
BODY = "RES","I38": #LOCATION = "R25W65" !CDS_LOCATION = "R25W65" #SEC = "1" !CDS_SEC = "1";
"A":   PN = "1"  !CDS_PN = "1";
"B":   PN = "2"  !CDS_PN = "2";
BODY = "RES","I100": #LOCATION = "R1T15" !CDS_LOCATION = "R1T15" #SEC = "1" !CDS_SEC = "1";
"A":   PN = "1"  !CDS_PN = "1";
"B":   PN = "2"  !CDS_PN = "2";
BODY = "RES","I101": #LOCATION = "R1T23" !CDS_LOCATION = "R1T23" #SEC = "1" !CDS_SEC = "1";
"A":   PN = "1"  !CDS_PN = "1";
"B":   PN = "2"  !CDS_PN = "2";
BODY = "AST2520A1-GP-GP","I117": #LOCATION = "U25W4" !CDS_LOCATION = "U25W4" #SEC = "3" !CDS_SEC = "3";
"CLKIN":   PN = "W18"  !CDS_PN = "W18";
"GPIOA0_MAC1LINK":   PN = "B14"  !CDS_PN = "B14";
"GPIOA1_MAC2LINK":   PN = "D14"  !CDS_PN = "D14";
"GPIOA2_TIMER3_SPI1CS1#":   PN = "D13"  !CDS_PN = "D13";
"GPIOA3_TIMER4":   PN = "E13"  !CDS_PN = "E13";
"GPIOC0_SD1CLK_SCL10":   PN = "C12"  !CDS_PN = "C12";
"GPIOC1_SD1CMD_SDA10":   PN = "A12"  !CDS_PN = "A12";
"GPIOC2_SD1DAT0_SCL11":   PN = "B12"  !CDS_PN = "B12";
"GPIOC3_SD1DAT1_SDA11":   PN = "D9"  !CDS_PN = "D9";
"GPIOC4_SD1DAT2_SCL12":   PN = "D10"  !CDS_PN = "D10";
"GPIOC5_SD1DAT3_SDA12":   PN = "E12"  !CDS_PN = "E12";
"GPIOC6_SD1CD#_SCL13":   PN = "C11"  !CDS_PN = "C11";
"GPIOC7_SD1WP#_SDA13":   PN = "B11"  !CDS_PN = "B11";
"GPIOD0_SD2CLK":   PN = "F19"  !CDS_PN = "F19";
"GPIOD1_SD2CMD":   PN = "E21"  !CDS_PN = "E21";
"GPIOD2_SD2DAT0":   PN = "F20"  !CDS_PN = "F20";
"GPIOD3_SD2DAT1":   PN = "D20"  !CDS_PN = "D20";
"GPIOD4_SD2DAT2":   PN = "D21"  !CDS_PN = "D21";
"GPIOD5_SD2DAT3":   PN = "E20"  !CDS_PN = "E20";
"GPIOD6_SD2CD#":   PN = "G18"  !CDS_PN = "G18";
"GPIOD7_SD2WP#":   PN = "C21"  !CDS_PN = "C21";
"GPIOE0_NCTS3":   PN = "B20"  !CDS_PN = "B20";
"GPIOE1_NDCD3":   PN = "C20"  !CDS_PN = "C20";
"GPIOE2_NDSR3":   PN = "F18"  !CDS_PN = "F18";
"GPIOE3_NRI3":   PN = "F17"  !CDS_PN = "F17";
"GPIOE4_NDTR3":   PN = "E18"  !CDS_PN = "E18";
"GPIOE5_NRTS3":   PN = "D19"  !CDS_PN = "D19";
"GPIOE6_TXD3":   PN = "A20"  !CDS_PN = "A20";
"GPIOE7_RXD3":   PN = "B19"  !CDS_PN = "B19";
"GPIOF0_NCTS4_LHAD0":   PN = "J19"  !CDS_PN = "J19";
"GPIOF1_NDCD4_LHAD1":   PN = "J18"  !CDS_PN = "J18";
"GPIOF2_NDSR4_LHAD2":   PN = "B22"  !CDS_PN = "B22";
"GPIOF3_NRI4_LHAD3":   PN = "B21"  !CDS_PN = "B21";
"GPIOF4_NDTR4_LHCLK":   PN = "A21"  !CDS_PN = "A21";
"GPIOF5_NRTS4_LHFRAME#":   PN = "H19"  !CDS_PN = "H19";
"GPIOF6_TXD4_LHSIRQ#":   PN = "G17"  !CDS_PN = "G17";
"GPIOF7_RXD4_LHRST#":   PN = "H18"  !CDS_PN = "H18";
"GPIOG4_SGPS2CK_SALT1":   PN = "E17"  !CDS_PN = "E17";
"GPIOG5_SGPS2LD_SALT2":   PN = "D16"  !CDS_PN = "D16";
"GPIOG6_SGPS2I0_SALT3":   PN = "D15"  !CDS_PN = "D15";
"GPIOG7_SGPS2I1_SALT4":   PN = "E14"  !CDS_PN = "E14";
"GPIOL0_NCTS1":   PN = "T2"  !CDS_PN = "T2";
"GPIOL1_NDCD1_VPIDE":   PN = "T1"  !CDS_PN = "T1";
"GPIOL2_NDSR1":   PN = "U1"  !CDS_PN = "U1";
"GPIOL3_NRI1_VPIHS":   PN = "U2"  !CDS_PN = "U2";
"GPIOL4_NDTR1_VPIVS":   PN = "P4"  !CDS_PN = "P4";
"GPIOL5_NRTS1_VPICLK":   PN = "P3"  !CDS_PN = "P3";
"GPIOL6_TXD1":   PN = "V1"  !CDS_PN = "V1";
"GPIOL7_RXD1":   PN = "W1"  !CDS_PN = "W1";
"GPIOM0_NCTS2_VPIB2":   PN = "Y1"  !CDS_PN = "Y1";
"GPIOM1_NDCD2_VPIB3":   PN = "AB2"  !CDS_PN = "AB2";
"GPIOM2_NDSR2_VPIB4":   PN = "AA1"  !CDS_PN = "AA1";
"GPIOM3_NRI2_VPIB5":   PN = "Y2"  !CDS_PN = "Y2";
"GPIOM4_NDTR2_VPIB6":   PN = "AA2"  !CDS_PN = "AA2";
"GPIOM5_NRTS2_VPIB7":   PN = "P5"  !CDS_PN = "P5";
"GPIOM6_TXD2_VPIB8":   PN = "R5"  !CDS_PN = "R5";
"GPIOM7_RXD2_VPIB9":   PN = "T5"  !CDS_PN = "T5";
"GPIOY3_SIOONCTRL#":   PN = "P21"  !CDS_PN = "P21";
"PECI":   PN = "AB18"  !CDS_PN = "AB18";
"PEREFCLKN":   PN = "K22"  !CDS_PN = "K22";
"PEREFCLKP":   PN = "K21"  !CDS_PN = "K21";
"PEREXT":   PN = "K20"  !CDS_PN = "K20";
"PERST#":   PN = "L20"  !CDS_PN = "L20";
"PERXN":   PN = "M22"  !CDS_PN = "M22";
"PERXP":   PN = "M21"  !CDS_PN = "M21";
"PETXN":   PN = "L22"  !CDS_PN = "L22";
"PETXP":   PN = "L21"  !CDS_PN = "L21";
"RXD5":   PN = "K2"  !CDS_PN = "K2";
"SRST#":   PN = "U18"  !CDS_PN = "U18";
"TXD5":   PN = "K1"  !CDS_PN = "K1";
BODY = "200R2F-L1-GP","I118": #LOCATION = "R25W67" !CDS_LOCATION = "R25W67" &SEC = "1" #&CDS_SEC = "1";
"1":   PN = "1"  !CDS_PN = "1";
"2":   PN = "2"  !CDS_PN = "2";
BODY = "RES","I119": #LOCATION = "R6W18" !CDS_LOCATION = "R6W18" #SEC = "1" !CDS_SEC = "1";
"A":   PN = "1"  !CDS_PN = "1";
"B":   PN = "2"  !CDS_PN = "2";
BODY = "RES","I120": #LOCATION = "R6W17" !CDS_LOCATION = "R6W17" #SEC = "1" !CDS_SEC = "1";
"A":   PN = "1"  !CDS_PN = "1";
"B":   PN = "2"  !CDS_PN = "2";
BODY = "RES","I136": #LOCATION = "R2T41" !CDS_LOCATION = "R2T41" #SEC = "1" !CDS_SEC = "1";
"A":   PN = "1"  !CDS_PN = "1";
"B":   PN = "2"  !CDS_PN = "2";
BODY = "CAP_A","I158": #LOCATION = "C25W20" !CDS_LOCATION = "C25W20" #SEC = "1" !CDS_SEC = "1";
"A":   PN = "1"  !CDS_PN = "1";
"B":   PN = "2"  !CDS_PN = "2";
BODY = "CAP_A","I159": #LOCATION = "C25W21" !CDS_LOCATION = "C25W21" #SEC = "1" !CDS_SEC = "1";
"A":   PN = "1"  !CDS_PN = "1";
"B":   PN = "2"  !CDS_PN = "2";
BODY = "RES","I160": #LOCATION = "R25W141" !CDS_LOCATION = "R25W141" #SEC = "1" !CDS_SEC = "1";
"A":   PN = "1"  !CDS_PN = "1";
"B":   PN = "2"  !CDS_PN = "2";
BODY = "RES","I163": #LOCATION = "R25W121" !CDS_LOCATION = "R25W121" #SEC = "1" !CDS_SEC = "1";
"A":   PN = "1"  !CDS_PN = "1";
"B":   PN = "2"  !CDS_PN = "2";
BODY = "RES","I164": #LOCATION = "R25W122" !CDS_LOCATION = "R25W122" #SEC = "1" !CDS_SEC = "1";
"A":   PN = "1"  !CDS_PN = "1";
"B":   PN = "2"  !CDS_PN = "2";
BODY = "RES","I173": #LOCATION = "R25W144" !CDS_LOCATION = "R25W144" #SEC = "1" !CDS_SEC = "1";
"A":   PN = "1"  !CDS_PN = "1";
"B":   PN = "2"  !CDS_PN = "2";
BODY = "RES","I175": #LOCATION = "R25W145" !CDS_LOCATION = "R25W145" #SEC = "1" !CDS_SEC = "1";
"A":   PN = "1"  !CDS_PN = "1";
"B":   PN = "2"  !CDS_PN = "2";
BODY = "RES","I176": #LOCATION = "R2W5" !CDS_LOCATION = "R2W5" #SEC = "1" !CDS_SEC = "1";
"A":   PN = "1"  !CDS_PN = "1";
"B":   PN = "2"  !CDS_PN = "2";
DRAWING = "@baseboard_fab2_lib.baseboard_fab2(sch_1):page146";
BODY = "RES","I26": #LOCATION = "R25W83" !CDS_LOCATION = "R25W83" #SEC = "1" !CDS_SEC = "1";
"A":   PN = "1"  !CDS_PN = "1";
"B":   PN = "2"  !CDS_PN = "2";
BODY = "RES","I35": #LOCATION = "R1T25" !CDS_LOCATION = "R1T25" #SEC = "1" !CDS_SEC = "1";
"A":   PN = "1"  !CDS_PN = "1";
"B":   PN = "2"  !CDS_PN = "2";
BODY = "RES","I37": #LOCATION = "R1T26" !CDS_LOCATION = "R1T26" #SEC = "1" !CDS_SEC = "1";
"A":   PN = "1"  !CDS_PN = "1";
"B":   PN = "2"  !CDS_PN = "2";
BODY = "RES","I65": #LOCATION = "R25W63" !CDS_LOCATION = "R25W63" #SEC = "1" !CDS_SEC = "1";
"A":   PN = "1"  !CDS_PN = "1";
"B":   PN = "2"  !CDS_PN = "2";
BODY = "RES","I67": #LOCATION = "R25W81" !CDS_LOCATION = "R25W81" #SEC = "1" !CDS_SEC = "1";
"A":   PN = "1"  !CDS_PN = "1";
"B":   PN = "2"  !CDS_PN = "2";
BODY = "RES","I68": #LOCATION = "R25W82" !CDS_LOCATION = "R25W82" #SEC = "1" !CDS_SEC = "1";
"A":   PN = "1"  !CDS_PN = "1";
"B":   PN = "2"  !CDS_PN = "2";
BODY = "RES","I70": #LOCATION = "R25W74" !CDS_LOCATION = "R25W74" #SEC = "1" !CDS_SEC = "1";
"A":   PN = "1"  !CDS_PN = "1";
"B":   PN = "2"  !CDS_PN = "2";
BODY = "RES","I71": #LOCATION = "R25W72" !CDS_LOCATION = "R25W72" #SEC = "1" !CDS_SEC = "1";
"A":   PN = "1"  !CDS_PN = "1";
"B":   PN = "2"  !CDS_PN = "2";
BODY = "RES","I73": #LOCATION = "R25W73" !CDS_LOCATION = "R25W73" #SEC = "1" !CDS_SEC = "1";
"A":   PN = "1"  !CDS_PN = "1";
"B":   PN = "2"  !CDS_PN = "2";
BODY = "RES","I74": #LOCATION = "R3N24" !CDS_LOCATION = "R3N24" #SEC = "1" !CDS_SEC = "1";
"A":   PN = "1"  !CDS_PN = "1";
"B":   PN = "2"  !CDS_PN = "2";
BODY = "RES","I75": #LOCATION = "R3N26" !CDS_LOCATION = "R3N26" #SEC = "1" !CDS_SEC = "1";
"A":   PN = "1"  !CDS_PN = "1";
"B":   PN = "2"  !CDS_PN = "2";
BODY = "RES","I76": #LOCATION = "R25W66" !CDS_LOCATION = "R25W66" &SEC = "1" #&CDS_SEC = "1";
"A":   PN = "1"  !CDS_PN = "1";
"B":   PN = "2"  !CDS_PN = "2";
BODY = "RES","I78": #LOCATION = "R1U7" !CDS_LOCATION = "R1U7" #SEC = "1" !CDS_SEC = "1";
"A":   PN = "1"  !CDS_PN = "1";
"B":   PN = "2"  !CDS_PN = "2";
BODY = "RES","I84": #LOCATION = "R25W68" !CDS_LOCATION = "R25W68" #SEC = "1" !CDS_SEC = "1";
"A":   PN = "1"  !CDS_PN = "1";
"B":   PN = "2"  !CDS_PN = "2";
BODY = "RES","I85": #LOCATION = "R25W69" !CDS_LOCATION = "R25W69" #SEC = "1" !CDS_SEC = "1";
"A":   PN = "1"  !CDS_PN = "1";
"B":   PN = "2"  !CDS_PN = "2";
BODY = "AST2520A1-GP-GP","I104": #LOCATION = "U25W4" !CDS_LOCATION = "U25W4" &SEC = "4" #&CDS_SEC = "4";
"GPIOAA0_VPOR2_NORD0_SALT7":   PN = "Y21"  !CDS_PN = "Y21";
"GPIOAA1_VPOR3_NORD1_SALT8":   PN = "V21"  !CDS_PN = "V21";
"GPIOAA2_VPOR4_NORD2_SALT9":   PN = "Y22"  !CDS_PN = "Y22";
"GPIOAA3_VPOR5_NORD3_SALT10":   PN = "AA22"  !CDS_PN = "AA22";
"GPIOAA4_VPOR6_NORD4_SALT11":   PN = "U22"  !CDS_PN = "U22";
"GPIOAA5_VPOR7_NORD5_SALT12":   PN = "T20"  !CDS_PN = "T20";
"GPIOAA6_VPOR8_NORD6_SALT13":   PN = "N18"  !CDS_PN = "N18";
"GPIOAA7_VPOR9_NORD7_SALT14":   PN = "P19"  !CDS_PN = "P19";
"GPIOH0_NCTS6":   PN = "A18"  !CDS_PN = "A18";
"GPIOH1_NDCD6":   PN = "B18"  !CDS_PN = "B18";
"GPIOH2_NDSR6":   PN = "D17"  !CDS_PN = "D17";
"GPIOH3_NRI6":   PN = "C17"  !CDS_PN = "C17";
"GPIOH4_NDTR6":   PN = "A17"  !CDS_PN = "A17";
"GPIOH5_NRTS6":   PN = "B17"  !CDS_PN = "B17";
"GPIOH6_TXD6":   PN = "A16"  !CDS_PN = "A16";
"GPIOH7_RXD6":   PN = "D18"  !CDS_PN = "D18";
"GPIOS0_VPOB2_SPI2CS1#":   PN = "V20"  !CDS_PN = "V20";
"GPIOS1_VPOB3_BMCINT":   PN = "U19"  !CDS_PN = "U19";
"GPIOS2_VPOB4_SALT5":   PN = "R18"  !CDS_PN = "R18";
"GPIOS3_VPOB5_SALT6":   PN = "P18"  !CDS_PN = "P18";
"GPIOS4_VPOB6":   PN = "R19"  !CDS_PN = "R19";
"GPIOS5_VPOB7":   PN = "W20"  !CDS_PN = "W20";
"GPIOS6_VPOB8":   PN = "U20"  !CDS_PN = "U20";
"GPIOS7_VPOB9":   PN = "AA20"  !CDS_PN = "AA20";
"GPIOZ0_VPOG2_NORA0_SIOPBI#":   PN = "Y20"  !CDS_PN = "Y20";
"GPIOZ1_VPOG3_NORA1_SIOPWRGD":   PN = "AB20"  !CDS_PN = "AB20";
"GPIOZ2_VPOG4_NORA2_SIOPBO#":   PN = "AB21"  !CDS_PN = "AB21";
"GPIOZ3_VPOG5_NORA3_SIOSCI#":   PN = "AA21"  !CDS_PN = "AA21";
"GPIOZ4_VPOG6_NORA4":   PN = "U21"  !CDS_PN = "U21";
"GPIOZ5_VPOG7_NORA5":   PN = "W22"  !CDS_PN = "W22";
"GPIOZ6_VPOG8_NORA6":   PN = "V22"  !CDS_PN = "V22";
"GPIOZ7_VPOG9_NORA7":   PN = "W21"  !CDS_PN = "W21";
"USB2A_DN":   PN = "A8"  !CDS_PN = "A8";
"USB2A_DP":   PN = "A7"  !CDS_PN = "A7";
"USB2AVRES":   PN = "B8"  !CDS_PN = "B8";
"USB2B_DN":   PN = "A6"  !CDS_PN = "A6";
"USB2B_DP":   PN = "B6"  !CDS_PN = "B6";
"USB2BVRES":   PN = "B7"  !CDS_PN = "B7";
BODY = "AST2520A1-GP-GP","I105": #LOCATION = "U25W4" !CDS_LOCATION = "U25W4" &SEC = "5" #&CDS_SEC = "5";
"ENTEST":   PN = "K3"  !CDS_PN = "K3";
"EXTRST#":   PN = "V18"  !CDS_PN = "V18";
"FWSPICK":   PN = "AA18"  !CDS_PN = "AA18";
"FWSPICS0#":   PN = "AB19"  !CDS_PN = "AB19";
"FWSPIMISO":   PN = "T18"  !CDS_PN = "T18";
"FWSPIMOSI":   PN = "U17"  !CDS_PN = "U17";
"GPIOAB0_VPODE_NOROE#":   PN = "N19"  !CDS_PN = "N19";
"GPIOAB1_VPOHS_NORWE#":   PN = "T21"  !CDS_PN = "T21";
"GPIOAB2_VPOVS_WDTRST1":   PN = "T22"  !CDS_PN = "T22";
"GPIOAB3_VPOCLK_WDTRST2":   PN = "R20"  !CDS_PN = "R20";
"GPIOAC0_ESPID0_LAD0":   PN = "G21"  !CDS_PN = "G21";
"GPIOAC1_ESPID1_LAD1":   PN = "G20"  !CDS_PN = "G20";
"GPIOAC2_ESPID2_LAD2":   PN = "D22"  !CDS_PN = "D22";
"GPIOAC3_ESPID3_LAD3":   PN = "E22"  !CDS_PN = "E22";
"GPIOAC4_ESPICK_LCLK":   PN = "C22"  !CDS_PN = "C22";
"GPIOAC5_ESPICS#_LFRAME#":   PN = "F21"  !CDS_PN = "F21";
"GPIOAC6_ESPIALT#_LSIRQ#":   PN = "F22"  !CDS_PN = "F22";
"GPIOAC7_ESPIRST#_LPCRST#":   PN = "G22"  !CDS_PN = "G22";
"GPIOJ4_VGAHS":   PN = "N5"  !CDS_PN = "N5";
"GPIOJ5_VGAVS":   PN = "R4"  !CDS_PN = "R4";
"GPIOJ6_DDCCLK":   PN = "R3"  !CDS_PN = "R3";
"GPIOJ7_DDCDAT":   PN = "T3"  !CDS_PN = "T3";
"GPIOQ6_OSCCLK":   PN = "B10"  !CDS_PN = "B10";
"GPIOQ7_PEWAKE#":   PN = "N20"  !CDS_PN = "N20";
"GPIOR0_FWSPICS1#":   PN = "AA19"  !CDS_PN = "AA19";
"GPIOR1_FWSPICS2#":   PN = "T19"  !CDS_PN = "T19";
"GPIOR2_SPI2CS0#":   PN = "T17"  !CDS_PN = "T17";
"GPIOR3_SPI2CK":   PN = "Y19"  !CDS_PN = "Y19";
"GPIOR4_SPI2MOSI":   PN = "W19"  !CDS_PN = "W19";
"GPIOR5_SPI2MISO":   PN = "V19"  !CDS_PN = "V19";
"HBLED#":   PN = "Y18"  !CDS_PN = "Y18";
"MALERT#":   PN = "U16"  !CDS_PN = "U16";
"MRESET#":   PN = "AB17"  !CDS_PN = "AB17";
BODY = "RES","I123": #LOCATION = "R25W78" !CDS_LOCATION = "R25W78" #SEC = "1" !CDS_SEC = "1";
"A":   PN = "1"  !CDS_PN = "1";
"B":   PN = "2"  !CDS_PN = "2";
BODY = "RES","I152": #LOCATION = "R25W129" !CDS_LOCATION = "R25W129" #SEC = "1" !CDS_SEC = "1";
"A":   PN = "1"  !CDS_PN = "1";
"B":   PN = "2"  !CDS_PN = "2";
BODY = "RES","I153": #LOCATION = "R25W130" !CDS_LOCATION = "R25W130" #SEC = "1" !CDS_SEC = "1";
"A":   PN = "1"  !CDS_PN = "1";
"B":   PN = "2"  !CDS_PN = "2";
BODY = "CAP","I160": #LOCATION = "C1W21" !CDS_LOCATION = "C1W21" #SEC = "1" !CDS_SEC = "1";
"A":   PN = "1"  !CDS_PN = "1";
"B":   PN = "2"  !CDS_PN = "2";
BODY = "RES","I166": #LOCATION = "R25W184" !CDS_LOCATION = "R25W184" #SEC = "1" !CDS_SEC = "1";
"A":   PN = "1"  !CDS_PN = "1";
"B":   PN = "2"  !CDS_PN = "2";
DRAWING = "@baseboard_fab2_lib.baseboard_fab2(sch_1):page147";
BODY = "RES","I21": #LOCATION = "R25W90" !CDS_LOCATION = "R25W90" #SEC = "1" !CDS_SEC = "1";
"A":   PN = "1"  !CDS_PN = "1";
"B":   PN = "2"  !CDS_PN = "2";
BODY = "RES","I62": #LOCATION = "R1U2" !CDS_LOCATION = "R1U2" #SEC = "1" !CDS_SEC = "1";
"A":   PN = "1"  !CDS_PN = "1";
"B":   PN = "2"  !CDS_PN = "2";
BODY = "RES","I8": #LOCATION = "R25W88" !CDS_LOCATION = "R25W88" #SEC = "1" !CDS_SEC = "1";
"A":   PN = "1"  !CDS_PN = "1";
"B":   PN = "2"  !CDS_PN = "2";
BODY = "RES","I22": #LOCATION = "R25W89" !CDS_LOCATION = "R25W89" #SEC = "1" !CDS_SEC = "1";
"A":   PN = "1"  !CDS_PN = "1";
"B":   PN = "2"  !CDS_PN = "2";
BODY = "RES","I23": #LOCATION = "R25W85" !CDS_LOCATION = "R25W85" #SEC = "1" !CDS_SEC = "1";
"A":   PN = "1"  !CDS_PN = "1";
"B":   PN = "2"  !CDS_PN = "2";
BODY = "RES","I24": #LOCATION = "R25W86" !CDS_LOCATION = "R25W86" #SEC = "1" !CDS_SEC = "1";
"A":   PN = "1"  !CDS_PN = "1";
"B":   PN = "2"  !CDS_PN = "2";
BODY = "RES","I25": #LOCATION = "R25W87" !CDS_LOCATION = "R25W87" #SEC = "1" !CDS_SEC = "1";
"A":   PN = "1"  !CDS_PN = "1";
"B":   PN = "2"  !CDS_PN = "2";
BODY = "RES","I42": #LOCATION = "R25W79" !CDS_LOCATION = "R25W79" #SEC = "1" !CDS_SEC = "1";
"A":   PN = "1"  !CDS_PN = "1";
"B":   PN = "2"  !CDS_PN = "2";
BODY = "RES","I43": #LOCATION = "R25W80" !CDS_LOCATION = "R25W80" #SEC = "1" !CDS_SEC = "1";
"A":   PN = "1"  !CDS_PN = "1";
"B":   PN = "2"  !CDS_PN = "2";
BODY = "RES","I65": #LOCATION = "R1U4" !CDS_LOCATION = "R1U4" #SEC = "1" !CDS_SEC = "1";
"A":   PN = "1"  !CDS_PN = "1";
"B":   PN = "2"  !CDS_PN = "2";
BODY = "RES","I66": #LOCATION = "R1U5" !CDS_LOCATION = "R1U5" #SEC = "1" !CDS_SEC = "1";
"A":   PN = "1"  !CDS_PN = "1";
"B":   PN = "2"  !CDS_PN = "2";
BODY = "RES","I61": #LOCATION = "R1U1" !CDS_LOCATION = "R1U1" #SEC = "1" !CDS_SEC = "1";
"A":   PN = "1"  !CDS_PN = "1";
"B":   PN = "2"  !CDS_PN = "2";
BODY = "RES","I75": #LOCATION = "R2N13" !CDS_LOCATION = "R2N13" #SEC = "1" !CDS_SEC = "1";
"A":   PN = "1"  !CDS_PN = "1";
"B":   PN = "2"  !CDS_PN = "2";
BODY = "AST2520A1-GP-GP","I106": #LOCATION = "U25W4" !CDS_LOCATION = "U25W4" #SEC = "6" !CDS_SEC = "6";
"ADC0_GPIW0":   PN = "F4"  !CDS_PN = "F4";
"ADC1_GPIW1":   PN = "F5"  !CDS_PN = "F5";
"ADC2_GPIW2":   PN = "E2"  !CDS_PN = "E2";
"ADC3_GPIW3":   PN = "E1"  !CDS_PN = "E1";
"ADC4_GPIW4":   PN = "F3"  !CDS_PN = "F3";
"ADC5_GPIW5":   PN = "E3"  !CDS_PN = "E3";
"ADC6_GPIW6":   PN = "G5"  !CDS_PN = "G5";
"ADC7_GPIW7":   PN = "G4"  !CDS_PN = "G4";
"ADC8_GPIX0":   PN = "F2"  !CDS_PN = "F2";
"ADC9_GPIX1":   PN = "G3"  !CDS_PN = "G3";
"ADC10_GPIX2":   PN = "G2"  !CDS_PN = "G2";
"ADC11_GPIX3":   PN = "F1"  !CDS_PN = "F1";
"ADC12_GPIX4":   PN = "H5"  !CDS_PN = "H5";
"ADC13_GPIX5":   PN = "G1"  !CDS_PN = "G1";
"ADC14_GPIX6":   PN = "H3"  !CDS_PN = "H3";
"ADC15_GPIX7":   PN = "H4"  !CDS_PN = "H4";
"ADCREXT":   PN = "J1"  !CDS_PN = "J1";
"ADCVREFN":   PN = "H1"  !CDS_PN = "H1";
"ADCVREFP":   PN = "H2"  !CDS_PN = "H2";
"GPIOA6_TIMER7_MDC2":   PN = "C13"  !CDS_PN = "C13";
"GPIOA7_TIMER8_MDIO2":   PN = "B13"  !CDS_PN = "B13";
"GPION0_PWM0":   PN = "V2"  !CDS_PN = "V2";
"GPION1_PWM1":   PN = "W2"  !CDS_PN = "W2";
"GPION2_PWM2_VPIG2":   PN = "V3"  !CDS_PN = "V3";
"GPION3_PWM3_VPIG3":   PN = "U3"  !CDS_PN = "U3";
"GPION4_PWM4_VPIG4":   PN = "W3"  !CDS_PN = "W3";
"GPION5_PWM5_VPIG5":   PN = "AA3"  !CDS_PN = "AA3";
"GPION6_PWM6_VPIG6":   PN = "Y3"  !CDS_PN = "Y3";
"GPION7_PWM7_VPIG7":   PN = "T4"  !CDS_PN = "T4";
"GPIOO0_TACH0_VPIG8":   PN = "U5"  !CDS_PN = "U5";
"GPIOO1_TACH1_VPIG9":   PN = "U4"  !CDS_PN = "U4";
"GPIOO2_TACH2":   PN = "V5"  !CDS_PN = "V5";
"GPIOO3_TACH3":   PN = "AB4"  !CDS_PN = "AB4";
"GPIOO4_TACH4_VPIR2":   PN = "AB3"  !CDS_PN = "AB3";
"GPIOO5_TACH5_VPIR3":   PN = "Y4"  !CDS_PN = "Y4";
"GPIOO6_TACH6_VPIR4":   PN = "AA4"  !CDS_PN = "AA4";
"GPIOO7_TACH7_VPIR5":   PN = "W4"  !CDS_PN = "W4";
"GPIOP0_TACH8_VPIR6":   PN = "V4"  !CDS_PN = "V4";
"GPIOP1_TACH9_VPIR7":   PN = "W5"  !CDS_PN = "W5";
"GPIOP2_TACH10_VPIR8":   PN = "AA5"  !CDS_PN = "AA5";
"GPIOP3_TACH11_VPIR9":   PN = "AB5"  !CDS_PN = "AB5";
"GPIOP4_TACH12":   PN = "Y6"  !CDS_PN = "Y6";
"GPIOP5_TACH13":   PN = "Y5"  !CDS_PN = "Y5";
"GPIOP6_TACH14":   PN = "W6"  !CDS_PN = "W6";
"GPIOP7_TACH15":   PN = "V6"  !CDS_PN = "V6";
"GPIOR6_MDC1":   PN = "D8"  !CDS_PN = "D8";
"GPIOR7_MDIO1":   PN = "E10"  !CDS_PN = "E10";
"RGMII1RXCK_RMII1RCLKI_GPIOU4":   PN = "B4"  !CDS_PN = "B4";
"RGMII1RXCTL_GPIOU5":   PN = "A4"  !CDS_PN = "A4";
"RGMII1RXD0_RMII1RXD0_GPIOU6":   PN = "A3"  !CDS_PN = "A3";
"RGMII1RXD1_RMII1RXD1_GPIOU7":   PN = "D6"  !CDS_PN = "D6";
"RGMII1RXD2_RMII1CRSDV_GPIOV0":   PN = "C5"  !CDS_PN = "C5";
"RGMII1RXD3_RMII1RXER_GPIOV1":   PN = "C4"  !CDS_PN = "C4";
"RGMII1TXCK_RMII1RCLKO_GPIOT0":   PN = "B5"  !CDS_PN = "B5";
"RGMII1TXCTL_RMII1TXEN_GPIOT1":   PN = "E9"  !CDS_PN = "E9";
"RGMII1TXD0_RMII1TXD0_GPIOT2":   PN = "F9"  !CDS_PN = "F9";
"RGMII1TXD1_RMII1TXD1_GPIOT3":   PN = "A5"  !CDS_PN = "A5";
"RGMII1TXD2_GPIOT4":   PN = "E7"  !CDS_PN = "E7";
"RGMII1TXD3_GPIOT5":   PN = "D7"  !CDS_PN = "D7";
"RGMII2RXCK_RMII2RCLKI_GPIOV2":   PN = "C2"  !CDS_PN = "C2";
"RGMII2RXCTL_GPIOV3":   PN = "C1"  !CDS_PN = "C1";
"RGMII2RXD0_RMII2RXD0_GPIOV4":   PN = "C3"  !CDS_PN = "C3";
"RGMII2RXD1_RMII2RXD1_GPIOV5":   PN = "D1"  !CDS_PN = "D1";
"RGMII2RXD2_RMII2CRSDV_GPIOV6":   PN = "D2"  !CDS_PN = "D2";
"RGMII2RXD3_RMII2RXER_GPIOV7":   PN = "E6"  !CDS_PN = "E6";
"RGMII2TXCK_RMII2RCLKO_GPIOT6":   PN = "B2"  !CDS_PN = "B2";
"RGMII2TXCTL_RMII2TXEN_GPIOT7":   PN = "B1"  !CDS_PN = "B1";
"RGMII2TXD0_RMII2TXD0_GPIOU0":   PN = "A2"  !CDS_PN = "A2";
"RGMII2TXD1_RMII2TXD1_GPIOU1":   PN = "B3"  !CDS_PN = "B3";
"RGMII2TXD2_GPIOU2":   PN = "D5"  !CDS_PN = "D5";
"RGMII2TXD3_GPIOU3":   PN = "D4"  !CDS_PN = "D4";
"RGMIICK":   PN = "D3"  !CDS_PN = "D3";
BODY = "RES","I129": #LOCATION = "R1T24" !CDS_LOCATION = "R1T24" #SEC = "1" !CDS_SEC = "1";
"A":   PN = "1"  !CDS_PN = "1";
"B":   PN = "2"  !CDS_PN = "2";
BODY = "RES","I151": #LOCATION = "R25W57" !CDS_LOCATION = "R25W57" #SEC = "1" !CDS_SEC = "1";
"A":   PN = "1"  !CDS_PN = "1";
"B":   PN = "2"  !CDS_PN = "2";
BODY = "RES","I156": #LOCATION = "R25W142" !CDS_LOCATION = "R25W142" #SEC = "1" !CDS_SEC = "1";
"A":   PN = "1"  !CDS_PN = "1";
"B":   PN = "2"  !CDS_PN = "2";
BODY = "RES","I159": #LOCATION = "R25W143" !CDS_LOCATION = "R25W143" #SEC = "1" !CDS_SEC = "1";
"A":   PN = "1"  !CDS_PN = "1";
"B":   PN = "2"  !CDS_PN = "2";
BODY = "CAP_A","I160": #LOCATION = "C25W9" !CDS_LOCATION = "C25W9" #SEC = "1" !CDS_SEC = "1";
"A":   PN = "1"  !CDS_PN = "1";
"B":   PN = "2"  !CDS_PN = "2";
BODY = "CAP_A","I161": #LOCATION = "C25W7" !CDS_LOCATION = "C25W7" #SEC = "1" !CDS_SEC = "1";
"A":   PN = "1"  !CDS_PN = "1";
"B":   PN = "2"  !CDS_PN = "2";
BODY = "CAP_A","I162": #LOCATION = "C25W8" !CDS_LOCATION = "C25W8" #SEC = "1" !CDS_SEC = "1";
"A":   PN = "1"  !CDS_PN = "1";
"B":   PN = "2"  !CDS_PN = "2";
BODY = "RES","I164": #LOCATION = "R25W157" !CDS_LOCATION = "R25W157" #SEC = "1" !CDS_SEC = "1";
"A":   PN = "1"  !CDS_PN = "1";
"B":   PN = "2"  !CDS_PN = "2";
BODY = "RES","I173": #LOCATION = "R25W181" !CDS_LOCATION = "R25W181" #SEC = "1" !CDS_SEC = "1";
"A":   PN = "1"  !CDS_PN = "1";
"B":   PN = "2"  !CDS_PN = "2";
DRAWING = "@baseboard_fab2_lib.baseboard_fab2(sch_1):page148";
BODY = "RES","I16": #LOCATION = "R25W59" !CDS_LOCATION = "R25W59" #SEC = "1" !CDS_SEC = "1";
"A":   PN = "1"  !CDS_PN = "1";
"B":   PN = "2"  !CDS_PN = "2";
BODY = "CAP_A","I20": #LOCATION = "C1T21" !CDS_LOCATION = "C1T21" #SEC = "1" !CDS_SEC = "1";
"A":   PN = "1"  !CDS_PN = "1";
"B":   PN = "2"  !CDS_PN = "2";
BODY = "AST2520A1-GP-GP","I28": LOCATION = "U25W4" #&CDS_LOCATION = "U25W4" &SEC = "7" #&CDS_SEC = "7";
"ADCAV33":   PN = "J6"  !CDS_PN = "J6";
"BATVDD":   PN = "E4"  !CDS_PN = "E4";
"DACAV33":   PN = "K6"  !CDS_PN = "K6";
"DACDV33":   PN = "K5"  !CDS_PN = "K5";
"GND0":   PN = "A1"  !CDS_PN = "A1";
"GND1":   PN = "A22"  !CDS_PN = "A22";
"GND2":   PN = "AA11"  !CDS_PN = "AA11";
"GND3":   PN = "AA13"  !CDS_PN = "AA13";
"GND4":   PN = "AA15"  !CDS_PN = "AA15";
"GND5":   PN = "AA7"  !CDS_PN = "AA7";
"GND6":   PN = "AA9"  !CDS_PN = "AA9";
"GND7":   PN = "AB1"  !CDS_PN = "AB1";
"GND8":   PN = "AB22"  !CDS_PN = "AB22";
"GND9":   PN = "C6"  !CDS_PN = "C6";
"GND10":   PN = "E8"  !CDS_PN = "E8";
"GND11":   PN = "F16"  !CDS_PN = "F16";
"GND12":   PN = "G19"  !CDS_PN = "G19";
"GND13":   PN = "G6"  !CDS_PN = "G6";
"GND14":   PN = "H6"  !CDS_PN = "H6";
"GND15":   PN = "J10"  !CDS_PN = "J10";
"GND16":   PN = "J11"  !CDS_PN = "J11";
"GND17":   PN = "J12"  !CDS_PN = "J12";
"GND18":   PN = "J13"  !CDS_PN = "J13";
"GND19":   PN = "J14"  !CDS_PN = "J14";
"GND20":   PN = "J21"  !CDS_PN = "J21";
"GND21":   PN = "J22"  !CDS_PN = "J22";
"GND22":   PN = "J5"  !CDS_PN = "J5";
"GND23":   PN = "J9"  !CDS_PN = "J9";
"GND24":   PN = "K10"  !CDS_PN = "K10";
"GND25":   PN = "K11"  !CDS_PN = "K11";
"GND26":   PN = "K12"  !CDS_PN = "K12";
"GND27":   PN = "K13"  !CDS_PN = "K13";
"GND28":   PN = "K14"  !CDS_PN = "K14";
"GND29":   PN = "K16"  !CDS_PN = "K16";
"GND30":   PN = "K9"  !CDS_PN = "K9";
"GND31":   PN = "L10"  !CDS_PN = "L10";
"GND32":   PN = "L11"  !CDS_PN = "L11";
"GND33":   PN = "L12"  !CDS_PN = "L12";
"GND34":   PN = "L13"  !CDS_PN = "L13";
"GND35":   PN = "L14"  !CDS_PN = "L14";
"GND36":   PN = "L9"  !CDS_PN = "L9";
"GND37":   PN = "M1"  !CDS_PN = "M1";
"GND38":   PN = "M10"  !CDS_PN = "M10";
"GND39":   PN = "M11"  !CDS_PN = "M11";
"GND40":   PN = "M12"  !CDS_PN = "M12";
"GND41":   PN = "M13"  !CDS_PN = "M13";
"GND42":   PN = "M14"  !CDS_PN = "M14";
"GND43":   PN = "M16"  !CDS_PN = "M16";
"GND44":   PN = "M17"  !CDS_PN = "M17";
"GND45":   PN = "M2"  !CDS_PN = "M2";
"GND46":   PN = "M3"  !CDS_PN = "M3";
"GND47":   PN = "M4"  !CDS_PN = "M4";
"GND48":   PN = "M5"  !CDS_PN = "M5";
"GND49":   PN = "M6"  !CDS_PN = "M6";
"GND50":   PN = "M7"  !CDS_PN = "M7";
"GND51":   PN = "M9"  !CDS_PN = "M9";
"GND52":   PN = "N10"  !CDS_PN = "N10";
"GND53":   PN = "N11"  !CDS_PN = "N11";
"GND54":   PN = "N12"  !CDS_PN = "N12";
"GND55":   PN = "N13"  !CDS_PN = "N13";
"GND56":   PN = "N14"  !CDS_PN = "N14";
"GND57":   PN = "N9"  !CDS_PN = "N9";
"GND58":   PN = "T16"  !CDS_PN = "T16";
"GND59":   PN = "T6"  !CDS_PN = "T6";
"GND60":   PN = "T7"  !CDS_PN = "T7";
"GND61":   PN = "U11"  !CDS_PN = "U11";
"GND62":   PN = "U6"  !CDS_PN = "U6";
"GND63":   PN = "V10"  !CDS_PN = "V10";
"GND64":   PN = "V12"  !CDS_PN = "V12";
"GND65":   PN = "V14"  !CDS_PN = "V14";
"GND66":   PN = "V16"  !CDS_PN = "V16";
"GND67":   PN = "V8"  !CDS_PN = "V8";
"GND68":   PN = "E5"  !CDS_PN = "E5";
"GPIOY0_SIOS3#":   PN = "R22"  !CDS_PN = "R22";
"GPIOY1_SIOS5#":   PN = "R21"  !CDS_PN = "R21";
"GPIOY2_SIOPWREQ#":   PN = "P22"  !CDS_PN = "P22";
"IV11D0":   PN = "F6"  !CDS_PN = "F6";
"IV11D1":   PN = "G10"  !CDS_PN = "G10";
"IV11D2":   PN = "G11"  !CDS_PN = "G11";
"IV11D3":   PN = "G12"  !CDS_PN = "G12";
"IV11D4":   PN = "G13"  !CDS_PN = "G13";
"IV11D5":   PN = "G14"  !CDS_PN = "G14";
"IV11D6":   PN = "G15"  !CDS_PN = "G15";
"IV11D7":   PN = "G7"  !CDS_PN = "G7";
"IV11D8":   PN = "G8"  !CDS_PN = "G8";
"IV11D9":   PN = "G9"  !CDS_PN = "G9";
"IV11D10":   PN = "H16"  !CDS_PN = "H16";
"IV11D11":   PN = "J16"  !CDS_PN = "J16";
"IV11D12":   PN = "L7"  !CDS_PN = "L7";
"IV11D13":   PN = "N16"  !CDS_PN = "N16";
"IV11D14":   PN = "N7"  !CDS_PN = "N7";
"IV11D15":   PN = "P10"  !CDS_PN = "P10";
"IV11D16":   PN = "P11"  !CDS_PN = "P11";
"IV11D17":   PN = "P12"  !CDS_PN = "P12";
"IV11D18":   PN = "P13"  !CDS_PN = "P13";
"IV11D19":   PN = "P14"  !CDS_PN = "P14";
"IV11D20":   PN = "P16"  !CDS_PN = "P16";
"IV11D21":   PN = "P7"  !CDS_PN = "P7";
"IV11D22":   PN = "P9"  !CDS_PN = "P9";
"IV11D23":   PN = "R16"  !CDS_PN = "R16";
"IV11D24":   PN = "R7"  !CDS_PN = "R7";
"LPVDD0":   PN = "J17"  !CDS_PN = "J17";
"LPVDD1":   PN = "K17"  !CDS_PN = "K17";
"MVDD0":   PN = "T10"  !CDS_PN = "T10";
"MVDD1":   PN = "T12"  !CDS_PN = "T12";
"MVDD2":   PN = "T13"  !CDS_PN = "T13";
"MVDD3":   PN = "T14"  !CDS_PN = "T14";
"MVDD4":   PN = "T8"  !CDS_PN = "T8";
"PEAV11":   PN = "L17"  !CDS_PN = "L17";
"PEAV33":   PN = "L16"  !CDS_PN = "L16";
"PECIVDD":   PN = "AA17"  !CDS_PN = "AA17";
"PLLAV330":   PN = "Y17"  !CDS_PN = "Y17";
"PLLAV331":   PN = "W17"  !CDS_PN = "W17";
"PLLDV11":   PN = "V17"  !CDS_PN = "V17";
"PV33D0":   PN = "F12"  !CDS_PN = "F12";
"PV33D1":   PN = "F13"  !CDS_PN = "F13";
"PV33D2":   PN = "F14"  !CDS_PN = "F14";
"PV33D3":   PN = "F15"  !CDS_PN = "F15";
"PV33D4":   PN = "G16"  !CDS_PN = "G16";
"PV33D5":   PN = "H17"  !CDS_PN = "H17";
"PV33D6":   PN = "K7"  !CDS_PN = "K7";
"PV33D7":   PN = "N17"  !CDS_PN = "N17";
"PV33D8":   PN = "N6"  !CDS_PN = "N6";
"PV33D9":   PN = "P17"  !CDS_PN = "P17";
"PV33D10":   PN = "P6"  !CDS_PN = "P6";
"PV33D11":   PN = "R17"  !CDS_PN = "R17";
"PV33D12":   PN = "R6"  !CDS_PN = "R6";
"PV33D13":   PN = "T11"  !CDS_PN = "T11";
"PV33D14":   PN = "T15"  !CDS_PN = "T15";
"R1VDD0":   PN = "F10"  !CDS_PN = "F10";
"R1VDD1":   PN = "F11"  !CDS_PN = "F11";
"R2VDD0":   PN = "F7"  !CDS_PN = "F7";
"R2VDD1":   PN = "F8"  !CDS_PN = "F8";
"USB2AV33":   PN = "C7"  !CDS_PN = "C7";
"VPLLAV110":   PN = "L5"  !CDS_PN = "L5";
"VPLLAV111":   PN = "L6"  !CDS_PN = "L6";
"VPLLAV330":   PN = "J7"  !CDS_PN = "J7";
"VPLLAV331":   PN = "H7"  !CDS_PN = "H7";
BODY = "RES","I29": #LOCATION = "R25W155" !CDS_LOCATION = "R25W155" #SEC = "1" !CDS_SEC = "1";
"A":   PN = "1"  !CDS_PN = "1";
"B":   PN = "2"  !CDS_PN = "2";
DRAWING = "@baseboard_fab2_lib.baseboard_fab2(sch_1):page248";
BODY = "TTL1G08","I11": #LOCATION = "U14E2" !CDS_LOCATION = "U14E2" #SEC = "1" !CDS_SEC = "1";
"A<0>":   PN = "1"  !CDS_PN = "1";
"B<0>":   PN = "2"  !CDS_PN = "2";
"Y<0>":   PN = "4"  !CDS_PN = "4";
BODY = "CAP_A","I13": #LOCATION = "C14W1" !CDS_LOCATION = "C14W1" #SEC = "1" !CDS_SEC = "1";
"A":   PN = "1"  !CDS_PN = "1";
"B":   PN = "2"  !CDS_PN = "2";
BODY = "CAP_A","I17": #LOCATION = "C14W2" !CDS_LOCATION = "C14W2" #SEC = "1" !CDS_SEC = "1";
"A":   PN = "1"  !CDS_PN = "1";
"B":   PN = "2"  !CDS_PN = "2";
BODY = "TTL1G08","I19": #LOCATION = "U14E3" !CDS_LOCATION = "U14E3" &SEC = "1" #&CDS_SEC = "1";
"A<0>":   PN = "1"  !CDS_PN = "1";
"B<0>":   PN = "2"  !CDS_PN = "2";
"Y<0>":   PN = "4"  !CDS_PN = "4";
BODY = "RES","I24": #LOCATION = "R6W26" !CDS_LOCATION = "R6W26" #SEC = "1" !CDS_SEC = "1";
"A":   PN = "1"  !CDS_PN = "1";
"B":   PN = "2"  !CDS_PN = "2";
BODY = "RES","I25": #LOCATION = "R6W27" !CDS_LOCATION = "R6W27" #SEC = "1" !CDS_SEC = "1";
"A":   PN = "1"  !CDS_PN = "1";
"B":   PN = "2"  !CDS_PN = "2";
BODY = "RES","I26": #LOCATION = "R9W19" !CDS_LOCATION = "R9W19" #SEC = "1" !CDS_SEC = "1";
"A":   PN = "1"  !CDS_PN = "1";
"B":   PN = "2"  !CDS_PN = "2";
BODY = "RES","I27": #LOCATION = "R9W18" !CDS_LOCATION = "R9W18" #SEC = "1" !CDS_SEC = "1";
"A":   PN = "1"  !CDS_PN = "1";
"B":   PN = "2"  !CDS_PN = "2";
BODY = "CAP_A","I30": #LOCATION = "C9W8" !CDS_LOCATION = "C9W8" #SEC = "1" !CDS_SEC = "1";
"A":   PN = "1"  !CDS_PN = "1";
"B":   PN = "2"  !CDS_PN = "2";
BODY = "CAP_A","I32": #LOCATION = "C9W7" !CDS_LOCATION = "C9W7" #SEC = "1" !CDS_SEC = "1";
"A":   PN = "1"  !CDS_PN = "1";
"B":   PN = "2"  !CDS_PN = "2";
BODY = "RES","I34": #LOCATION = "R9W16" !CDS_LOCATION = "R9W16" #SEC = "1" !CDS_SEC = "1";
"A":   PN = "1"  !CDS_PN = "1";
"B":   PN = "2"  !CDS_PN = "2";
BODY = "RES","I35": #LOCATION = "R9W17" !CDS_LOCATION = "R9W17" #SEC = "1" !CDS_SEC = "1";
"A":   PN = "1"  !CDS_PN = "1";
"B":   PN = "2"  !CDS_PN = "2";
BODY = "RES","I37": #LOCATION = "R9W14" !CDS_LOCATION = "R9W14" #SEC = "1" !CDS_SEC = "1";
"A":   PN = "1"  !CDS_PN = "1";
"B":   PN = "2"  !CDS_PN = "2";
BODY = "RES","I38": #LOCATION = "R9W13" !CDS_LOCATION = "R9W13" #SEC = "1" !CDS_SEC = "1";
"A":   PN = "1"  !CDS_PN = "1";
"B":   PN = "2"  !CDS_PN = "2";
BODY = "TCA9517DGKR-GP","I49": #LOCATION = "U1W2" !CDS_LOCATION = "U1W2" #SEC = "1" !CDS_SEC = "1";
"EN":   PN = "5"  !CDS_PN = "5";
"GND":   PN = "4"  !CDS_PN = "4";
"SCLA":   PN = "2"  !CDS_PN = "2";
"SCLB":   PN = "7"  !CDS_PN = "7";
"SDAA":   PN = "3"  !CDS_PN = "3";
"SDAB":   PN = "6"  !CDS_PN = "6";
"VCCA":   PN = "1"  !CDS_PN = "1";
"VCCB":   PN = "8"  !CDS_PN = "8";
DRAWING = "@baseboard_fab2_lib.baseboard_fab2(sch_1):page149";
BODY = "CAP","I5": #LOCATION = "C25W70" !CDS_LOCATION = "C25W70" &SEC = "1" #&CDS_SEC = "1";
"A":   PN = "1"  !CDS_PN = "1";
"B":   PN = "2"  !CDS_PN = "2";
BODY = "CAP","I17": #LOCATION = "C25W69" !CDS_LOCATION = "C25W69" &SEC = "1" #&CDS_SEC = "1";
"A":   PN = "1"  !CDS_PN = "1";
"B":   PN = "2"  !CDS_PN = "2";
BODY = "HCB1608KF-800T30-GP","I22": #LOCATION = "FB2T1" !CDS_LOCATION = "FB2T1" &SEC = "1" #&CDS_SEC = "1";
"1":   PN = "1"  !CDS_PN = "1";
"2":   PN = "2"  !CDS_PN = "2";
BODY = "CAP","I25": #LOCATION = "C25W39" !CDS_LOCATION = "C25W39" &SEC = "1" #&CDS_SEC = "1";
"A":   PN = "1"  !CDS_PN = "1";
"B":   PN = "2"  !CDS_PN = "2";
BODY = "CAP","I31": #LOCATION = "C25W50" !CDS_LOCATION = "C25W50" &SEC = "1" #&CDS_SEC = "1";
"A":   PN = "1"  !CDS_PN = "1";
"B":   PN = "2"  !CDS_PN = "2";
BODY = "CAP","I40": #LOCATION = "C25W62" !CDS_LOCATION = "C25W62" &SEC = "1" #&CDS_SEC = "1";
"A":   PN = "1"  !CDS_PN = "1";
"B":   PN = "2"  !CDS_PN = "2";
BODY = "HCB1608KF-800T30-GP","I42": #LOCATION = "FB2T7" !CDS_LOCATION = "FB2T7" &SEC = "1" #&CDS_SEC = "1";
"1":   PN = "1"  !CDS_PN = "1";
"2":   PN = "2"  !CDS_PN = "2";
BODY = "CAP","I46": #LOCATION = "C25W36" !CDS_LOCATION = "C25W36" &SEC = "1" #&CDS_SEC = "1";
"A":   PN = "1"  !CDS_PN = "1";
"B":   PN = "2"  !CDS_PN = "2";
BODY = "CAP","I50": #LOCATION = "C25W47" !CDS_LOCATION = "C25W47" &SEC = "1" #&CDS_SEC = "1";
"A":   PN = "1"  !CDS_PN = "1";
"B":   PN = "2"  !CDS_PN = "2";
BODY = "CAP","I51": #LOCATION = "C25W46" !CDS_LOCATION = "C25W46" &SEC = "1" #&CDS_SEC = "1";
"A":   PN = "1"  !CDS_PN = "1";
"B":   PN = "2"  !CDS_PN = "2";
BODY = "CAP","I79": #LOCATION = "C25W59" !CDS_LOCATION = "C25W59" #SEC = "1" !CDS_SEC = "1";
"A":   PN = "1"  !CDS_PN = "1";
"B":   PN = "2"  !CDS_PN = "2";
BODY = "HCB1608KF-800T30-GP","I85": #LOCATION = "FB2T3" !CDS_LOCATION = "FB2T3" &SEC = "1" #&CDS_SEC = "1";
"1":   PN = "1"  !CDS_PN = "1";
"2":   PN = "2"  !CDS_PN = "2";
BODY = "HCB1608KF-800T30-GP","I86": #LOCATION = "FB2T4" !CDS_LOCATION = "FB2T4" &SEC = "1" #&CDS_SEC = "1";
"1":   PN = "1"  !CDS_PN = "1";
"2":   PN = "2"  !CDS_PN = "2";
BODY = "HCB1608KF-800T30-GP","I88": #LOCATION = "FB2T5" !CDS_LOCATION = "FB2T5" &SEC = "1" #&CDS_SEC = "1";
"1":   PN = "1"  !CDS_PN = "1";
"2":   PN = "2"  !CDS_PN = "2";
BODY = "CAP","I1": #LOCATION = "C25W30" !CDS_LOCATION = "C25W30" &SEC = "1" #&CDS_SEC = "1";
"A":   PN = "1"  !CDS_PN = "1";
"B":   PN = "2"  !CDS_PN = "2";
BODY = "RES","I90": #LOCATION = "R25W93" !CDS_LOCATION = "R25W93" &SEC = "1" #&CDS_SEC = "1";
"A":   PN = "1"  !CDS_PN = "1";
"B":   PN = "2"  !CDS_PN = "2";
BODY = "RES","I91": #LOCATION = "R25W120" !CDS_LOCATION = "R25W120" &SEC = "1" #&CDS_SEC = "1";
"A":   PN = "1"  !CDS_PN = "1";
"B":   PN = "2"  !CDS_PN = "2";
BODY = "CAP","I92": #LOCATION = "C25W53" !CDS_LOCATION = "C25W53" #SEC = "1" !CDS_SEC = "1";
"A":   PN = "1"  !CDS_PN = "1";
"B":   PN = "2"  !CDS_PN = "2";
BODY = "CAP","I93": #LOCATION = "C25W56" !CDS_LOCATION = "C25W56" &SEC = "1" #&CDS_SEC = "1";
"A":   PN = "1"  !CDS_PN = "1";
"B":   PN = "2"  !CDS_PN = "2";
BODY = "CAP","I95": #LOCATION = "C25W54" !CDS_LOCATION = "C25W54" &SEC = "1" #&CDS_SEC = "1";
"A":   PN = "1"  !CDS_PN = "1";
"B":   PN = "2"  !CDS_PN = "2";
BODY = "CAP","I96": #LOCATION = "C25W40" !CDS_LOCATION = "C25W40" &SEC = "1" #&CDS_SEC = "1";
"A":   PN = "1"  !CDS_PN = "1";
"B":   PN = "2"  !CDS_PN = "2";
BODY = "CAP","I97": #LOCATION = "C25W41" !CDS_LOCATION = "C25W41" &SEC = "1" #&CDS_SEC = "1";
"A":   PN = "1"  !CDS_PN = "1";
"B":   PN = "2"  !CDS_PN = "2";
BODY = "CAP","I98": #LOCATION = "C25W42" !CDS_LOCATION = "C25W42" &SEC = "1" #&CDS_SEC = "1";
"A":   PN = "1"  !CDS_PN = "1";
"B":   PN = "2"  !CDS_PN = "2";
BODY = "CAP","I99": #LOCATION = "C25W32" !CDS_LOCATION = "C25W32" &SEC = "1" #&CDS_SEC = "1";
"A":   PN = "1"  !CDS_PN = "1";
"B":   PN = "2"  !CDS_PN = "2";
BODY = "CAP","I100": #LOCATION = "C25W43" !CDS_LOCATION = "C25W43" &SEC = "1" #&CDS_SEC = "1";
"A":   PN = "1"  !CDS_PN = "1";
"B":   PN = "2"  !CDS_PN = "2";
BODY = "CAP","I101": #LOCATION = "C25W44" !CDS_LOCATION = "C25W44" &SEC = "1" #&CDS_SEC = "1";
"A":   PN = "1"  !CDS_PN = "1";
"B":   PN = "2"  !CDS_PN = "2";
BODY = "CAP","I102": #LOCATION = "C25W33" !CDS_LOCATION = "C25W33" &SEC = "1" #&CDS_SEC = "1";
"A":   PN = "1"  !CDS_PN = "1";
"B":   PN = "2"  !CDS_PN = "2";
BODY = "CAP","I103": #LOCATION = "C25W23" !CDS_LOCATION = "C25W23" &SEC = "1" #&CDS_SEC = "1";
"A":   PN = "1"  !CDS_PN = "1";
"B":   PN = "2"  !CDS_PN = "2";
BODY = "CAP","I104": #LOCATION = "C25W24" !CDS_LOCATION = "C25W24" &SEC = "1" #&CDS_SEC = "1";
"A":   PN = "1"  !CDS_PN = "1";
"B":   PN = "2"  !CDS_PN = "2";
BODY = "CAP","I105": #LOCATION = "C25W25" !CDS_LOCATION = "C25W25" &SEC = "1" #&CDS_SEC = "1";
"A":   PN = "1"  !CDS_PN = "1";
"B":   PN = "2"  !CDS_PN = "2";
BODY = "CAP","I106": #LOCATION = "C25W26" !CDS_LOCATION = "C25W26" &SEC = "1" #&CDS_SEC = "1";
"A":   PN = "1"  !CDS_PN = "1";
"B":   PN = "2"  !CDS_PN = "2";
BODY = "CAP","I107": #LOCATION = "C25W27" !CDS_LOCATION = "C25W27" &SEC = "1" #&CDS_SEC = "1";
"A":   PN = "1"  !CDS_PN = "1";
"B":   PN = "2"  !CDS_PN = "2";
BODY = "CAP","I108": #LOCATION = "C25W28" !CDS_LOCATION = "C25W28" &SEC = "1" #&CDS_SEC = "1";
"A":   PN = "1"  !CDS_PN = "1";
"B":   PN = "2"  !CDS_PN = "2";
BODY = "CAP","I109": #LOCATION = "C25W60" !CDS_LOCATION = "C25W60" &SEC = "1" #&CDS_SEC = "1";
"A":   PN = "1"  !CDS_PN = "1";
"B":   PN = "2"  !CDS_PN = "2";
BODY = "CAP","I110": #LOCATION = "C25W35" !CDS_LOCATION = "C25W35" &SEC = "1" #&CDS_SEC = "1";
"A":   PN = "1"  !CDS_PN = "1";
"B":   PN = "2"  !CDS_PN = "2";
BODY = "CAP","I112": #LOCATION = "C25W48" !CDS_LOCATION = "C25W48" &SEC = "1" #&CDS_SEC = "1";
"A":   PN = "1"  !CDS_PN = "1";
"B":   PN = "2"  !CDS_PN = "2";
BODY = "CAP","I113": #LOCATION = "C25W37" !CDS_LOCATION = "C25W37" &SEC = "1" #&CDS_SEC = "1";
"A":   PN = "1"  !CDS_PN = "1";
"B":   PN = "2"  !CDS_PN = "2";
BODY = "CAP","I114": #LOCATION = "C25W51" !CDS_LOCATION = "C25W51" &SEC = "1" #&CDS_SEC = "1";
"A":   PN = "1"  !CDS_PN = "1";
"B":   PN = "2"  !CDS_PN = "2";
BODY = "CAP","I115": #LOCATION = "C25W71" !CDS_LOCATION = "C25W71" &SEC = "1" #&CDS_SEC = "1";
"A":   PN = "1"  !CDS_PN = "1";
"B":   PN = "2"  !CDS_PN = "2";
BODY = "CAP","I116": #LOCATION = "C25W66" !CDS_LOCATION = "C25W66" &SEC = "1" #&CDS_SEC = "1";
"A":   PN = "1"  !CDS_PN = "1";
"B":   PN = "2"  !CDS_PN = "2";
BODY = "CAP","I117": #LOCATION = "C25W67" !CDS_LOCATION = "C25W67" &SEC = "1" #&CDS_SEC = "1";
"A":   PN = "1"  !CDS_PN = "1";
"B":   PN = "2"  !CDS_PN = "2";
BODY = "CAP","I118": #LOCATION = "C25W52" !CDS_LOCATION = "C25W52" &SEC = "1" #&CDS_SEC = "1";
"A":   PN = "1"  !CDS_PN = "1";
"B":   PN = "2"  !CDS_PN = "2";
BODY = "CAP_A","I119": #LOCATION = "C25W31" !CDS_LOCATION = "C25W31" #SEC = "1" !CDS_SEC = "1";
"A":   PN = "1"  !CDS_PN = "1";
"B":   PN = "2"  !CDS_PN = "2";
BODY = "CAP_A","I120": #LOCATION = "C25W34" !CDS_LOCATION = "C25W34" #SEC = "1" !CDS_SEC = "1";
"A":   PN = "1"  !CDS_PN = "1";
"B":   PN = "2"  !CDS_PN = "2";
BODY = "CAP_A","I121": #LOCATION = "C25W38" !CDS_LOCATION = "C25W38" #SEC = "1" !CDS_SEC = "1";
"A":   PN = "1"  !CDS_PN = "1";
"B":   PN = "2"  !CDS_PN = "2";
BODY = "CAP_A","I122": #LOCATION = "C25W45" !CDS_LOCATION = "C25W45" #SEC = "1" !CDS_SEC = "1";
"A":   PN = "1"  !CDS_PN = "1";
"B":   PN = "2"  !CDS_PN = "2";
BODY = "CAP_A","I123": #LOCATION = "C25W49" !CDS_LOCATION = "C25W49" #SEC = "1" !CDS_SEC = "1";
"A":   PN = "1"  !CDS_PN = "1";
"B":   PN = "2"  !CDS_PN = "2";
BODY = "CAP_A","I124": #LOCATION = "C25W55" !CDS_LOCATION = "C25W55" #SEC = "1" !CDS_SEC = "1";
"A":   PN = "1"  !CDS_PN = "1";
"B":   PN = "2"  !CDS_PN = "2";
BODY = "CAP_A","I125": #LOCATION = "C25W58" !CDS_LOCATION = "C25W58" #SEC = "1" !CDS_SEC = "1";
"A":   PN = "1"  !CDS_PN = "1";
"B":   PN = "2"  !CDS_PN = "2";
BODY = "CAP_A","I126": #LOCATION = "C25W61" !CDS_LOCATION = "C25W61" #SEC = "1" !CDS_SEC = "1";
"A":   PN = "1"  !CDS_PN = "1";
"B":   PN = "2"  !CDS_PN = "2";
BODY = "CAP_A","I128": #LOCATION = "C25W68" !CDS_LOCATION = "C25W68" #SEC = "1" !CDS_SEC = "1";
"A":   PN = "1"  !CDS_PN = "1";
"B":   PN = "2"  !CDS_PN = "2";
BODY = "CAP","I129": #LOCATION = "C25W29" !CDS_LOCATION = "C25W29" #SEC = "1" !CDS_SEC = "1";
"A":   PN = "1"  !CDS_PN = "1";
"B":   PN = "2"  !CDS_PN = "2";
BODY = "CAP","I130": #LOCATION = "C25W57" !CDS_LOCATION = "C25W57" #SEC = "1" !CDS_SEC = "1";
"A":   PN = "1"  !CDS_PN = "1";
"B":   PN = "2"  !CDS_PN = "2";
DRAWING = "@baseboard_fab2_lib.baseboard_fab2(sch_1):page151";
BODY = "H5AN4G6NAFR-TFC-GP","I49": #LOCATION = "U25W5" !CDS_LOCATION = "U25W5" &SEC = "1" #&CDS_SEC = "1";
"A0":   PN = "P3"  !CDS_PN = "P3";
"A1":   PN = "P7"  !CDS_PN = "P7";
"A2":   PN = "R3"  !CDS_PN = "R3";
"A3":   PN = "N7"  !CDS_PN = "N7";
"A4":   PN = "N3"  !CDS_PN = "N3";
"A5":   PN = "P8"  !CDS_PN = "P8";
"A6":   PN = "P2"  !CDS_PN = "P2";
"A7":   PN = "R8"  !CDS_PN = "R8";
"A8":   PN = "R2"  !CDS_PN = "R2";
"A9":   PN = "R7"  !CDS_PN = "R7";
"A10/AP":   PN = "M3"  !CDS_PN = "M3";
"A11":   PN = "T2"  !CDS_PN = "T2";
"A12/BC#":   PN = "M7"  !CDS_PN = "M7";
"A13":   PN = "T8"  !CDS_PN = "T8";
"ACT#":   PN = "L3"  !CDS_PN = "L3";
"ALERT#":   PN = "P9"  !CDS_PN = "P9";
"BA0":   PN = "N2"  !CDS_PN = "N2";
"BA1":   PN = "N8"  !CDS_PN = "N8";
"BG0":   PN = "M2"  !CDS_PN = "M2";
"CAS#/A15":   PN = "M8"  !CDS_PN = "M8";
"CK_C":   PN = "K8"  !CDS_PN = "K8";
"CK_T":   PN = "K7"  !CDS_PN = "K7";
"CKE":   PN = "K2"  !CDS_PN = "K2";
"CS#":   PN = "L7"  !CDS_PN = "L7";
"DML#/DBIL#":   PN = "E7"  !CDS_PN = "E7";
"DMU#/DBIU#":   PN = "E2"  !CDS_PN = "E2";
"DQL0":   PN = "G2"  !CDS_PN = "G2";
"DQL1":   PN = "F7"  !CDS_PN = "F7";
"DQL2":   PN = "H3"  !CDS_PN = "H3";
"DQL3":   PN = "H7"  !CDS_PN = "H7";
"DQL4":   PN = "H2"  !CDS_PN = "H2";
"DQL5":   PN = "H8"  !CDS_PN = "H8";
"DQL6":   PN = "J3"  !CDS_PN = "J3";
"DQL7":   PN = "J7"  !CDS_PN = "J7";
"DQSL_C":   PN = "F3"  !CDS_PN = "F3";
"DQSL_T":   PN = "G3"  !CDS_PN = "G3";
"DQSU_C":   PN = "A7"  !CDS_PN = "A7";
"DQSU_T":   PN = "B7"  !CDS_PN = "B7";
"DQU0":   PN = "A3"  !CDS_PN = "A3";
"DQU1":   PN = "B8"  !CDS_PN = "B8";
"DQU2":   PN = "C3"  !CDS_PN = "C3";
"DQU3":   PN = "C7"  !CDS_PN = "C7";
"DQU4":   PN = "C2"  !CDS_PN = "C2";
"DQU5":   PN = "C8"  !CDS_PN = "C8";
"DQU6":   PN = "D3"  !CDS_PN = "D3";
"DQU7":   PN = "D7"  !CDS_PN = "D7";
"NC#T7":   PN = "T7"  !CDS_PN = "T7";
"ODT":   PN = "K3"  !CDS_PN = "K3";
"PAR":   PN = "T3"  !CDS_PN = "T3";
"RAS#/A16":   PN = "L8"  !CDS_PN = "L8";
"RESET#":   PN = "P1"  !CDS_PN = "P1";
"TEN":   PN = "N9"  !CDS_PN = "N9";
"VDD<0>":   PN = "B3"  !CDS_PN = "B3";
"VDD<1>":   PN = "B9"  !CDS_PN = "B9";
"VDD<2>":   PN = "D1"  !CDS_PN = "D1";
"VDD<3>":   PN = "G7"  !CDS_PN = "G7";
"VDD<4>":   PN = "J1"  !CDS_PN = "J1";
"VDD<5>":   PN = "J9"  !CDS_PN = "J9";
"VDD<6>":   PN = "L1"  !CDS_PN = "L1";
"VDD<7>":   PN = "L9"  !CDS_PN = "L9";
"VDD<8>":   PN = "R1"  !CDS_PN = "R1";
"VDD<9>":   PN = "T9"  !CDS_PN = "T9";
"VDDQ<0>":   PN = "A1"  !CDS_PN = "A1";
"VDDQ<1>":   PN = "A9"  !CDS_PN = "A9";
"VDDQ<2>":   PN = "C1"  !CDS_PN = "C1";
"VDDQ<3>":   PN = "D9"  !CDS_PN = "D9";
"VDDQ<4>":   PN = "F2"  !CDS_PN = "F2";
"VDDQ<5>":   PN = "F8"  !CDS_PN = "F8";
"VDDQ<6>":   PN = "G1"  !CDS_PN = "G1";
"VDDQ<7>":   PN = "G9"  !CDS_PN = "G9";
"VDDQ<8>":   PN = "J2"  !CDS_PN = "J2";
"VDDQ<9>":   PN = "J8"  !CDS_PN = "J8";
"VPP<0>":   PN = "B1"  !CDS_PN = "B1";
"VPP<1>":   PN = "R9"  !CDS_PN = "R9";
"VREFCA":   PN = "M1"  !CDS_PN = "M1";
"VSS<0>":   PN = "B2"  !CDS_PN = "B2";
"VSS<1>":   PN = "E1"  !CDS_PN = "E1";
"VSS<2>":   PN = "E9"  !CDS_PN = "E9";
"VSS<3>":   PN = "G8"  !CDS_PN = "G8";
"VSS<4>":   PN = "K1"  !CDS_PN = "K1";
"VSS<5>":   PN = "K9"  !CDS_PN = "K9";
"VSS<6>":   PN = "M9"  !CDS_PN = "M9";
"VSS<7>":   PN = "N1"  !CDS_PN = "N1";
"VSS<8>":   PN = "T1"  !CDS_PN = "T1";
"VSSQ<0>":   PN = "A2"  !CDS_PN = "A2";
"VSSQ<1>":   PN = "A8"  !CDS_PN = "A8";
"VSSQ<2>":   PN = "C9"  !CDS_PN = "C9";
"VSSQ<3>":   PN = "D2"  !CDS_PN = "D2";
"VSSQ<4>":   PN = "D8"  !CDS_PN = "D8";
"VSSQ<5>":   PN = "E3"  !CDS_PN = "E3";
"VSSQ<6>":   PN = "E8"  !CDS_PN = "E8";
"VSSQ<7>":   PN = "F1"  !CDS_PN = "F1";
"VSSQ<8>":   PN = "H1"  !CDS_PN = "H1";
"VSSQ<9>":   PN = "H9"  !CDS_PN = "H9";
"WE#/A14":   PN = "L2"  !CDS_PN = "L2";
"ZQ":   PN = "F9"  !CDS_PN = "F9";
BODY = "RES","I55": #LOCATION = "R9F29" !CDS_LOCATION = "R9F29" #SEC = "1" !CDS_SEC = "1";
"A":   PN = "1"  !CDS_PN = "1";
"B":   PN = "2"  !CDS_PN = "2";
BODY = "TTL1G07_A","I56": #LOCATION = "U9F3" !CDS_LOCATION = "U9F3" #SEC = "1" !CDS_SEC = "1";
"A":   PN = "2"  !CDS_PN = "2";
"Y":   PN = "4"  !CDS_PN = "4";
BODY = "CAP","I58": #LOCATION = "C25W16" !CDS_LOCATION = "C25W16" #SEC = "1" !CDS_SEC = "1";
"A":   PN = "1"  !CDS_PN = "1";
"B":   PN = "2"  !CDS_PN = "2";
BODY = "RES","I101": #LOCATION = "R25W117" !CDS_LOCATION = "R25W117" #SEC = "1" !CDS_SEC = "1";
"A":   PN = "1"  !CDS_PN = "1";
"B":   PN = "2"  !CDS_PN = "2";
BODY = "SC1U16V3KX-2GP","I120": #LOCATION = "C25W17" !CDS_LOCATION = "C25W17" &SEC = "1" #&CDS_SEC = "1";
"1":   PN = "1"  !CDS_PN = "1";
"2":   PN = "2"  !CDS_PN = "2";
BODY = "SC1U16V3KX-2GP","I121": #LOCATION = "C25W18" !CDS_LOCATION = "C25W18" &SEC = "1" #&CDS_SEC = "1";
"1":   PN = "1"  !CDS_PN = "1";
"2":   PN = "2"  !CDS_PN = "2";
BODY = "CAP","I123": #LOCATION = "C25W19" !CDS_LOCATION = "C25W19" #SEC = "1" !CDS_SEC = "1";
"A":   PN = "1"  !CDS_PN = "1";
"B":   PN = "2"  !CDS_PN = "2";
BODY = "CAP","I125": #LOCATION = "C25W1" !CDS_LOCATION = "C25W1" &SEC = "1" #&CDS_SEC = "1";
"A":   PN = "1"  !CDS_PN = "1";
"B":   PN = "2"  !CDS_PN = "2";
BODY = "RES","I138": #LOCATION = "R9E24" !CDS_LOCATION = "R9E24" #SEC = "1" !CDS_SEC = "1";
"A":   PN = "1"  !CDS_PN = "1";
"B":   PN = "2"  !CDS_PN = "2";
BODY = "CAP","I139": #LOCATION = "C25W2" !CDS_LOCATION = "C25W2" &SEC = "1" #&CDS_SEC = "1";
"A":   PN = "1"  !CDS_PN = "1";
"B":   PN = "2"  !CDS_PN = "2";
BODY = "CAP","I140": #LOCATION = "C25W3" !CDS_LOCATION = "C25W3" &SEC = "1" #&CDS_SEC = "1";
"A":   PN = "1"  !CDS_PN = "1";
"B":   PN = "2"  !CDS_PN = "2";
BODY = "CAP","I141": #LOCATION = "C25W4" !CDS_LOCATION = "C25W4" &SEC = "1" #&CDS_SEC = "1";
"A":   PN = "1"  !CDS_PN = "1";
"B":   PN = "2"  !CDS_PN = "2";
BODY = "CAP","I142": #LOCATION = "C25W5" !CDS_LOCATION = "C25W5" &SEC = "1" #&CDS_SEC = "1";
"A":   PN = "1"  !CDS_PN = "1";
"B":   PN = "2"  !CDS_PN = "2";
BODY = "CAP","I143": #LOCATION = "C25W6" !CDS_LOCATION = "C25W6" &SEC = "1" #&CDS_SEC = "1";
"A":   PN = "1"  !CDS_PN = "1";
"B":   PN = "2"  !CDS_PN = "2";
BODY = "LED","I144": #LOCATION = "DS9E1" !CDS_LOCATION = "DS9E1" #SEC = "1" !CDS_SEC = "1";
"A":   PN = "1"  !CDS_PN = "1";
"C":   PN = "2"  !CDS_PN = "2";
BODY = "FET_N_DUAL","I145": #LOCATION = "Q9E1" !CDS_LOCATION = "Q9E1" #SEC = "2" !CDS_SEC = "2";
"DRAIN<0>":   PN = "3"  !CDS_PN = "3";
"GATE<0>":   PN = "5"  !CDS_PN = "5";
"SOURCE<0>":   PN = "4"  !CDS_PN = "4";
BODY = "RES","I173": #LOCATION = "R9E21" !CDS_LOCATION = "R9E21" #SEC = "1" !CDS_SEC = "1";
"A":   PN = "1"  !CDS_PN = "1";
"B":   PN = "2"  !CDS_PN = "2";
BODY = "RES","I175": #LOCATION = "R8B25" !CDS_LOCATION = "R8B25" #SEC = "1" !CDS_SEC = "1";
"A":   PN = "1"  !CDS_PN = "1";
"B":   PN = "2"  !CDS_PN = "2";
BODY = "FET_N_DUAL","I198": #LOCATION = "Q9E1" !CDS_LOCATION = "Q9E1" #SEC = "1" !CDS_SEC = "1";
"DRAIN<0>":   PN = "6"  !CDS_PN = "6";
"GATE<0>":   PN = "2"  !CDS_PN = "2";
"SOURCE<0>":   PN = "1"  !CDS_PN = "1";
BODY = "RES","I201": #LOCATION = "R1T30" !CDS_LOCATION = "R1T30" #SEC = "1" !CDS_SEC = "1";
"A":   PN = "1"  !CDS_PN = "1";
"B":   PN = "2"  !CDS_PN = "2";
BODY = "RES","I202": #LOCATION = "R1T29" !CDS_LOCATION = "R1T29" #SEC = "1" !CDS_SEC = "1";
"A":   PN = "1"  !CDS_PN = "1";
"B":   PN = "2"  !CDS_PN = "2";
BODY = "RES","I209": #LOCATION = "R9F34" !CDS_LOCATION = "R9F34" #SEC = "1" !CDS_SEC = "1";
"A":   PN = "1"  !CDS_PN = "1";
"B":   PN = "2"  !CDS_PN = "2";
BODY = "RES","I210": #LOCATION = "R25W119" !CDS_LOCATION = "R25W119" #SEC = "1" !CDS_SEC = "1";
"A":   PN = "1"  !CDS_PN = "1";
"B":   PN = "2"  !CDS_PN = "2";
BODY = "RES","I211": #LOCATION = "R25W118" !CDS_LOCATION = "R25W118" #SEC = "1" !CDS_SEC = "1";
"A":   PN = "1"  !CDS_PN = "1";
"B":   PN = "2"  !CDS_PN = "2";
BODY = "CAP_A","I212": #LOCATION = "C25W12" !CDS_LOCATION = "C25W12" #SEC = "1" !CDS_SEC = "1";
"A":   PN = "1"  !CDS_PN = "1";
"B":   PN = "2"  !CDS_PN = "2";
BODY = "CAP_A","I213": #LOCATION = "C25W10" !CDS_LOCATION = "C25W10" #SEC = "1" !CDS_SEC = "1";
"A":   PN = "1"  !CDS_PN = "1";
"B":   PN = "2"  !CDS_PN = "2";
BODY = "CAP_A","I214": #LOCATION = "C25W11" !CDS_LOCATION = "C25W11" #SEC = "1" !CDS_SEC = "1";
"A":   PN = "1"  !CDS_PN = "1";
"B":   PN = "2"  !CDS_PN = "2";
BODY = "CAP_A","I215": #LOCATION = "C25W14" !CDS_LOCATION = "C25W14" #SEC = "1" !CDS_SEC = "1";
"A":   PN = "1"  !CDS_PN = "1";
"B":   PN = "2"  !CDS_PN = "2";
BODY = "CAP_A","I216": #LOCATION = "C25W15" !CDS_LOCATION = "C25W15" #SEC = "1" !CDS_SEC = "1";
"A":   PN = "1"  !CDS_PN = "1";
"B":   PN = "2"  !CDS_PN = "2";
BODY = "CAP_A","I217": #LOCATION = "C25W13" !CDS_LOCATION = "C25W13" #SEC = "1" !CDS_SEC = "1";
"A":   PN = "1"  !CDS_PN = "1";
"B":   PN = "2"  !CDS_PN = "2";
BODY = "CAP","I220": #LOCATION = "C1W20" !CDS_LOCATION = "C1W20" #SEC = "1" !CDS_SEC = "1";
"A":   PN = "1"  !CDS_PN = "1";
"B":   PN = "2"  !CDS_PN = "2";
BODY = "RES","I222": #LOCATION = "R25W30" !CDS_LOCATION = "R25W30" #SEC = "1" !CDS_SEC = "1";
"A":   PN = "1"  !CDS_PN = "1";
"B":   PN = "2"  !CDS_PN = "2";
BODY = "120R2F-GP","I223": #LOCATION = "R25W27" !CDS_LOCATION = "R25W27" #SEC = "1" !CDS_SEC = "1";
"1":   PN = "1"  !CDS_PN = "1";
"2":   PN = "2"  !CDS_PN = "2";
BODY = "120R2F-GP","I224": #LOCATION = "R25W28" !CDS_LOCATION = "R25W28" #SEC = "1" !CDS_SEC = "1";
"1":   PN = "1"  !CDS_PN = "1";
"2":   PN = "2"  !CDS_PN = "2";
BODY = "120R2F-GP","I225": #LOCATION = "R25W29" !CDS_LOCATION = "R25W29" #SEC = "1" !CDS_SEC = "1";
"1":   PN = "1"  !CDS_PN = "1";
"2":   PN = "2"  !CDS_PN = "2";
BODY = "120R2F-GP","I226": #LOCATION = "R25W31" !CDS_LOCATION = "R25W31" #SEC = "1" !CDS_SEC = "1";
"1":   PN = "1"  !CDS_PN = "1";
"2":   PN = "2"  !CDS_PN = "2";
BODY = "120R2F-GP","I227": #LOCATION = "R25W32" !CDS_LOCATION = "R25W32" #SEC = "1" !CDS_SEC = "1";
"1":   PN = "1"  !CDS_PN = "1";
"2":   PN = "2"  !CDS_PN = "2";
BODY = "120R2F-GP","I228": #LOCATION = "R25W33" !CDS_LOCATION = "R25W33" #SEC = "1" !CDS_SEC = "1";
"1":   PN = "1"  !CDS_PN = "1";
"2":   PN = "2"  !CDS_PN = "2";
BODY = "120R2F-GP","I229": #LOCATION = "R25W34" !CDS_LOCATION = "R25W34" #SEC = "1" !CDS_SEC = "1";
"1":   PN = "1"  !CDS_PN = "1";
"2":   PN = "2"  !CDS_PN = "2";
BODY = "120R2F-GP","I230": #LOCATION = "R25W35" !CDS_LOCATION = "R25W35" #SEC = "1" !CDS_SEC = "1";
"1":   PN = "1"  !CDS_PN = "1";
"2":   PN = "2"  !CDS_PN = "2";
BODY = "120R2F-GP","I231": #LOCATION = "R25W36" !CDS_LOCATION = "R25W36" #SEC = "1" !CDS_SEC = "1";
"1":   PN = "1"  !CDS_PN = "1";
"2":   PN = "2"  !CDS_PN = "2";
BODY = "120R2F-GP","I232": #LOCATION = "R25W37" !CDS_LOCATION = "R25W37" #SEC = "1" !CDS_SEC = "1";
"1":   PN = "1"  !CDS_PN = "1";
"2":   PN = "2"  !CDS_PN = "2";
BODY = "120R2F-GP","I233": #LOCATION = "R25W38" !CDS_LOCATION = "R25W38" #SEC = "1" !CDS_SEC = "1";
"1":   PN = "1"  !CDS_PN = "1";
"2":   PN = "2"  !CDS_PN = "2";
BODY = "120R2F-GP","I234": #LOCATION = "R25W39" !CDS_LOCATION = "R25W39" #SEC = "1" !CDS_SEC = "1";
"1":   PN = "1"  !CDS_PN = "1";
"2":   PN = "2"  !CDS_PN = "2";
BODY = "120R2F-GP","I235": #LOCATION = "R25W41" !CDS_LOCATION = "R25W41" #SEC = "1" !CDS_SEC = "1";
"1":   PN = "1"  !CDS_PN = "1";
"2":   PN = "2"  !CDS_PN = "2";
BODY = "120R2F-GP","I236": #LOCATION = "R25W42" !CDS_LOCATION = "R25W42" #SEC = "1" !CDS_SEC = "1";
"1":   PN = "1"  !CDS_PN = "1";
"2":   PN = "2"  !CDS_PN = "2";
BODY = "120R2F-GP","I237": #LOCATION = "R25W44" !CDS_LOCATION = "R25W44" #SEC = "1" !CDS_SEC = "1";
"1":   PN = "1"  !CDS_PN = "1";
"2":   PN = "2"  !CDS_PN = "2";
BODY = "120R2F-GP","I238": #LOCATION = "R25W43" !CDS_LOCATION = "R25W43" #SEC = "1" !CDS_SEC = "1";
"1":   PN = "1"  !CDS_PN = "1";
"2":   PN = "2"  !CDS_PN = "2";
BODY = "120R2F-GP","I239": #LOCATION = "R25W47" !CDS_LOCATION = "R25W47" #SEC = "1" !CDS_SEC = "1";
"1":   PN = "1"  !CDS_PN = "1";
"2":   PN = "2"  !CDS_PN = "2";
BODY = "120R2F-GP","I240": #LOCATION = "R25W48" !CDS_LOCATION = "R25W48" #SEC = "1" !CDS_SEC = "1";
"1":   PN = "1"  !CDS_PN = "1";
"2":   PN = "2"  !CDS_PN = "2";
BODY = "120R2F-GP","I241": #LOCATION = "R25W46" !CDS_LOCATION = "R25W46" #SEC = "1" !CDS_SEC = "1";
"1":   PN = "1"  !CDS_PN = "1";
"2":   PN = "2"  !CDS_PN = "2";
BODY = "120R2F-GP","I242": #LOCATION = "R25W45" !CDS_LOCATION = "R25W45" #SEC = "1" !CDS_SEC = "1";
"1":   PN = "1"  !CDS_PN = "1";
"2":   PN = "2"  !CDS_PN = "2";
BODY = "120R2F-GP","I243": #LOCATION = "R25W49" !CDS_LOCATION = "R25W49" #SEC = "1" !CDS_SEC = "1";
"1":   PN = "1"  !CDS_PN = "1";
"2":   PN = "2"  !CDS_PN = "2";
BODY = "120R2F-GP","I244": #LOCATION = "R25W50" !CDS_LOCATION = "R25W50" #SEC = "1" !CDS_SEC = "1";
"1":   PN = "1"  !CDS_PN = "1";
"2":   PN = "2"  !CDS_PN = "2";
BODY = "120R2F-GP","I245": #LOCATION = "R25W51" !CDS_LOCATION = "R25W51" #SEC = "1" !CDS_SEC = "1";
"1":   PN = "1"  !CDS_PN = "1";
"2":   PN = "2"  !CDS_PN = "2";
BODY = "120R2F-GP","I246": #LOCATION = "R25W52" !CDS_LOCATION = "R25W52" #SEC = "1" !CDS_SEC = "1";
"1":   PN = "1"  !CDS_PN = "1";
"2":   PN = "2"  !CDS_PN = "2";
BODY = "120R2F-GP","I247": #LOCATION = "R25W40" !CDS_LOCATION = "R25W40" #SEC = "1" !CDS_SEC = "1";
"1":   PN = "1"  !CDS_PN = "1";
"2":   PN = "2"  !CDS_PN = "2";
BODY = "120R2F-GP","I248": #LOCATION = "R25W1" !CDS_LOCATION = "R25W1" #SEC = "1" !CDS_SEC = "1";
"1":   PN = "1"  !CDS_PN = "1";
"2":   PN = "2"  !CDS_PN = "2";
BODY = "120R2F-GP","I249": #LOCATION = "R25W2" !CDS_LOCATION = "R25W2" #SEC = "1" !CDS_SEC = "1";
"1":   PN = "1"  !CDS_PN = "1";
"2":   PN = "2"  !CDS_PN = "2";
BODY = "120R2F-GP","I250": #LOCATION = "R25W3" !CDS_LOCATION = "R25W3" #SEC = "1" !CDS_SEC = "1";
"1":   PN = "1"  !CDS_PN = "1";
"2":   PN = "2"  !CDS_PN = "2";
BODY = "120R2F-GP","I251": #LOCATION = "R25W4" !CDS_LOCATION = "R25W4" #SEC = "1" !CDS_SEC = "1";
"1":   PN = "1"  !CDS_PN = "1";
"2":   PN = "2"  !CDS_PN = "2";
BODY = "120R2F-GP","I252": #LOCATION = "R25W5" !CDS_LOCATION = "R25W5" #SEC = "1" !CDS_SEC = "1";
"1":   PN = "1"  !CDS_PN = "1";
"2":   PN = "2"  !CDS_PN = "2";
BODY = "120R2F-GP","I253": #LOCATION = "R25W6" !CDS_LOCATION = "R25W6" #SEC = "1" !CDS_SEC = "1";
"1":   PN = "1"  !CDS_PN = "1";
"2":   PN = "2"  !CDS_PN = "2";
BODY = "120R2F-GP","I254": #LOCATION = "R25W7" !CDS_LOCATION = "R25W7" #SEC = "1" !CDS_SEC = "1";
"1":   PN = "1"  !CDS_PN = "1";
"2":   PN = "2"  !CDS_PN = "2";
BODY = "120R2F-GP","I255": #LOCATION = "R25W8" !CDS_LOCATION = "R25W8" #SEC = "1" !CDS_SEC = "1";
"1":   PN = "1"  !CDS_PN = "1";
"2":   PN = "2"  !CDS_PN = "2";
BODY = "120R2F-GP","I256": #LOCATION = "R25W12" !CDS_LOCATION = "R25W12" #SEC = "1" !CDS_SEC = "1";
"1":   PN = "1"  !CDS_PN = "1";
"2":   PN = "2"  !CDS_PN = "2";
BODY = "120R2F-GP","I257": #LOCATION = "R25W11" !CDS_LOCATION = "R25W11" #SEC = "1" !CDS_SEC = "1";
"1":   PN = "1"  !CDS_PN = "1";
"2":   PN = "2"  !CDS_PN = "2";
BODY = "120R2F-GP","I258": #LOCATION = "R25W9" !CDS_LOCATION = "R25W9" #SEC = "1" !CDS_SEC = "1";
"1":   PN = "1"  !CDS_PN = "1";
"2":   PN = "2"  !CDS_PN = "2";
BODY = "120R2F-GP","I259": #LOCATION = "R25W10" !CDS_LOCATION = "R25W10" #SEC = "1" !CDS_SEC = "1";
"1":   PN = "1"  !CDS_PN = "1";
"2":   PN = "2"  !CDS_PN = "2";
BODY = "120R2F-GP","I260": #LOCATION = "R25W13" !CDS_LOCATION = "R25W13" #SEC = "1" !CDS_SEC = "1";
"1":   PN = "1"  !CDS_PN = "1";
"2":   PN = "2"  !CDS_PN = "2";
BODY = "120R2F-GP","I261": #LOCATION = "R25W16" !CDS_LOCATION = "R25W16" #SEC = "1" !CDS_SEC = "1";
"1":   PN = "1"  !CDS_PN = "1";
"2":   PN = "2"  !CDS_PN = "2";
BODY = "120R2F-GP","I262": #LOCATION = "R25W15" !CDS_LOCATION = "R25W15" #SEC = "1" !CDS_SEC = "1";
"1":   PN = "1"  !CDS_PN = "1";
"2":   PN = "2"  !CDS_PN = "2";
BODY = "120R2F-GP","I263": #LOCATION = "R25W14" !CDS_LOCATION = "R25W14" #SEC = "1" !CDS_SEC = "1";
"1":   PN = "1"  !CDS_PN = "1";
"2":   PN = "2"  !CDS_PN = "2";
BODY = "120R2F-GP","I264": #LOCATION = "R25W17" !CDS_LOCATION = "R25W17" #SEC = "1" !CDS_SEC = "1";
"1":   PN = "1"  !CDS_PN = "1";
"2":   PN = "2"  !CDS_PN = "2";
BODY = "120R2F-GP","I265": #LOCATION = "R25W18" !CDS_LOCATION = "R25W18" #SEC = "1" !CDS_SEC = "1";
"1":   PN = "1"  !CDS_PN = "1";
"2":   PN = "2"  !CDS_PN = "2";
BODY = "120R2F-GP","I266": #LOCATION = "R25W20" !CDS_LOCATION = "R25W20" #SEC = "1" !CDS_SEC = "1";
"1":   PN = "1"  !CDS_PN = "1";
"2":   PN = "2"  !CDS_PN = "2";
BODY = "120R2F-GP","I267": #LOCATION = "R25W19" !CDS_LOCATION = "R25W19" #SEC = "1" !CDS_SEC = "1";
"1":   PN = "1"  !CDS_PN = "1";
"2":   PN = "2"  !CDS_PN = "2";
BODY = "120R2F-GP","I268": #LOCATION = "R25W24" !CDS_LOCATION = "R25W24" #SEC = "1" !CDS_SEC = "1";
"1":   PN = "1"  !CDS_PN = "1";
"2":   PN = "2"  !CDS_PN = "2";
BODY = "120R2F-GP","I269": #LOCATION = "R25W23" !CDS_LOCATION = "R25W23" #SEC = "1" !CDS_SEC = "1";
"1":   PN = "1"  !CDS_PN = "1";
"2":   PN = "2"  !CDS_PN = "2";
BODY = "120R2F-GP","I270": #LOCATION = "R25W22" !CDS_LOCATION = "R25W22" #SEC = "1" !CDS_SEC = "1";
"1":   PN = "1"  !CDS_PN = "1";
"2":   PN = "2"  !CDS_PN = "2";
BODY = "120R2F-GP","I271": #LOCATION = "R25W21" !CDS_LOCATION = "R25W21" #SEC = "1" !CDS_SEC = "1";
"1":   PN = "1"  !CDS_PN = "1";
"2":   PN = "2"  !CDS_PN = "2";
BODY = "120R2F-GP","I274": #LOCATION = "R25W26" !CDS_LOCATION = "R25W26" #SEC = "1" !CDS_SEC = "1";
"1":   PN = "1"  !CDS_PN = "1";
"2":   PN = "2"  !CDS_PN = "2";
BODY = "120R2F-GP","I275": #LOCATION = "R25W25" !CDS_LOCATION = "R25W25" #SEC = "1" !CDS_SEC = "1";
"1":   PN = "1"  !CDS_PN = "1";
"2":   PN = "2"  !CDS_PN = "2";
BODY = "RES","I278": #LOCATION = "R1T40" !CDS_LOCATION = "R1T40" #SEC = "1" !CDS_SEC = "1";
"A":   PN = "1"  !CDS_PN = "1";
"B":   PN = "2"  !CDS_PN = "2";
BODY = "RES","I279": #LOCATION = "R1T28" !CDS_LOCATION = "R1T28" #SEC = "1" !CDS_SEC = "1";
"A":   PN = "1"  !CDS_PN = "1";
"B":   PN = "2"  !CDS_PN = "2";
DRAWING = "@baseboard_fab2_lib.baseboard_fab2(sch_1):page150";
BODY = "RES","I144": #LOCATION = "R25W95" !CDS_LOCATION = "R25W95" #SEC = "1" !CDS_SEC = "1";
"A":   PN = "1"  !CDS_PN = "1";
"B":   PN = "2"  !CDS_PN = "2";
BODY = "RES","I145": #LOCATION = "R25W96" !CDS_LOCATION = "R25W96" #SEC = "1" !CDS_SEC = "1";
"A":   PN = "1"  !CDS_PN = "1";
"B":   PN = "2"  !CDS_PN = "2";
BODY = "RES","I146": #LOCATION = "R25W97" !CDS_LOCATION = "R25W97" #SEC = "1" !CDS_SEC = "1";
"A":   PN = "1"  !CDS_PN = "1";
"B":   PN = "2"  !CDS_PN = "2";
BODY = "RES","I175": #LOCATION = "R25W106" !CDS_LOCATION = "R25W106" #SEC = "1" !CDS_SEC = "1";
"A":   PN = "1"  !CDS_PN = "1";
"B":   PN = "2"  !CDS_PN = "2";
BODY = "RES","I180": #LOCATION = "R25W111" !CDS_LOCATION = "R25W111" #SEC = "1" !CDS_SEC = "1";
"A":   PN = "1"  !CDS_PN = "1";
"B":   PN = "2"  !CDS_PN = "2";
BODY = "RES","I189": #LOCATION = "R25W116" !CDS_LOCATION = "R25W116" #SEC = "1" !CDS_SEC = "1";
"A":   PN = "1"  !CDS_PN = "1";
"B":   PN = "2"  !CDS_PN = "2";
BODY = "RES","I190": #LOCATION = "R25W107" !CDS_LOCATION = "R25W107" #SEC = "1" !CDS_SEC = "1";
"A":   PN = "1"  !CDS_PN = "1";
"B":   PN = "2"  !CDS_PN = "2";
BODY = "RES","I191": #LOCATION = "R25W108" !CDS_LOCATION = "R25W108" #SEC = "1" !CDS_SEC = "1";
"A":   PN = "1"  !CDS_PN = "1";
"B":   PN = "2"  !CDS_PN = "2";
BODY = "RES","I196": #LOCATION = "R25W105" !CDS_LOCATION = "R25W105" #SEC = "1" !CDS_SEC = "1";
"A":   PN = "1"  !CDS_PN = "1";
"B":   PN = "2"  !CDS_PN = "2";
BODY = "RES","I199": #LOCATION = "R25W146" !CDS_LOCATION = "R25W146" #SEC = "1" !CDS_SEC = "1";
"A":   PN = "1"  !CDS_PN = "1";
"B":   PN = "2"  !CDS_PN = "2";
BODY = "RES","I209": #LOCATION = "R25W98" !CDS_LOCATION = "R25W98" #SEC = "1" !CDS_SEC = "1";
"A":   PN = "1"  !CDS_PN = "1";
"B":   PN = "2"  !CDS_PN = "2";
BODY = "RES","I210": #LOCATION = "R25W99" !CDS_LOCATION = "R25W99" #SEC = "1" !CDS_SEC = "1";
"A":   PN = "1"  !CDS_PN = "1";
"B":   PN = "2"  !CDS_PN = "2";
BODY = "RES","I211": #LOCATION = "R25W100" !CDS_LOCATION = "R25W100" #SEC = "1" !CDS_SEC = "1";
"A":   PN = "1"  !CDS_PN = "1";
"B":   PN = "2"  !CDS_PN = "2";
BODY = "RES","I214": #LOCATION = "R25W103" !CDS_LOCATION = "R25W103" #SEC = "1" !CDS_SEC = "1";
"A":   PN = "1"  !CDS_PN = "1";
"B":   PN = "2"  !CDS_PN = "2";
BODY = "RES","I215": #LOCATION = "R25W104" !CDS_LOCATION = "R25W104" #SEC = "1" !CDS_SEC = "1";
"A":   PN = "1"  !CDS_PN = "1";
"B":   PN = "2"  !CDS_PN = "2";
BODY = "RES","I216": #LOCATION = "R25W148" !CDS_LOCATION = "R25W148" #SEC = "1" !CDS_SEC = "1";
"A":   PN = "1"  !CDS_PN = "1";
"B":   PN = "2"  !CDS_PN = "2";
BODY = "RES","I228": #LOCATION = "R25W112" !CDS_LOCATION = "R25W112" #SEC = "1" !CDS_SEC = "1";
"A":   PN = "1"  !CDS_PN = "1";
"B":   PN = "2"  !CDS_PN = "2";
BODY = "RES","I230": #LOCATION = "R25W113" !CDS_LOCATION = "R25W113" #SEC = "1" !CDS_SEC = "1";
"A":   PN = "1"  !CDS_PN = "1";
"B":   PN = "2"  !CDS_PN = "2";
BODY = "RES","I232": #LOCATION = "R25W151" !CDS_LOCATION = "R25W151" #SEC = "1" !CDS_SEC = "1";
"A":   PN = "1"  !CDS_PN = "1";
"B":   PN = "2"  !CDS_PN = "2";
BODY = "RES","I218": #LOCATION = "R25W114" !CDS_LOCATION = "R25W114" #SEC = "1" !CDS_SEC = "1";
"A":   PN = "1"  !CDS_PN = "1";
"B":   PN = "2"  !CDS_PN = "2";
BODY = "RES","I219": #LOCATION = "R25W149" !CDS_LOCATION = "R25W149" #SEC = "1" !CDS_SEC = "1";
"A":   PN = "1"  !CDS_PN = "1";
"B":   PN = "2"  !CDS_PN = "2";
BODY = "RES","I229": #LOCATION = "R25W150" !CDS_LOCATION = "R25W150" #SEC = "1" !CDS_SEC = "1";
"A":   PN = "1"  !CDS_PN = "1";
"B":   PN = "2"  !CDS_PN = "2";
BODY = "RES","I233": #LOCATION = "R25W110" !CDS_LOCATION = "R25W110" #SEC = "1" !CDS_SEC = "1";
"A":   PN = "1"  !CDS_PN = "1";
"B":   PN = "2"  !CDS_PN = "2";
BODY = "RES","I234": #LOCATION = "R25W152" !CDS_LOCATION = "R25W152" #SEC = "1" !CDS_SEC = "1";
"A":   PN = "1"  !CDS_PN = "1";
"B":   PN = "2"  !CDS_PN = "2";
BODY = "RES","I236": #LOCATION = "R25W109" !CDS_LOCATION = "R25W109" #SEC = "1" !CDS_SEC = "1";
"A":   PN = "1"  !CDS_PN = "1";
"B":   PN = "2"  !CDS_PN = "2";
BODY = "RES","I239": #LOCATION = "R25W102" !CDS_LOCATION = "R25W102" #SEC = "1" !CDS_SEC = "1";
"A":   PN = "1"  !CDS_PN = "1";
"B":   PN = "2"  !CDS_PN = "2";
BODY = "RES","I240": #LOCATION = "R25W156" !CDS_LOCATION = "R25W156" #SEC = "1" !CDS_SEC = "1";
"A":   PN = "1"  !CDS_PN = "1";
"B":   PN = "2"  !CDS_PN = "2";
BODY = "RES","I241": #LOCATION = "R25W101" !CDS_LOCATION = "R25W101" #SEC = "1" !CDS_SEC = "1";
"A":   PN = "1"  !CDS_PN = "1";
"B":   PN = "2"  !CDS_PN = "2";
BODY = "RES","I242": #LOCATION = "R25W115" !CDS_LOCATION = "R25W115" #SEC = "1" !CDS_SEC = "1";
"A":   PN = "1"  !CDS_PN = "1";
"B":   PN = "2"  !CDS_PN = "2";
DRAWING = "@baseboard_fab2_lib.baseboard_fab2(sch_1):page250";
BODY = "1MR2F-L-GP","I2": #LOCATION = "R1W6" !CDS_LOCATION = "R1W6" &SEC = "1" #&CDS_SEC = "1";
"1":   PN = "1"  !CDS_PN = "1";
"2":   PN = "2"  !CDS_PN = "2";
BODY = "FET_N_DUAL","I3": #LOCATION = "Q1W4" !CDS_LOCATION = "Q1W4" #SEC = "1" !CDS_SEC = "1";
"DRAIN<0>":   PN = "6"  !CDS_PN = "6";
"GATE<0>":   PN = "2"  !CDS_PN = "2";
"SOURCE<0>":   PN = "1"  !CDS_PN = "1";
BODY = "RES","I6": #LOCATION = "R1W7" !CDS_LOCATION = "R1W7" #SEC = "1" !CDS_SEC = "1";
"A":   PN = "1"  !CDS_PN = "1";
"B":   PN = "2"  !CDS_PN = "2";
BODY = "FET_N_DUAL","I8": #LOCATION = "Q1W4" !CDS_LOCATION = "Q1W4" #SEC = "2" !CDS_SEC = "2";
"DRAIN<0>":   PN = "3"  !CDS_PN = "3";
"GATE<0>":   PN = "5"  !CDS_PN = "5";
"SOURCE<0>":   PN = "4"  !CDS_PN = "4";
BODY = "FET_N_DUAL","I12": #LOCATION = "Q1W2" !CDS_LOCATION = "Q1W2" #SEC = "2" !CDS_SEC = "2";
"DRAIN<0>":   PN = "3"  !CDS_PN = "3";
"GATE<0>":   PN = "5"  !CDS_PN = "5";
"SOURCE<0>":   PN = "4"  !CDS_PN = "4";
BODY = "1MR2F-L-GP","I18": #LOCATION = "R1W1" !CDS_LOCATION = "R1W1" &SEC = "1" #&CDS_SEC = "1";
"1":   PN = "1"  !CDS_PN = "1";
"2":   PN = "2"  !CDS_PN = "2";
BODY = "RES","I22": #LOCATION = "R1W4" !CDS_LOCATION = "R1W4" #SEC = "1" !CDS_SEC = "1";
"A":   PN = "1"  !CDS_PN = "1";
"B":   PN = "2"  !CDS_PN = "2";
BODY = "FET_N_DUAL","I24": #LOCATION = "Q1W2" !CDS_LOCATION = "Q1W2" #SEC = "1" !CDS_SEC = "1";
"DRAIN<0>":   PN = "6"  !CDS_PN = "6";
"GATE<0>":   PN = "2"  !CDS_PN = "2";
"SOURCE<0>":   PN = "1"  !CDS_PN = "1";
BODY = "1MR2F-L-GP","I27": #LOCATION = "R1W3" !CDS_LOCATION = "R1W3" &SEC = "1" #&CDS_SEC = "1";
"1":   PN = "1"  !CDS_PN = "1";
"2":   PN = "2"  !CDS_PN = "2";
BODY = "FET_N","I29": #LOCATION = "Q1W1" !CDS_LOCATION = "Q1W1" #SEC = "1" !CDS_SEC = "1";
"DRN":   PN = "3"  !CDS_PN = "3";
"GATE":   PN = "1"  !CDS_PN = "1";
"SRC":   PN = "2"  !CDS_PN = "2";
DRAWING = "@baseboard_fab2_lib.baseboard_fab2(sch_1):page251";
BODY = "CAP_A","I1": #LOCATION = "C10W2" !CDS_LOCATION = "C10W2" #SEC = "1" !CDS_SEC = "1";
"A":   PN = "1"  !CDS_PN = "1";
"B":   PN = "2"  !CDS_PN = "2";
BODY = "CAP","I3": #LOCATION = "C10W1" !CDS_LOCATION = "C10W1" #SEC = "1" !CDS_SEC = "1";
"A":   PN = "1"  !CDS_PN = "1";
"B":   PN = "2"  !CDS_PN = "2";
BODY = "RES","I5": #LOCATION = "R10W5" !CDS_LOCATION = "R10W5" #SEC = "1" !CDS_SEC = "1";
"A":   PN = "1"  !CDS_PN = "1";
"B":   PN = "2"  !CDS_PN = "2";
BODY = "DIODE","I10": #LOCATION = "CR10W2" !CDS_LOCATION = "CR10W2" #SEC = "1" !CDS_SEC = "1";
"A":   PN = "2"  !CDS_PN = "2";
"C":   PN = "1"  !CDS_PN = "1";
BODY = "RES","I11": #LOCATION = "R10W3" !CDS_LOCATION = "R10W3" #SEC = "1" !CDS_SEC = "1";
"A":   PN = "1"  !CDS_PN = "1";
"B":   PN = "2"  !CDS_PN = "2";
BODY = "DIODE","I12": #LOCATION = "CR10W1" !CDS_LOCATION = "CR10W1" #SEC = "1" !CDS_SEC = "1";
"A":   PN = "2"  !CDS_PN = "2";
"C":   PN = "1"  !CDS_PN = "1";
BODY = "RES","I13": #LOCATION = "R10W1" !CDS_LOCATION = "R10W1" #SEC = "1" !CDS_SEC = "1";
"A":   PN = "1"  !CDS_PN = "1";
"B":   PN = "2"  !CDS_PN = "2";
BODY = "RES","I14": #LOCATION = "R10W4" !CDS_LOCATION = "R10W4" #SEC = "1" !CDS_SEC = "1";
"A":   PN = "1"  !CDS_PN = "1";
"B":   PN = "2"  !CDS_PN = "2";
BODY = "RES","I15": #LOCATION = "R10W2" !CDS_LOCATION = "R10W2" #SEC = "1" !CDS_SEC = "1";
"A":   PN = "1"  !CDS_PN = "1";
"B":   PN = "2"  !CDS_PN = "2";
BODY = "CAP_A","I16": #LOCATION = "C10W3" !CDS_LOCATION = "C10W3" #SEC = "1" !CDS_SEC = "1";
"A":   PN = "1"  !CDS_PN = "1";
"B":   PN = "2"  !CDS_PN = "2";
BODY = "TTL1G07_A","I19": #LOCATION = "U10W1" !CDS_LOCATION = "U10W1" #SEC = "1" !CDS_SEC = "1";
"A":   PN = "2"  !CDS_PN = "2";
"Y":   PN = "4"  !CDS_PN = "4";
BODY = "CAP_A","I21": #LOCATION = "C10W4" !CDS_LOCATION = "C10W4" #SEC = "1" !CDS_SEC = "1";
"A":   PN = "1"  !CDS_PN = "1";
"B":   PN = "2"  !CDS_PN = "2";
BODY = "CONN6_C74770005","I25": #LOCATION = "J1B2" !CDS_LOCATION = "J1B2" #SEC = "1" !CDS_SEC = "1";
"IO1":   PN = "1"  !CDS_PN = "1";
"IO2":   PN = "2"  !CDS_PN = "2";
"IO3":   PN = "3"  !CDS_PN = "3";
"IO4":   PN = "4"  !CDS_PN = "4";
"IO5":   PN = "5"  !CDS_PN = "5";
"IO6":   PN = "6"  !CDS_PN = "6";
BODY = "DIODE","I26": #LOCATION = "CR10W3" !CDS_LOCATION = "CR10W3" #SEC = "1" !CDS_SEC = "1";
"A":   PN = "2"  !CDS_PN = "2";
"C":   PN = "1"  !CDS_PN = "1";
BODY = "RES","I27": #LOCATION = "R10W6" !CDS_LOCATION = "R10W6" #SEC = "1" !CDS_SEC = "1";
"A":   PN = "1"  !CDS_PN = "1";
"B":   PN = "2"  !CDS_PN = "2";
BODY = "CAP_A","I29": #LOCATION = "C10W5" !CDS_LOCATION = "C10W5" #SEC = "1" !CDS_SEC = "1";
"A":   PN = "1"  !CDS_PN = "1";
"B":   PN = "2"  !CDS_PN = "2";
BODY = "RES","I31": #LOCATION = "R10W7" !CDS_LOCATION = "R10W7" #SEC = "1" !CDS_SEC = "1";
"A":   PN = "1"  !CDS_PN = "1";
"B":   PN = "2"  !CDS_PN = "2";
DRAWING = "@baseboard_fab2_lib.baseboard_fab2(sch_1):page255";
BODY = "CAP","I7": #LOCATION = "C25W72" !CDS_LOCATION = "C25W72" #SEC = "1" !CDS_SEC = "1";
"A":   PN = "1"  !CDS_PN = "1";
"B":   PN = "2"  !CDS_PN = "2";
BODY = "CAP","I11": #LOCATION = "C25W73" !CDS_LOCATION = "C25W73" #SEC = "1" !CDS_SEC = "1";
"A":   PN = "1"  !CDS_PN = "1";
"B":   PN = "2"  !CDS_PN = "2";
BODY = "CAP","I12": #LOCATION = "C25W74" !CDS_LOCATION = "C25W74" #SEC = "1" !CDS_SEC = "1";
"A":   PN = "1"  !CDS_PN = "1";
"B":   PN = "2"  !CDS_PN = "2";
BODY = "CAP","I16": #LOCATION = "C25W77" !CDS_LOCATION = "C25W77" #SEC = "1" !CDS_SEC = "1";
"A":   PN = "1"  !CDS_PN = "1";
"B":   PN = "2"  !CDS_PN = "2";
BODY = "CAP","I18": #LOCATION = "C25W76" !CDS_LOCATION = "C25W76" #SEC = "1" !CDS_SEC = "1";
"A":   PN = "1"  !CDS_PN = "1";
"B":   PN = "2"  !CDS_PN = "2";
BODY = "CAP","I21": #LOCATION = "C25W75" !CDS_LOCATION = "C25W75" #SEC = "1" !CDS_SEC = "1";
"A":   PN = "1"  !CDS_PN = "1";
"B":   PN = "2"  !CDS_PN = "2";
BODY = "RES","I22": #LOCATION = "R25W128" !CDS_LOCATION = "R25W128" &SEC = "1" #&CDS_SEC = "1";
"A":   PN = "1"  !CDS_PN = "1";
"B":   PN = "2"  !CDS_PN = "2";
BODY = "RES","I24": #LOCATION = "R25W127" !CDS_LOCATION = "R25W127" &SEC = "1" #&CDS_SEC = "1";
"A":   PN = "1"  !CDS_PN = "1";
"B":   PN = "2"  !CDS_PN = "2";
BODY = "RES","I26": #LOCATION = "R25W126" !CDS_LOCATION = "R25W126" &SEC = "1" #&CDS_SEC = "1";
"A":   PN = "1"  !CDS_PN = "1";
"B":   PN = "2"  !CDS_PN = "2";
BODY = "RES","I30": #LOCATION = "R25W131" !CDS_LOCATION = "R25W131" #SEC = "1" !CDS_SEC = "1";
"A":   PN = "1"  !CDS_PN = "1";
"B":   PN = "2"  !CDS_PN = "2";
BODY = "RES","I31": #LOCATION = "R25W132" !CDS_LOCATION = "R25W132" #SEC = "1" !CDS_SEC = "1";
"A":   PN = "1"  !CDS_PN = "1";
"B":   PN = "2"  !CDS_PN = "2";
BODY = "RES","I34": #LOCATION = "R25W133" !CDS_LOCATION = "R25W133" #SEC = "1" !CDS_SEC = "1";
"A":   PN = "1"  !CDS_PN = "1";
"B":   PN = "2"  !CDS_PN = "2";
BODY = "CAP","I35": #LOCATION = "C25W78" !CDS_LOCATION = "C25W78" #SEC = "1" !CDS_SEC = "1";
"A":   PN = "1"  !CDS_PN = "1";
"B":   PN = "2"  !CDS_PN = "2";
BODY = "RES","I38": #LOCATION = "R25W136" !CDS_LOCATION = "R25W136" #SEC = "1" !CDS_SEC = "1";
"A":   PN = "1"  !CDS_PN = "1";
"B":   PN = "2"  !CDS_PN = "2";
BODY = "CAP","I39": #LOCATION = "C25W79" !CDS_LOCATION = "C25W79" #SEC = "1" !CDS_SEC = "1";
"A":   PN = "1"  !CDS_PN = "1";
"B":   PN = "2"  !CDS_PN = "2";
BODY = "RES","I43": #LOCATION = "R25W134" !CDS_LOCATION = "R25W134" #SEC = "1" !CDS_SEC = "1";
"A":   PN = "1"  !CDS_PN = "1";
"B":   PN = "2"  !CDS_PN = "2";
BODY = "RES","I44": #LOCATION = "R25W135" !CDS_LOCATION = "R25W135" &SEC = "1" #&CDS_SEC = "1";
"A":   PN = "1"  !CDS_PN = "1";
"B":   PN = "2"  !CDS_PN = "2";
BODY = "RES","I49": #LOCATION = "R25W138" !CDS_LOCATION = "R25W138" #SEC = "1" !CDS_SEC = "1";
"A":   PN = "1"  !CDS_PN = "1";
"B":   PN = "2"  !CDS_PN = "2";
BODY = "RES","I59": #LOCATION = "R25W139" !CDS_LOCATION = "R25W139" #SEC = "1" !CDS_SEC = "1";
"A":   PN = "1"  !CDS_PN = "1";
"B":   PN = "2"  !CDS_PN = "2";
BODY = "CAP","I60": #LOCATION = "C25W81" !CDS_LOCATION = "C25W81" #SEC = "1" !CDS_SEC = "1";
"A":   PN = "1"  !CDS_PN = "1";
"B":   PN = "2"  !CDS_PN = "2";
BODY = "CAP","I62": #LOCATION = "C25W82" !CDS_LOCATION = "C25W82" #SEC = "1" !CDS_SEC = "1";
"A":   PN = "1"  !CDS_PN = "1";
"B":   PN = "2"  !CDS_PN = "2";
BODY = "CAP_A","I74": #LOCATION = "C25P83" !CDS_LOCATION = "C25P83" #SEC = "1" !CDS_SEC = "1";
"A":   PN = "1"  !CDS_PN = "1";
"B":   PN = "2"  !CDS_PN = "2";
BODY = "IND-68NH-15-GP","I76": #LOCATION = "L25W1" !CDS_LOCATION = "L25W1" #SEC = "1" !CDS_SEC = "1";
"1":   PN = "1"  !CDS_PN = "1";
"2":   PN = "2"  !CDS_PN = "2";
BODY = "IND-68NH-15-GP","I77": #LOCATION = "L25W2" !CDS_LOCATION = "L25W2" #SEC = "1" !CDS_SEC = "1";
"1":   PN = "1"  !CDS_PN = "1";
"2":   PN = "2"  !CDS_PN = "2";
BODY = "IND-68NH-15-GP","I78": #LOCATION = "L25W3" !CDS_LOCATION = "L25W3" #SEC = "1" !CDS_SEC = "1";
"1":   PN = "1"  !CDS_PN = "1";
"2":   PN = "2"  !CDS_PN = "2";
BODY = "POLYSW-D5A6V-2-GP-U","I89": #LOCATION = "F25W1" !CDS_LOCATION = "F25W1" #SEC = "1" !CDS_SEC = "1";
"1":   PN = "1"  !CDS_PN = "1";
"2":   PN = "2"  !CDS_PN = "2";
BODY = "FET_N_DUAL","I95": #LOCATION = "Q25W4" !CDS_LOCATION = "Q25W4" #SEC = "1" !CDS_SEC = "1";
"DRAIN<0>":   PN = "6"  !CDS_PN = "6";
"GATE<0>":   PN = "2"  !CDS_PN = "2";
"SOURCE<0>":   PN = "1"  !CDS_PN = "1";
BODY = "FET_N_DUAL","I96": #LOCATION = "Q25W4" !CDS_LOCATION = "Q25W4" #SEC = "2" !CDS_SEC = "2";
"DRAIN<0>":   PN = "3"  !CDS_PN = "3";
"GATE<0>":   PN = "5"  !CDS_PN = "5";
"SOURCE<0>":   PN = "4"  !CDS_PN = "4";
BODY = "U74AHCT1G125G-AL5-R-GP-U","I111": #LOCATION = "U25W7" !CDS_LOCATION = "U25W7" #SEC = "1" !CDS_SEC = "1";
"A":   PN = "2"  !CDS_PN = "2";
"GND":   PN = "3"  !CDS_PN = "3";
"OE#":   PN = "1"  !CDS_PN = "1";
"VCC":   PN = "5"  !CDS_PN = "5";
"Y":   PN = "4"  !CDS_PN = "4";
BODY = "U74AHCT1G125G-AL5-R-GP-U","I112": #LOCATION = "U25W8" !CDS_LOCATION = "U25W8" #SEC = "1" !CDS_SEC = "1";
"A":   PN = "2"  !CDS_PN = "2";
"GND":   PN = "3"  !CDS_PN = "3";
"OE#":   PN = "1"  !CDS_PN = "1";
"VCC":   PN = "5"  !CDS_PN = "5";
"Y":   PN = "4"  !CDS_PN = "4";
BODY = "CAP_A","I118": #LOCATION = "C25W90" !CDS_LOCATION = "C25W90" #SEC = "1" !CDS_SEC = "1";
"A":   PN = "1"  !CDS_PN = "1";
"B":   PN = "2"  !CDS_PN = "2";
BODY = "RB551V30-GP","I128": #LOCATION = "D25W8" !CDS_LOCATION = "D25W8" #SEC = "1" !CDS_SEC = "1";
"ANODE":   PN = "A"  !CDS_PN = "A";
"CATHODE":   PN = "K"  !CDS_PN = "K";
BODY = "DIODEAC_DUAL_ARRAY","I129": #LOCATION = "CR25W1" !CDS_LOCATION = "CR25W1" #SEC = "1" !CDS_SEC = "1";
"AC0":   PN = "1"  !CDS_PN = "1";
"AC1":   PN = "2"  !CDS_PN = "2";
"AC2":   PN = "4"  !CDS_PN = "4";
"AC3":   PN = "5"  !CDS_PN = "5";
"GND<0>":   PN = "3"  !CDS_PN = "3";
"OUT0":   PN = "9"  !CDS_PN = "9";
"OUT1":   PN = "8"  !CDS_PN = "8";
"OUT2":   PN = "7"  !CDS_PN = "7";
"OUT3":   PN = "6"  !CDS_PN = "6";
BODY = "DIODEAC_DUAL_ARRAY","I131": #LOCATION = "CR25W2" !CDS_LOCATION = "CR25W2" #SEC = "1" !CDS_SEC = "1";
"AC0":   PN = "1"  !CDS_PN = "1";
"AC1":   PN = "2"  !CDS_PN = "2";
"AC2":   PN = "4"  !CDS_PN = "4";
"AC3":   PN = "5"  !CDS_PN = "5";
"GND<0>":   PN = "3"  !CDS_PN = "3";
"OUT0":   PN = "9"  !CDS_PN = "9";
"OUT1":   PN = "8"  !CDS_PN = "8";
"OUT2":   PN = "7"  !CDS_PN = "7";
"OUT3":   PN = "6"  !CDS_PN = "6";
BODY = "CAP_A","I134": #LOCATION = "C25P80" !CDS_LOCATION = "C25P80" #SEC = "1" !CDS_SEC = "1";
"A":   PN = "1"  !CDS_PN = "1";
"B":   PN = "2"  !CDS_PN = "2";
BODY = "SMC-CON13-GP","I136": #LOCATION = "J25W1" !CDS_LOCATION = "J25W1" #SEC = "1" !CDS_SEC = "1";
"1":   PN = "1"  !CDS_PN = "1";
"2":   PN = "2"  !CDS_PN = "2";
"3":   PN = "3"  !CDS_PN = "3";
"4":   PN = "4"  !CDS_PN = "4";
"5":   PN = "5"  !CDS_PN = "5";
"6":   PN = "6"  !CDS_PN = "6";
"7":   PN = "7"  !CDS_PN = "7";
"8":   PN = "8"  !CDS_PN = "8";
"9":   PN = "9"  !CDS_PN = "9";
"10":   PN = "10"  !CDS_PN = "10";
"11":   PN = "11"  !CDS_PN = "11";
"12":   PN = "12"  !CDS_PN = "12";
"13":   PN = "13"  !CDS_PN = "13";
"PTH1":   PN = "PTH1"  !CDS_PN = "PTH1";
"PTH2":   PN = "PTH2"  !CDS_PN = "PTH2";
DRAWING = "@baseboard_fab2_lib.baseboard_fab2(sch_1):page253";
BODY = "DIODEAC_DUAL_ARRAY","I5": #LOCATION = "CR30W1" !CDS_LOCATION = "CR30W1" #SEC = "1" !CDS_SEC = "1";
"AC0":   PN = "1"  !CDS_PN = "1";
"AC1":   PN = "2"  !CDS_PN = "2";
"AC2":   PN = "4"  !CDS_PN = "4";
"AC3":   PN = "5"  !CDS_PN = "5";
"GND<0>":   PN = "3"  !CDS_PN = "3";
"OUT0":   PN = "9"  !CDS_PN = "9";
"OUT1":   PN = "8"  !CDS_PN = "8";
"OUT2":   PN = "7"  !CDS_PN = "7";
"OUT3":   PN = "6"  !CDS_PN = "6";
BODY = "CHOKE_4PIN","I11": #LOCATION = "L30W2" !CDS_LOCATION = "L30W2" #SEC = "1" !CDS_SEC = "1";
"1":   PN = "1"  !CDS_PN = "1";
"2":   PN = "2"  !CDS_PN = "2";
"3":   PN = "3"  !CDS_PN = "3";
"4":   PN = "4"  !CDS_PN = "4";
BODY = "RES","I12": #LOCATION = "R30W2" !CDS_LOCATION = "R30W2" #SEC = "1" !CDS_SEC = "1";
"A":   PN = "1"  !CDS_PN = "1";
"B":   PN = "2"  !CDS_PN = "2";
BODY = "RES","I13": #LOCATION = "R30W1" !CDS_LOCATION = "R30W1" #SEC = "1" !CDS_SEC = "1";
"A":   PN = "1"  !CDS_PN = "1";
"B":   PN = "2"  !CDS_PN = "2";
BODY = "RES","I14": #LOCATION = "R30W4" !CDS_LOCATION = "R30W4" #SEC = "1" !CDS_SEC = "1";
"A":   PN = "1"  !CDS_PN = "1";
"B":   PN = "2"  !CDS_PN = "2";
BODY = "RES","I15": #LOCATION = "R30W3" !CDS_LOCATION = "R30W3" #SEC = "1" !CDS_SEC = "1";
"A":   PN = "1"  !CDS_PN = "1";
"B":   PN = "2"  !CDS_PN = "2";
BODY = "CHOKE_4PIN","I16": #LOCATION = "L30W1" !CDS_LOCATION = "L30W1" #SEC = "1" !CDS_SEC = "1";
"1":   PN = "1"  !CDS_PN = "1";
"2":   PN = "2"  !CDS_PN = "2";
"3":   PN = "3"  !CDS_PN = "3";
"4":   PN = "4"  !CDS_PN = "4";
BODY = "CAP_A","I19": #LOCATION = "C30W2" !CDS_LOCATION = "C30W2" #SEC = "1" !CDS_SEC = "1";
"A":   PN = "1"  !CDS_PN = "1";
"B":   PN = "2"  !CDS_PN = "2";
BODY = "CAP_A","I20": #LOCATION = "C30W1" !CDS_LOCATION = "C30W1" #SEC = "1" !CDS_SEC = "1";
"A":   PN = "1"  !CDS_PN = "1";
"B":   PN = "2"  !CDS_PN = "2";
BODY = "SKT-USB32-8-GP","I26": #LOCATION = "J30W1" !CDS_LOCATION = "J30W1" #SEC = "1" !CDS_SEC = "1";
"CC1":   PN = "A5"  !CDS_PN = "A5";
"CC2":   PN = "B5"  !CDS_PN = "B5";
"DN1":   PN = "A7"  !CDS_PN = "A7";
"DN2":   PN = "B7"  !CDS_PN = "B7";
"DP1":   PN = "A6"  !CDS_PN = "A6";
"DP2":   PN = "B6"  !CDS_PN = "B6";
"GND<0>":   PN = "A1"  !CDS_PN = "A1";
"GND<1>":   PN = "A12"  !CDS_PN = "A12";
"GND<2>":   PN = "B1"  !CDS_PN = "B1";
"GND<3>":   PN = "B12"  !CDS_PN = "B12";
"NP1":   PN = "NP1"  !CDS_PN = "NP1";
"NP2":   PN = "NP2"  !CDS_PN = "NP2";
"PTH1":   PN = "PTH1"  !CDS_PN = "PTH1";
"PTH2":   PN = "PTH2"  !CDS_PN = "PTH2";
"PTH3":   PN = "PTH3"  !CDS_PN = "PTH3";
"PTH4":   PN = "PTH4"  !CDS_PN = "PTH4";
"PTH5":   PN = "PTH5"  !CDS_PN = "PTH5";
"PTH6":   PN = "PTH6"  !CDS_PN = "PTH6";
"PTH7":   PN = "PTH7"  !CDS_PN = "PTH7";
"PTH8":   PN = "PTH8"  !CDS_PN = "PTH8";
"SBU1":   PN = "A8"  !CDS_PN = "A8";
"SBU2":   PN = "B8"  !CDS_PN = "B8";
"SSRXN1":   PN = "B10"  !CDS_PN = "B10";
"SSRXN2":   PN = "A10"  !CDS_PN = "A10";
"SSRXP1":   PN = "B11"  !CDS_PN = "B11";
"SSRXP2":   PN = "A11"  !CDS_PN = "A11";
"SSTXN1":   PN = "A3"  !CDS_PN = "A3";
"SSTXN2":   PN = "B3"  !CDS_PN = "B3";
"SSTXP1":   PN = "A2"  !CDS_PN = "A2";
"SSTXP2":   PN = "B2"  !CDS_PN = "B2";
"VBUS<0>":   PN = "A4"  !CDS_PN = "A4";
"VBUS<1>":   PN = "A9"  !CDS_PN = "A9";
"VBUS<2>":   PN = "B4"  !CDS_PN = "B4";
"VBUS<3>":   PN = "B9"  !CDS_PN = "B9";
BODY = "SC22U16V5MX-4-GP","I35": #LOCATION = "C30W3" !CDS_LOCATION = "C30W3" #SEC = "1" !CDS_SEC = "1";
"1":   PN = "1"  !CDS_PN = "1";
"2":   PN = "2"  !CDS_PN = "2";
BODY = "SC22U16V5MX-4-GP","I36": #LOCATION = "C30W4" !CDS_LOCATION = "C30W4" #SEC = "1" !CDS_SEC = "1";
"1":   PN = "1"  !CDS_PN = "1";
"2":   PN = "2"  !CDS_PN = "2";
BODY = "SC22U16V5MX-4-GP","I37": #LOCATION = "C30W6" !CDS_LOCATION = "C30W6" #SEC = "1" !CDS_SEC = "1";
"1":   PN = "1"  !CDS_PN = "1";
"2":   PN = "2"  !CDS_PN = "2";
BODY = "SC22U16V5MX-4-GP","I38": #LOCATION = "C30W5" !CDS_LOCATION = "C30W5" #SEC = "1" !CDS_SEC = "1";
"1":   PN = "1"  !CDS_PN = "1";
"2":   PN = "2"  !CDS_PN = "2";
BODY = "SC22U16V5MX-4-GP","I40": #LOCATION = "C30W9" !CDS_LOCATION = "C30W9" #SEC = "1" !CDS_SEC = "1";
"1":   PN = "1"  !CDS_PN = "1";
"2":   PN = "2"  !CDS_PN = "2";
BODY = "SC22U16V5MX-4-GP","I41": #LOCATION = "C30W8" !CDS_LOCATION = "C30W8" #SEC = "1" !CDS_SEC = "1";
"1":   PN = "1"  !CDS_PN = "1";
"2":   PN = "2"  !CDS_PN = "2";
BODY = "SC22U16V5MX-4-GP","I42": #LOCATION = "C30W7" !CDS_LOCATION = "C30W7" #SEC = "1" !CDS_SEC = "1";
"1":   PN = "1"  !CDS_PN = "1";
"2":   PN = "2"  !CDS_PN = "2";
BODY = "POLYSW-1D1A6V-2-GP-U","I44": #LOCATION = "F30W1" !CDS_LOCATION = "F30W1" #SEC = "1" !CDS_SEC = "1";
"1":   PN = "1"  !CDS_PN = "1";
"2":   PN = "2"  !CDS_PN = "2";
DRAWING = "@baseboard_fab2_lib.baseboard_fab2(sch_1):page183";
BODY = "RES","I3": #LOCATION = "R9F55" !CDS_LOCATION = "R9F55" #SEC = "1" !CDS_SEC = "1";
"A":   PN = "1"  !CDS_PN = "1";
"B":   PN = "2"  !CDS_PN = "2";
DRAWING = "@baseboard_fab2_lib.baseboard_fab2(sch_1):page215";
BODY = "RES","I12": #LOCATION = "R7G9" !CDS_LOCATION = "R7G9" #SEC = "1" !CDS_SEC = "1";
"A":   PN = "1"  !CDS_PN = "1";
"B":   PN = "2"  !CDS_PN = "2";
BODY = "RES","I13": #LOCATION = "R7F21" !CDS_LOCATION = "R7F21" #SEC = "1" !CDS_SEC = "1";
"A":   PN = "1"  !CDS_PN = "1";
"B":   PN = "2"  !CDS_PN = "2";
BODY = "CAP","I14": #LOCATION = "C7G4" !CDS_LOCATION = "C7G4" #SEC = "1" !CDS_SEC = "1";
"A":   PN = "1"  !CDS_PN = "1";
"B":   PN = "2"  !CDS_PN = "2";
BODY = "RES","I15": #LOCATION = "RF15" !CDS_LOCATION = "RF15" #SEC = "1" !CDS_SEC = "1";
"A":   PN = "1"  !CDS_PN = "1";
"B":   PN = "2"  !CDS_PN = "2";
BODY = "SC22P50V2JN-4GP","I16": #LOCATION = "CF15" !CDS_LOCATION = "CF15" &SEC = "1" #&CDS_SEC = "1";
"1":   PN = "1"  !CDS_PN = "1";
"2":   PN = "2"  !CDS_PN = "2";
BODY = "CAP","I22": #LOCATION = "C7G3" !CDS_LOCATION = "C7G3" #SEC = "1" !CDS_SEC = "1";
"A":   PN = "1"  !CDS_PN = "1";
"B":   PN = "2"  !CDS_PN = "2";
BODY = "SC22P50V2JN-4GP","I26": #LOCATION = "CF16" !CDS_LOCATION = "CF16" &SEC = "1" #&CDS_SEC = "1";
"1":   PN = "1"  !CDS_PN = "1";
"2":   PN = "2"  !CDS_PN = "2";
BODY = "RES","I27": #LOCATION = "RF16" !CDS_LOCATION = "RF16" #SEC = "1" !CDS_SEC = "1";
"A":   PN = "1"  !CDS_PN = "1";
"B":   PN = "2"  !CDS_PN = "2";
BODY = "RES","I28": #LOCATION = "R7G24" !CDS_LOCATION = "R7G24" #SEC = "1" !CDS_SEC = "1";
"A":   PN = "1"  !CDS_PN = "1";
"B":   PN = "2"  !CDS_PN = "2";
BODY = "RES","I29": #LOCATION = "R7F20" !CDS_LOCATION = "R7F20" #SEC = "1" !CDS_SEC = "1";
"A":   PN = "1"  !CDS_PN = "1";
"B":   PN = "2"  !CDS_PN = "2";
BODY = "RES","I33": #LOCATION = "R3T13" !CDS_LOCATION = "R3T13" #SEC = "1" !CDS_SEC = "1";
"A":   PN = "1"  !CDS_PN = "1";
"B":   PN = "2"  !CDS_PN = "2";
BODY = "CAP_A","I34": #LOCATION = "C7F17" !CDS_LOCATION = "C7F17" #SEC = "1" !CDS_SEC = "1";
"A":   PN = "1"  !CDS_PN = "1";
"B":   PN = "2"  !CDS_PN = "2";
BODY = "CAP_A","I35": #LOCATION = "C7F18" !CDS_LOCATION = "C7F18" #SEC = "1" !CDS_SEC = "1";
"A":   PN = "1"  !CDS_PN = "1";
"B":   PN = "2"  !CDS_PN = "2";
BODY = "CAP_A","I38": #LOCATION = "C7F15" !CDS_LOCATION = "C7F15" #SEC = "1" !CDS_SEC = "1";
"A":   PN = "1"  !CDS_PN = "1";
"B":   PN = "2"  !CDS_PN = "2";
BODY = "CAP_A","I40": #LOCATION = "C7F16" !CDS_LOCATION = "C7F16" #SEC = "1" !CDS_SEC = "1";
"A":   PN = "1"  !CDS_PN = "1";
"B":   PN = "2"  !CDS_PN = "2";
BODY = "RES","I41": #LOCATION = "R7G2" !CDS_LOCATION = "R7G2" #SEC = "1" !CDS_SEC = "1";
"A":   PN = "1"  !CDS_PN = "1";
"B":   PN = "2"  !CDS_PN = "2";
BODY = "CAP","I44": #LOCATION = "C7F14" !CDS_LOCATION = "C7F14" #SEC = "1" !CDS_SEC = "1";
"A":   PN = "1"  !CDS_PN = "1";
"B":   PN = "2"  !CDS_PN = "2";
BODY = "RES","I45": #LOCATION = "R12W26" !CDS_LOCATION = "R12W26" #SEC = "1" !CDS_SEC = "1";
"A":   PN = "1"  !CDS_PN = "1";
"B":   PN = "2"  !CDS_PN = "2";
BODY = "RES","I49": #LOCATION = "R7G4" !CDS_LOCATION = "R7G4" #SEC = "1" !CDS_SEC = "1";
"A":   PN = "1"  !CDS_PN = "1";
"B":   PN = "2"  !CDS_PN = "2";
BODY = "RES","I50": #LOCATION = "R7F27" !CDS_LOCATION = "R7F27" #SEC = "1" !CDS_SEC = "1";
"A":   PN = "1"  !CDS_PN = "1";
"B":   PN = "2"  !CDS_PN = "2";
BODY = "RES","I51": #LOCATION = "R7F22" !CDS_LOCATION = "R7F22" #SEC = "1" !CDS_SEC = "1";
"A":   PN = "1"  !CDS_PN = "1";
"B":   PN = "2"  !CDS_PN = "2";
BODY = "RES","I53": #LOCATION = "R7F23" !CDS_LOCATION = "R7F23" #SEC = "1" !CDS_SEC = "1";
"A":   PN = "1"  !CDS_PN = "1";
"B":   PN = "2"  !CDS_PN = "2";
BODY = "RES","I54": #LOCATION = "R12W27" !CDS_LOCATION = "R12W27" #SEC = "1" !CDS_SEC = "1";
"A":   PN = "1"  !CDS_PN = "1";
"B":   PN = "2"  !CDS_PN = "2";
BODY = "RES","I56": #LOCATION = "R7F24" !CDS_LOCATION = "R7F24" #SEC = "1" !CDS_SEC = "1";
"A":   PN = "1"  !CDS_PN = "1";
"B":   PN = "2"  !CDS_PN = "2";
BODY = "RES","I58": #LOCATION = "R3U2" !CDS_LOCATION = "R3U2" #SEC = "1" !CDS_SEC = "1";
"A":   PN = "1"  !CDS_PN = "1";
"B":   PN = "2"  !CDS_PN = "2";
BODY = "PXM1310B","I69": #LOCATION = "EU7G1" !CDS_LOCATION = "EU7G1" &SEC = "1" #&CDS_SEC = "1";
"AIREF1":   PN = "21"  !CDS_PN = "21";
"AIREF2":   PN = "23"  !CDS_PN = "23";
"AIREF3":   PN = "25"  !CDS_PN = "25";
"AISEN1":   PN = "22"  !CDS_PN = "22";
"AISEN2":   PN = "24"  !CDS_PN = "24";
"AISEN3":   PN = "26"  !CDS_PN = "26";
"APWM1":   PN = "5"  !CDS_PN = "5";
"APWM2":   PN = "4"  !CDS_PN = "4";
"APWM3":   PN = "3"  !CDS_PN = "3";
"ATSEN":   PN = "35"  !CDS_PN = "35";
"AVREF":   PN = "20"  !CDS_PN = "20";
"AVREN":   PN = "10"  !CDS_PN = "10";
"AVRRDY":   PN = "9"  !CDS_PN = "9";
"AVSEN":   PN = "19"  !CDS_PN = "19";
"BIREF1":   PN = "31"  !CDS_PN = "31";
"BISEN1":   PN = "32"  !CDS_PN = "32";
"BPWM1":   PN = "1"  !CDS_PN = "1";
"BTSEN":   PN = "34"  !CDS_PN = "34";
"BVREF":   PN = "30"  !CDS_PN = "30";
"BVSEN":   PN = "29"  !CDS_PN = "29";
"DNC<0>":   PN = "2"  !CDS_PN = "2";
"DNC<1>":   PN = "28"  !CDS_PN = "28";
"GND":   PN = "27"  !CDS_PN = "27";
"IINSEN":   PN = "38"  !CDS_PN = "38";
"MP0":   PN = "13"  !CDS_PN = "13";
"MP1":   PN = "14"  !CDS_PN = "14";
"MP2":   PN = "18"  !CDS_PN = "18";
"PINALRT_N":   PN = "12"  !CDS_PN = "12";
"RESET_N":   PN = "8"  !CDS_PN = "8";
"SCL":   PN = "7"  !CDS_PN = "7";
"SDA":   PN = "6"  !CDS_PN = "6";
"THPAD":   PN = "41"  !CDS_PN = "41";
"VALRT_N":   PN = "17"  !CDS_PN = "17";
"VCLK":   PN = "15"  !CDS_PN = "15";
"VD12":   PN = "40"  !CDS_PN = "40";
"VDD":   PN = "39"  !CDS_PN = "39";
"VDIO":   PN = "16"  !CDS_PN = "16";
"VINSEN":   PN = "37"  !CDS_PN = "37";
"VRHOT_N":   PN = "11"  !CDS_PN = "11";
"XADDR1":   PN = "36"  !CDS_PN = "36";
"XADDR2":   PN = "33"  !CDS_PN = "33";
BODY = "RES","I70": #LOCATION = "R3T11" !CDS_LOCATION = "R3T11" #SEC = "1" !CDS_SEC = "1";
"A":   PN = "1"  !CDS_PN = "1";
"B":   PN = "2"  !CDS_PN = "2";
BODY = "RES","I72": #LOCATION = "R7G8" !CDS_LOCATION = "R7G8" #SEC = "1" !CDS_SEC = "1";
"A":   PN = "1"  !CDS_PN = "1";
"B":   PN = "2"  !CDS_PN = "2";
BODY = "RES","I73": #LOCATION = "R7G10" !CDS_LOCATION = "R7G10" #SEC = "1" !CDS_SEC = "1";
"A":   PN = "1"  !CDS_PN = "1";
"B":   PN = "2"  !CDS_PN = "2";
BODY = "RES","I74": #LOCATION = "R12W25" !CDS_LOCATION = "R12W25" #SEC = "1" !CDS_SEC = "1";
"A":   PN = "1"  !CDS_PN = "1";
"B":   PN = "2"  !CDS_PN = "2";
BODY = "RES","I75": #LOCATION = "R7F36" !CDS_LOCATION = "R7F36" #SEC = "1" !CDS_SEC = "1";
"A":   PN = "1"  !CDS_PN = "1";
"B":   PN = "2"  !CDS_PN = "2";
DRAWING = "@baseboard_fab2_lib.baseboard_fab2(sch_1):page197";
BODY = "CAP","I1": #LOCATION = "C12W2" !CDS_LOCATION = "C12W2" #SEC = "1" !CDS_SEC = "1";
"A":   PN = "1"  !CDS_PN = "1";
"B":   PN = "2"  !CDS_PN = "2";
BODY = "RES","I6": #LOCATION = "R4B12" !CDS_LOCATION = "R4B12" #SEC = "1" !CDS_SEC = "1";
"A":   PN = "1"  !CDS_PN = "1";
"B":   PN = "2"  !CDS_PN = "2";
BODY = "CAP","I8": #LOCATION = "C12W1" !CDS_LOCATION = "C12W1" #SEC = "1" !CDS_SEC = "1";
"A":   PN = "1"  !CDS_PN = "1";
"B":   PN = "2"  !CDS_PN = "2";
BODY = "RES","I14": #LOCATION = "R4F2" !CDS_LOCATION = "R4F2" #SEC = "1" !CDS_SEC = "1";
"A":   PN = "1"  !CDS_PN = "1";
"B":   PN = "2"  !CDS_PN = "2";
BODY = "CAP","I18": #LOCATION = "C12W4" !CDS_LOCATION = "C12W4" #SEC = "1" !CDS_SEC = "1";
"A":   PN = "1"  !CDS_PN = "1";
"B":   PN = "2"  !CDS_PN = "2";
BODY = "BSL308C-H6327-GP","I19": #LOCATION = "Q12W2" !CDS_LOCATION = "Q12W2" #SEC = "1" !CDS_SEC = "1";
"DRAIN#4":   PN = "4"  !CDS_PN = "4";
"DRAIN#6":   PN = "6"  !CDS_PN = "6";
"GATE#1":   PN = "1"  !CDS_PN = "1";
"GATE#3":   PN = "3"  !CDS_PN = "3";
"SOURCE#2":   PN = "2"  !CDS_PN = "2";
"SOURCE#5":   PN = "5"  !CDS_PN = "5";
BODY = "RES","I21": #LOCATION = "R12W9" !CDS_LOCATION = "R12W9" #SEC = "1" !CDS_SEC = "1";
"A":   PN = "1"  !CDS_PN = "1";
"B":   PN = "2"  !CDS_PN = "2";
BODY = "RES","I29": #LOCATION = "R9M4" !CDS_LOCATION = "R9M4" #SEC = "1" !CDS_SEC = "1";
"A":   PN = "1"  !CDS_PN = "1";
"B":   PN = "2"  !CDS_PN = "2";
BODY = "BSL308C-H6327-GP","I35": #LOCATION = "Q12W4" !CDS_LOCATION = "Q12W4" #SEC = "1" !CDS_SEC = "1";
"DRAIN#4":   PN = "4"  !CDS_PN = "4";
"DRAIN#6":   PN = "6"  !CDS_PN = "6";
"GATE#1":   PN = "1"  !CDS_PN = "1";
"GATE#3":   PN = "3"  !CDS_PN = "3";
"SOURCE#2":   PN = "2"  !CDS_PN = "2";
"SOURCE#5":   PN = "5"  !CDS_PN = "5";
BODY = "RES","I37": #LOCATION = "R12W19" !CDS_LOCATION = "R12W19" #SEC = "1" !CDS_SEC = "1";
"A":   PN = "1"  !CDS_PN = "1";
"B":   PN = "2"  !CDS_PN = "2";
BODY = "CAP","I42": #LOCATION = "C12W3" !CDS_LOCATION = "C12W3" #SEC = "1" !CDS_SEC = "1";
"A":   PN = "1"  !CDS_PN = "1";
"B":   PN = "2"  !CDS_PN = "2";
BODY = "BSL308C-H6327-GP","I43": #LOCATION = "Q12W1" !CDS_LOCATION = "Q12W1" #SEC = "1" !CDS_SEC = "1";
"DRAIN#4":   PN = "4"  !CDS_PN = "4";
"DRAIN#6":   PN = "6"  !CDS_PN = "6";
"GATE#1":   PN = "1"  !CDS_PN = "1";
"GATE#3":   PN = "3"  !CDS_PN = "3";
"SOURCE#2":   PN = "2"  !CDS_PN = "2";
"SOURCE#5":   PN = "5"  !CDS_PN = "5";
BODY = "RES","I45": #LOCATION = "R12W4" !CDS_LOCATION = "R12W4" #SEC = "1" !CDS_SEC = "1";
"A":   PN = "1"  !CDS_PN = "1";
"B":   PN = "2"  !CDS_PN = "2";
BODY = "RES","I50": #LOCATION = "R1F3" !CDS_LOCATION = "R1F3" #SEC = "1" !CDS_SEC = "1";
"A":   PN = "1"  !CDS_PN = "1";
"B":   PN = "2"  !CDS_PN = "2";
BODY = "RES","I53": #LOCATION = "R12W14" !CDS_LOCATION = "R12W14" #SEC = "1" !CDS_SEC = "1";
"A":   PN = "1"  !CDS_PN = "1";
"B":   PN = "2"  !CDS_PN = "2";
BODY = "CAP","I56": #LOCATION = "C9T8" !CDS_LOCATION = "C9T8" &SEC = "1" #&CDS_SEC = "1";
"A":   PN = "1"  !CDS_PN = "1";
"B":   PN = "2"  !CDS_PN = "2";
BODY = "CAP","I60": #LOCATION = "C1A4" !CDS_LOCATION = "C1A4" &SEC = "1" #&CDS_SEC = "1";
"A":   PN = "1"  !CDS_PN = "1";
"B":   PN = "2"  !CDS_PN = "2";
BODY = "CAP","I63": #LOCATION = "C9U11" !CDS_LOCATION = "C9U11" &SEC = "1" #&CDS_SEC = "1";
"A":   PN = "1"  !CDS_PN = "1";
"B":   PN = "2"  !CDS_PN = "2";
BODY = "CAP","I66": #LOCATION = "C9U8" !CDS_LOCATION = "C9U8" &SEC = "1" #&CDS_SEC = "1";
"A":   PN = "1"  !CDS_PN = "1";
"B":   PN = "2"  !CDS_PN = "2";
BODY = "CAP","I69": #LOCATION = "C6U18" !CDS_LOCATION = "C6U18" &SEC = "1" #&CDS_SEC = "1";
"A":   PN = "1"  !CDS_PN = "1";
"B":   PN = "2"  !CDS_PN = "2";
BODY = "CAP","I71": #LOCATION = "C6T2" !CDS_LOCATION = "C6T2" &SEC = "1" #&CDS_SEC = "1";
"A":   PN = "1"  !CDS_PN = "1";
"B":   PN = "2"  !CDS_PN = "2";
BODY = "CAP","I72": #LOCATION = "C1B7" !CDS_LOCATION = "C1B7" &SEC = "1" #&CDS_SEC = "1";
"A":   PN = "1"  !CDS_PN = "1";
"B":   PN = "2"  !CDS_PN = "2";
BODY = "CAP","I75": #LOCATION = "C1A16" !CDS_LOCATION = "C1A16" &SEC = "1" #&CDS_SEC = "1";
"A":   PN = "1"  !CDS_PN = "1";
"B":   PN = "2"  !CDS_PN = "2";
BODY = "CAP","I78": #LOCATION = "C4B11" !CDS_LOCATION = "C4B11" &SEC = "1" #&CDS_SEC = "1";
"A":   PN = "1"  !CDS_PN = "1";
"B":   PN = "2"  !CDS_PN = "2";
BODY = "CAP","I81": #LOCATION = "C4A4" !CDS_LOCATION = "C4A4" &SEC = "1" #&CDS_SEC = "1";
"A":   PN = "1"  !CDS_PN = "1";
"B":   PN = "2"  !CDS_PN = "2";
BODY = "CAP","I84": #LOCATION = "C6U10" !CDS_LOCATION = "C6U10" &SEC = "1" #&CDS_SEC = "1";
"A":   PN = "1"  !CDS_PN = "1";
"B":   PN = "2"  !CDS_PN = "2";
BODY = "CAP","I88": #LOCATION = "C4A17" !CDS_LOCATION = "C4A17" &SEC = "1" #&CDS_SEC = "1";
"A":   PN = "1"  !CDS_PN = "1";
"B":   PN = "2"  !CDS_PN = "2";
BODY = "BSL308C-H6327-GP","I91": #LOCATION = "Q12W3" !CDS_LOCATION = "Q12W3" #SEC = "1" !CDS_SEC = "1";
"DRAIN#4":   PN = "4"  !CDS_PN = "4";
"DRAIN#6":   PN = "6"  !CDS_PN = "6";
"GATE#1":   PN = "1"  !CDS_PN = "1";
"GATE#3":   PN = "3"  !CDS_PN = "3";
"SOURCE#2":   PN = "2"  !CDS_PN = "2";
"SOURCE#5":   PN = "5"  !CDS_PN = "5";
BODY = "665KR5B-1-GP","I101": #LOCATION = "R12W1" !CDS_LOCATION = "R12W1" &SEC = "1" #&CDS_SEC = "1";
"1":   PN = "1"  !CDS_PN = "1";
"2":   PN = "2"  !CDS_PN = "2";
BODY = "665KR2B-GP","I109": #LOCATION = "R12W10" !CDS_LOCATION = "R12W10" #SEC = "1" !CDS_SEC = "1";
"1":   PN = "1"  !CDS_PN = "1";
"2":   PN = "2"  !CDS_PN = "2";
BODY = "665KR2B-GP","I110": #LOCATION = "R12W20" !CDS_LOCATION = "R12W20" #SEC = "1" !CDS_SEC = "1";
"1":   PN = "1"  !CDS_PN = "1";
"2":   PN = "2"  !CDS_PN = "2";
BODY = "665KR2B-GP","I111": #LOCATION = "R12W5" !CDS_LOCATION = "R12W5" #SEC = "1" !CDS_SEC = "1";
"1":   PN = "1"  !CDS_PN = "1";
"2":   PN = "2"  !CDS_PN = "2";
BODY = "665KR2B-GP","I112": #LOCATION = "R12W15" !CDS_LOCATION = "R12W15" #SEC = "1" !CDS_SEC = "1";
"1":   PN = "1"  !CDS_PN = "1";
"2":   PN = "2"  !CDS_PN = "2";
BODY = "4D02R2F-GP","I113": #LOCATION = "R12W8" !CDS_LOCATION = "R12W8" #SEC = "1" !CDS_SEC = "1";
"1":   PN = "1"  !CDS_PN = "1";
"2":   PN = "2"  !CDS_PN = "2";
BODY = "4D02R2F-GP","I114": #LOCATION = "R12W18" !CDS_LOCATION = "R12W18" #SEC = "1" !CDS_SEC = "1";
"1":   PN = "1"  !CDS_PN = "1";
"2":   PN = "2"  !CDS_PN = "2";
BODY = "4D02R2F-GP","I115": #LOCATION = "R12W3" !CDS_LOCATION = "R12W3" #SEC = "1" !CDS_SEC = "1";
"1":   PN = "1"  !CDS_PN = "1";
"2":   PN = "2"  !CDS_PN = "2";
BODY = "4D02R2F-GP","I116": #LOCATION = "R12W13" !CDS_LOCATION = "R12W13" #SEC = "1" !CDS_SEC = "1";
"1":   PN = "1"  !CDS_PN = "1";
"2":   PN = "2"  !CDS_PN = "2";
BODY = "665KR5B-1-GP","I117": #LOCATION = "R12W2" !CDS_LOCATION = "R12W2" &SEC = "1" #&CDS_SEC = "1";
"1":   PN = "1"  !CDS_PN = "1";
"2":   PN = "2"  !CDS_PN = "2";
BODY = "665KR5B-1-GP","I118": #LOCATION = "R12W11" !CDS_LOCATION = "R12W11" &SEC = "1" #&CDS_SEC = "1";
"1":   PN = "1"  !CDS_PN = "1";
"2":   PN = "2"  !CDS_PN = "2";
BODY = "665KR5B-1-GP","I119": #LOCATION = "R12W12" !CDS_LOCATION = "R12W12" &SEC = "1" #&CDS_SEC = "1";
"1":   PN = "1"  !CDS_PN = "1";
"2":   PN = "2"  !CDS_PN = "2";
BODY = "665KR5B-1-GP","I120": #LOCATION = "R12W6" !CDS_LOCATION = "R12W6" &SEC = "1" #&CDS_SEC = "1";
"1":   PN = "1"  !CDS_PN = "1";
"2":   PN = "2"  !CDS_PN = "2";
BODY = "665KR5B-1-GP","I121": #LOCATION = "R12W7" !CDS_LOCATION = "R12W7" &SEC = "1" #&CDS_SEC = "1";
"1":   PN = "1"  !CDS_PN = "1";
"2":   PN = "2"  !CDS_PN = "2";
BODY = "665KR5B-1-GP","I122": #LOCATION = "R12W16" !CDS_LOCATION = "R12W16" &SEC = "1" #&CDS_SEC = "1";
"1":   PN = "1"  !CDS_PN = "1";
"2":   PN = "2"  !CDS_PN = "2";
BODY = "665KR5B-1-GP","I123": #LOCATION = "R12W17" !CDS_LOCATION = "R12W17" &SEC = "1" #&CDS_SEC = "1";
"1":   PN = "1"  !CDS_PN = "1";
"2":   PN = "2"  !CDS_PN = "2";
DRAWING = "@baseboard_fab2_lib.baseboard_fab2(sch_1):page230";
BODY = "CAP","I2": #LOCATION = "C4A6" !CDS_LOCATION = "C4A6" #SEC = "1" !CDS_SEC = "1";
"A":   PN = "1"  !CDS_PN = "1";
"B":   PN = "2"  !CDS_PN = "2";
BODY = "RES","I4": #LOCATION = "R4A3" !CDS_LOCATION = "R4A3" #SEC = "1" !CDS_SEC = "1";
"A":   PN = "1"  !CDS_PN = "1";
"B":   PN = "2"  !CDS_PN = "2";
BODY = "RES","I5": #LOCATION = "R6L5" !CDS_LOCATION = "R6L5" #SEC = "1" !CDS_SEC = "1";
"A":   PN = "1"  !CDS_PN = "1";
"B":   PN = "2"  !CDS_PN = "2";
BODY = "RES","I6": #LOCATION = "R6L6" !CDS_LOCATION = "R6L6" #SEC = "1" !CDS_SEC = "1";
"A":   PN = "1"  !CDS_PN = "1";
"B":   PN = "2"  !CDS_PN = "2";
BODY = "CAP","I10": #LOCATION = "C4A7" !CDS_LOCATION = "C4A7" #SEC = "1" !CDS_SEC = "1";
"A":   PN = "1"  !CDS_PN = "1";
"B":   PN = "2"  !CDS_PN = "2";
BODY = "CAP","I12": #LOCATION = "C4A8" !CDS_LOCATION = "C4A8" #SEC = "1" !CDS_SEC = "1";
"A":   PN = "1"  !CDS_PN = "1";
"B":   PN = "2"  !CDS_PN = "2";
BODY = "RES","I13": #LOCATION = "R6L8" !CDS_LOCATION = "R6L8" #SEC = "1" !CDS_SEC = "1";
"A":   PN = "1"  !CDS_PN = "1";
"B":   PN = "2"  !CDS_PN = "2";
BODY = "CAP","I20": #LOCATION = "C4A13" !CDS_LOCATION = "C4A13" #SEC = "1" !CDS_SEC = "1";
"A":   PN = "1"  !CDS_PN = "1";
"B":   PN = "2"  !CDS_PN = "2";
BODY = "CAP","I23": #LOCATION = "C4A3" !CDS_LOCATION = "C4A3" #SEC = "1" !CDS_SEC = "1";
"A":   PN = "1"  !CDS_PN = "1";
"B":   PN = "2"  !CDS_PN = "2";
BODY = "CAP_A","I24": #LOCATION = "C8M12" !CDS_LOCATION = "C8M12" #SEC = "1" !CDS_SEC = "1";
"A":   PN = "1"  !CDS_PN = "1";
"B":   PN = "2"  !CDS_PN = "2";
BODY = "RES","I32": #LOCATION = "R4A4" !CDS_LOCATION = "R4A4" #SEC = "1" !CDS_SEC = "1";
"A":   PN = "1"  !CDS_PN = "1";
"B":   PN = "2"  !CDS_PN = "2";
BODY = "CAP","I35": #LOCATION = "C6L5" !CDS_LOCATION = "C6L5" #SEC = "1" !CDS_SEC = "1";
"A":   PN = "1"  !CDS_PN = "1";
"B":   PN = "2"  !CDS_PN = "2";
BODY = "CAP","I36": #LOCATION = "C4A14" !CDS_LOCATION = "C4A14" #SEC = "1" !CDS_SEC = "1";
"A":   PN = "1"  !CDS_PN = "1";
"B":   PN = "2"  !CDS_PN = "2";
BODY = "CAP","I17": #LOCATION = "C4A15" !CDS_LOCATION = "C4A15" #SEC = "1" !CDS_SEC = "1";
"A":   PN = "1"  !CDS_PN = "1";
"B":   PN = "2"  !CDS_PN = "2";
BODY = "RES","I21": #LOCATION = "R4A5" !CDS_LOCATION = "R4A5" #SEC = "1" !CDS_SEC = "1";
"A":   PN = "1"  !CDS_PN = "1";
"B":   PN = "2"  !CDS_PN = "2";
BODY = "SHUNT","I30": #LOCATION = "SH8L1" !CDS_LOCATION = "SH8L1" #SEC = "1" !CDS_SEC = "1";
"A":   PN = "1"  !CDS_PN = "1";
"B":   PN = "2"  !CDS_PN = "2";
BODY = "MIC5166","I37": #LOCATION = "EU4A2" !CDS_LOCATION = "EU4A2" #SEC = "1" !CDS_SEC = "1";
"AGND":   PN = "3"  !CDS_PN = "3";
"BIAS":   PN = "2"  !CDS_PN = "2";
"EN":   PN = "7"  !CDS_PN = "7";
"PG":   PN = "5"  !CDS_PN = "5";
"PGND":   PN = "8"  !CDS_PN = "8";
"SNS":   PN = "6"  !CDS_PN = "6";
"THPAD":   PN = "11"  !CDS_PN = "11";
"VDDQ":   PN = "4"  !CDS_PN = "4";
"VIN":   PN = "10"  !CDS_PN = "10";
"VREF":   PN = "1"  !CDS_PN = "1";
"VTT":   PN = "9"  !CDS_PN = "9";
BODY = "CAP","I41": #LOCATION = "C8L3" !CDS_LOCATION = "C8L3" #SEC = "1" !CDS_SEC = "1";
"A":   PN = "1"  !CDS_PN = "1";
"B":   PN = "2"  !CDS_PN = "2";
BODY = "CAP","I42": #LOCATION = "C8L4" !CDS_LOCATION = "C8L4" #SEC = "1" !CDS_SEC = "1";
"A":   PN = "1"  !CDS_PN = "1";
"B":   PN = "2"  !CDS_PN = "2";
BODY = "CAP","I43": #LOCATION = "C6W13" !CDS_LOCATION = "C6W13" #SEC = "1" !CDS_SEC = "1";
"A":   PN = "1"  !CDS_PN = "1";
"B":   PN = "2"  !CDS_PN = "2";
DRAWING = "@baseboard_fab2_lib.baseboard_fab2(sch_1):page181";
BODY = "RES","I4": #LOCATION = "R9T9" !CDS_LOCATION = "R9T9" #SEC = "1" !CDS_SEC = "1";
"A":   PN = "1"  !CDS_PN = "1";
"B":   PN = "2"  !CDS_PN = "2";
BODY = "DIODE","I5": #LOCATION = "CR1F4" !CDS_LOCATION = "CR1F4" #SEC = "1" !CDS_SEC = "1";
"A":   PN = "2"  !CDS_PN = "2";
"C":   PN = "1"  !CDS_PN = "1";
BODY = "RES","I22": #LOCATION = "R1F8" !CDS_LOCATION = "R1F8" #SEC = "1" !CDS_SEC = "1";
"A":   PN = "1"  !CDS_PN = "1";
"B":   PN = "2"  !CDS_PN = "2";
BODY = "RES","I26": #LOCATION = "R9T1" !CDS_LOCATION = "R9T1" #SEC = "1" !CDS_SEC = "1";
"A":   PN = "1"  !CDS_PN = "1";
"B":   PN = "2"  !CDS_PN = "2";
BODY = "RES","I27": #LOCATION = "R9R12" !CDS_LOCATION = "R9R12" #SEC = "1" !CDS_SEC = "1";
"A":   PN = "1"  !CDS_PN = "1";
"B":   PN = "2"  !CDS_PN = "2";
BODY = "RES","I28": #LOCATION = "R9F63" !CDS_LOCATION = "R9F63" #SEC = "1" !CDS_SEC = "1";
"A":   PN = "1"  !CDS_PN = "1";
"B":   PN = "2"  !CDS_PN = "2";
BODY = "RES","I29": #LOCATION = "R9F64" !CDS_LOCATION = "R9F64" #SEC = "1" !CDS_SEC = "1";
"A":   PN = "1"  !CDS_PN = "1";
"B":   PN = "2"  !CDS_PN = "2";
BODY = "RES","I30": #LOCATION = "R9F70" !CDS_LOCATION = "R9F70" #SEC = "1" !CDS_SEC = "1";
"A":   PN = "1"  !CDS_PN = "1";
"B":   PN = "2"  !CDS_PN = "2";
BODY = "RES","I31": #LOCATION = "R9R10" !CDS_LOCATION = "R9R10" #SEC = "1" !CDS_SEC = "1";
"A":   PN = "1"  !CDS_PN = "1";
"B":   PN = "2"  !CDS_PN = "2";
BODY = "RES","I32": #LOCATION = "R9R9" !CDS_LOCATION = "R9R9" #SEC = "1" !CDS_SEC = "1";
"A":   PN = "1"  !CDS_PN = "1";
"B":   PN = "2"  !CDS_PN = "2";
BODY = "RES","I33": #LOCATION = "R9F67" !CDS_LOCATION = "R9F67" &SEC = "1" #&CDS_SEC = "1";
"A":   PN = "1"  !CDS_PN = "1";
"B":   PN = "2"  !CDS_PN = "2";
BODY = "CAP_A","I34": #LOCATION = "C8E1" !CDS_LOCATION = "C8E1" #SEC = "1" !CDS_SEC = "1";
"A":   PN = "1"  !CDS_PN = "1";
"B":   PN = "2"  !CDS_PN = "2";
BODY = "DIODE","I37": #LOCATION = "CR1F3" !CDS_LOCATION = "CR1F3" #SEC = "1" !CDS_SEC = "1";
"A":   PN = "2"  !CDS_PN = "2";
"C":   PN = "1"  !CDS_PN = "1";
BODY = "CAP","I40": #LOCATION = "C2R6" !CDS_LOCATION = "C2R6" #SEC = "1" !CDS_SEC = "1";
"A":   PN = "1"  !CDS_PN = "1";
"B":   PN = "2"  !CDS_PN = "2";
BODY = "NPN","I42": #LOCATION = "Q9T1" !CDS_LOCATION = "Q9T1" #SEC = "1" !CDS_SEC = "1";
"B":   PN = "1"  !CDS_PN = "1";
"C":   PN = "3"  !CDS_PN = "3";
"E":   PN = "2"  !CDS_PN = "2";
BODY = "TTL08","I60": #LOCATION = "U8E1" !CDS_LOCATION = "U8E1" #SEC = "2" !CDS_SEC = "2";
"A<0>":   PN = "9"  !CDS_PN = "9";
"B<0>":   PN = "10"  !CDS_PN = "10";
"Y<0>":   PN = "8"  !CDS_PN = "8";
BODY = "RES","I63": #LOCATION = "R8E5" !CDS_LOCATION = "R8E5" #SEC = "1" !CDS_SEC = "1";
"A":   PN = "1"  !CDS_PN = "1";
"B":   PN = "2"  !CDS_PN = "2";
BODY = "RES","I64": #LOCATION = "R9T3" !CDS_LOCATION = "R9T3" #SEC = "1" !CDS_SEC = "1";
"A":   PN = "1"  !CDS_PN = "1";
"B":   PN = "2"  !CDS_PN = "2";
BODY = "RES","I68": #LOCATION = "R9T6" !CDS_LOCATION = "R9T6" #SEC = "1" !CDS_SEC = "1";
"A":   PN = "1"  !CDS_PN = "1";
"B":   PN = "2"  !CDS_PN = "2";
BODY = "CAP","I70": #LOCATION = "C1F14" !CDS_LOCATION = "C1F14" #SEC = "1" !CDS_SEC = "1";
"A":   PN = "1"  !CDS_PN = "1";
"B":   PN = "2"  !CDS_PN = "2";
BODY = "CAP","I71": #LOCATION = "C1F17" !CDS_LOCATION = "C1F17" #SEC = "1" !CDS_SEC = "1";
"A":   PN = "1"  !CDS_PN = "1";
"B":   PN = "2"  !CDS_PN = "2";
BODY = "CAP","I72": #LOCATION = "C1F18" !CDS_LOCATION = "C1F18" #SEC = "1" !CDS_SEC = "1";
"A":   PN = "1"  !CDS_PN = "1";
"B":   PN = "2"  !CDS_PN = "2";
BODY = "CAP","I73": #LOCATION = "C1F8" !CDS_LOCATION = "C1F8" #SEC = "1" !CDS_SEC = "1";
"A":   PN = "1"  !CDS_PN = "1";
"B":   PN = "2"  !CDS_PN = "2";
BODY = "CAP","I74": #LOCATION = "C1F11" !CDS_LOCATION = "C1F11" #SEC = "1" !CDS_SEC = "1";
"A":   PN = "1"  !CDS_PN = "1";
"B":   PN = "2"  !CDS_PN = "2";
BODY = "CAP","I75": #LOCATION = "C1F12" !CDS_LOCATION = "C1F12" #SEC = "1" !CDS_SEC = "1";
"A":   PN = "1"  !CDS_PN = "1";
"B":   PN = "2"  !CDS_PN = "2";
BODY = "CAP","I76": #LOCATION = "C1F3" !CDS_LOCATION = "C1F3" #SEC = "1" !CDS_SEC = "1";
"A":   PN = "1"  !CDS_PN = "1";
"B":   PN = "2"  !CDS_PN = "2";
BODY = "CAP","I77": #LOCATION = "C1F5" !CDS_LOCATION = "C1F5" #SEC = "1" !CDS_SEC = "1";
"A":   PN = "1"  !CDS_PN = "1";
"B":   PN = "2"  !CDS_PN = "2";
BODY = "CAP","I78": #LOCATION = "C1F15" !CDS_LOCATION = "C1F15" #SEC = "1" !CDS_SEC = "1";
"A":   PN = "1"  !CDS_PN = "1";
"B":   PN = "2"  !CDS_PN = "2";
BODY = "CAP","I79": #LOCATION = "C1F16" !CDS_LOCATION = "C1F16" #SEC = "1" !CDS_SEC = "1";
"A":   PN = "1"  !CDS_PN = "1";
"B":   PN = "2"  !CDS_PN = "2";
BODY = "RES","I80": #LOCATION = "R7D9" !CDS_LOCATION = "R7D9" #SEC = "1" !CDS_SEC = "1";
"A":   PN = "1"  !CDS_PN = "1";
"B":   PN = "2"  !CDS_PN = "2";
BODY = "RES","I81": #LOCATION = "R3P61" !CDS_LOCATION = "R3P61" #SEC = "1" !CDS_SEC = "1";
"A":   PN = "1"  !CDS_PN = "1";
"B":   PN = "2"  !CDS_PN = "2";
BODY = "RES","I82": #LOCATION = "R7D5" !CDS_LOCATION = "R7D5" #SEC = "1" !CDS_SEC = "1";
"A":   PN = "1"  !CDS_PN = "1";
"B":   PN = "2"  !CDS_PN = "2";
BODY = "CAP","I86": #LOCATION = "C1F20" !CDS_LOCATION = "C1F20" #SEC = "1" !CDS_SEC = "1";
"A":   PN = "1"  !CDS_PN = "1";
"B":   PN = "2"  !CDS_PN = "2";
BODY = "CAP","I87": #LOCATION = "C1F10" !CDS_LOCATION = "C1F10" #SEC = "1" !CDS_SEC = "1";
"A":   PN = "1"  !CDS_PN = "1";
"B":   PN = "2"  !CDS_PN = "2";
BODY = "CAP","I88": #LOCATION = "C1F6" !CDS_LOCATION = "C1F6" #SEC = "1" !CDS_SEC = "1";
"A":   PN = "1"  !CDS_PN = "1";
"B":   PN = "2"  !CDS_PN = "2";
BODY = "CAP","I89": #LOCATION = "C1F13" !CDS_LOCATION = "C1F13" #SEC = "1" !CDS_SEC = "1";
"A":   PN = "1"  !CDS_PN = "1";
"B":   PN = "2"  !CDS_PN = "2";
BODY = "CAP","I90": #LOCATION = "C1F2" !CDS_LOCATION = "C1F2" #SEC = "1" !CDS_SEC = "1";
"A":   PN = "1"  !CDS_PN = "1";
"B":   PN = "2"  !CDS_PN = "2";
BODY = "CAP","I91": #LOCATION = "C1F4" !CDS_LOCATION = "C1F4" #SEC = "1" !CDS_SEC = "1";
"A":   PN = "1"  !CDS_PN = "1";
"B":   PN = "2"  !CDS_PN = "2";
BODY = "CONN8_H62179001","I106": #LOCATION = "J1F3" !CDS_LOCATION = "J1F3" &SEC = "1" #&CDS_SEC = "1";
"IO1":   PN = "1"  !CDS_PN = "1";
"IO2":   PN = "2"  !CDS_PN = "2";
"IO3":   PN = "3"  !CDS_PN = "3";
"IO4":   PN = "4"  !CDS_PN = "4";
"IO5":   PN = "5"  !CDS_PN = "5";
"IO6":   PN = "6"  !CDS_PN = "6";
"IO7":   PN = "7"  !CDS_PN = "7";
"IO8":   PN = "8"  !CDS_PN = "8";
BODY = "DM-FCI-CONN76-8R-GP-U-01","I134": #LOCATION = "J1F1" !CDS_LOCATION = "J1F1" #SEC = "1" !CDS_SEC = "1";
"COM_RX":   PN = "H3"  !CDS_PN = "H3";
"COM_TX":   PN = "G3"  !CDS_PN = "G3";
"FAN_PWM0":   PN = "F4"  !CDS_PN = "F4";
"FAN_TACH0":   PN = "D4"  !CDS_PN = "D4";
"FAN_TACH1":   PN = "C4"  !CDS_PN = "C4";
"FAN_TACH2":   PN = "B4"  !CDS_PN = "B4";
"FAN_TACH3":   PN = "A4"  !CDS_PN = "A4";
"GND1":   PN = "A2"  !CDS_PN = "A2";
"GND2":   PN = "A8"  !CDS_PN = "A8";
"GND3":   PN = "C1"  !CDS_PN = "C1";
"GND4":   PN = "C3"  !CDS_PN = "C3";
"GND5":   PN = "C5"  !CDS_PN = "C5";
"GND6":   PN = "C7"  !CDS_PN = "C7";
"GND7":   PN = "D2"  !CDS_PN = "D2";
"GND8":   PN = "D6"  !CDS_PN = "D6";
"GND9":   PN = "D8"  !CDS_PN = "D8";
"GND10":   PN = "F1"  !CDS_PN = "F1";
"GND11":   PN = "F3"  !CDS_PN = "F3";
"GND12":   PN = "F7"  !CDS_PN = "F7";
"GND13":   PN = "G2"  !CDS_PN = "G2";
"GND14":   PN = "G4"  !CDS_PN = "G4";
"GND15":   PN = "G6"  !CDS_PN = "G6";
"GND16":   PN = "G8"  !CDS_PN = "G8";
"GND17":   PN = "I1"  !CDS_PN = "I1";
"GND18":   PN = "I7"  !CDS_PN = "I7";
"J2":   PN = "J2"  !CDS_PN = "J2";
"J4":   PN = "J4"  !CDS_PN = "J4";
"J6":   PN = "J6"  !CDS_PN = "J6";
"J8":   PN = "J8"  !CDS_PN = "J8";
"MATED_IN#":   PN = "E4"  !CDS_PN = "E4";
"MB_ON#":   PN = "I3"  !CDS_PN = "I3";
"MB_SLOT_ID0":   PN = "F5"  !CDS_PN = "F5";
"MB_SLOT_ID1":   PN = "G5"  !CDS_PN = "G5";
"MB_SLOT_ID2":   PN = "H5"  !CDS_PN = "H5";
"MNG_RX_DN":   PN = "E5"  !CDS_PN = "E5";
"MNG_RX_DP":   PN = "D5"  !CDS_PN = "D5";
"MNG_TX_DN":   PN = "B5"  !CDS_PN = "B5";
"MNG_TX_DP":   PN = "A5"  !CDS_PN = "A5";
"PCIE_CLK_100M_DN":   PN = "I4"  !CDS_PN = "I4";
"PCIE_CLK_100M_DP":   PN = "H4"  !CDS_PN = "H4";
"PCIE_PERST#":   PN = "I5"  !CDS_PN = "I5";
"PCIE_RX_DN0":   PN = "B1"  !CDS_PN = "B1";
"PCIE_RX_DN1":   PN = "E1"  !CDS_PN = "E1";
"PCIE_RX_DN2":   PN = "H1"  !CDS_PN = "H1";
"PCIE_RX_DN3":   PN = "C2"  !CDS_PN = "C2";
"PCIE_RX_DN4":   PN = "F2"  !CDS_PN = "F2";
"PCIE_RX_DN5":   PN = "I2"  !CDS_PN = "I2";
"PCIE_RX_DN6":   PN = "B3"  !CDS_PN = "B3";
"PCIE_RX_DN7":   PN = "E3"  !CDS_PN = "E3";
"PCIE_RX_DP0":   PN = "A1"  !CDS_PN = "A1";
"PCIE_RX_DP1":   PN = "D1"  !CDS_PN = "D1";
"PCIE_RX_DP2":   PN = "G1"  !CDS_PN = "G1";
"PCIE_RX_DP3":   PN = "B2"  !CDS_PN = "B2";
"PCIE_RX_DP4":   PN = "E2"  !CDS_PN = "E2";
"PCIE_RX_DP5":   PN = "H2"  !CDS_PN = "H2";
"PCIE_RX_DP6":   PN = "A3"  !CDS_PN = "A3";
"PCIE_RX_DP7":   PN = "D3"  !CDS_PN = "D3";
"PCIE_TX_DN0":   PN = "C8"  !CDS_PN = "C8";
"PCIE_TX_DN1":   PN = "F8"  !CDS_PN = "F8";
"PCIE_TX_DN2":   PN = "I8"  !CDS_PN = "I8";
"PCIE_TX_DN3":   PN = "B7"  !CDS_PN = "B7";
"PCIE_TX_DN4":   PN = "E7"  !CDS_PN = "E7";
"PCIE_TX_DN5":   PN = "H7"  !CDS_PN = "H7";
"PCIE_TX_DN6":   PN = "F6"  !CDS_PN = "F6";
"PCIE_TX_DN7":   PN = "I6"  !CDS_PN = "I6";
"PCIE_TX_DP0":   PN = "B8"  !CDS_PN = "B8";
"PCIE_TX_DP1":   PN = "E8"  !CDS_PN = "E8";
"PCIE_TX_DP2":   PN = "H8"  !CDS_PN = "H8";
"PCIE_TX_DP3":   PN = "A7"  !CDS_PN = "A7";
"PCIE_TX_DP4":   PN = "D7"  !CDS_PN = "D7";
"PCIE_TX_DP5":   PN = "G7"  !CDS_PN = "G7";
"PCIE_TX_DP6":   PN = "E6"  !CDS_PN = "E6";
"PCIE_TX_DP7":   PN = "H6"  !CDS_PN = "H6";
"PMBUS_ALERT#":   PN = "A6"  !CDS_PN = "A6";
"PMBUS_CLK":   PN = "C6"  !CDS_PN = "C6";
"PMBUS_DATA":   PN = "B6"  !CDS_PN = "B6";
BODY = "RES","I137": #LOCATION = "R9T8" !CDS_LOCATION = "R9T8" #SEC = "1" !CDS_SEC = "1";
"A":   PN = "1"  !CDS_PN = "1";
"B":   PN = "2"  !CDS_PN = "2";
DRAWING = "@baseboard_fab2_lib.baseboard_fab2(sch_1):page182";
BODY = "RES","I6": #LOCATION = "R1C31" !CDS_LOCATION = "R1C31" #SEC = "1" !CDS_SEC = "1";
"A":   PN = "1"  !CDS_PN = "1";
"B":   PN = "2"  !CDS_PN = "2";
BODY = "RES","I7": #LOCATION = "R1F9" !CDS_LOCATION = "R1F9" #SEC = "1" !CDS_SEC = "1";
"A":   PN = "1"  !CDS_PN = "1";
"B":   PN = "2"  !CDS_PN = "2";
BODY = "RES","I8": #LOCATION = "R1C9" !CDS_LOCATION = "R1C9" #SEC = "1" !CDS_SEC = "1";
"A":   PN = "1"  !CDS_PN = "1";
"B":   PN = "2"  !CDS_PN = "2";
BODY = "RES","I9": #LOCATION = "R1C10" !CDS_LOCATION = "R1C10" #SEC = "1" !CDS_SEC = "1";
"A":   PN = "1"  !CDS_PN = "1";
"B":   PN = "2"  !CDS_PN = "2";
BODY = "RES","I10": #LOCATION = "R1C11" !CDS_LOCATION = "R1C11" #SEC = "1" !CDS_SEC = "1";
"A":   PN = "1"  !CDS_PN = "1";
"B":   PN = "2"  !CDS_PN = "2";
BODY = "CAP","I36": #LOCATION = "C9N2" !CDS_LOCATION = "C9N2" #SEC = "1" !CDS_SEC = "1";
"A":   PN = "1"  !CDS_PN = "1";
"B":   PN = "2"  !CDS_PN = "2";
BODY = "CAP","I37": #LOCATION = "C9N12" !CDS_LOCATION = "C9N12" #SEC = "1" !CDS_SEC = "1";
"A":   PN = "1"  !CDS_PN = "1";
"B":   PN = "2"  !CDS_PN = "2";
BODY = "CAP","I38": #LOCATION = "C9N17" !CDS_LOCATION = "C9N17" #SEC = "1" !CDS_SEC = "1";
"A":   PN = "1"  !CDS_PN = "1";
"B":   PN = "2"  !CDS_PN = "2";
BODY = "CAP","I39": #LOCATION = "C9N18" !CDS_LOCATION = "C9N18" #SEC = "1" !CDS_SEC = "1";
"A":   PN = "1"  !CDS_PN = "1";
"B":   PN = "2"  !CDS_PN = "2";
BODY = "CAP","I40": #LOCATION = "C9N1" !CDS_LOCATION = "C9N1" #SEC = "1" !CDS_SEC = "1";
"A":   PN = "1"  !CDS_PN = "1";
"B":   PN = "2"  !CDS_PN = "2";
BODY = "CAP","I41": #LOCATION = "C9N15" !CDS_LOCATION = "C9N15" #SEC = "1" !CDS_SEC = "1";
"A":   PN = "1"  !CDS_PN = "1";
"B":   PN = "2"  !CDS_PN = "2";
BODY = "CAP","I42": #LOCATION = "C9N6" !CDS_LOCATION = "C9N6" #SEC = "1" !CDS_SEC = "1";
"A":   PN = "1"  !CDS_PN = "1";
"B":   PN = "2"  !CDS_PN = "2";
BODY = "CAP","I43": #LOCATION = "C9N14" !CDS_LOCATION = "C9N14" #SEC = "1" !CDS_SEC = "1";
"A":   PN = "1"  !CDS_PN = "1";
"B":   PN = "2"  !CDS_PN = "2";
BODY = "CAP","I44": #LOCATION = "C9N4" !CDS_LOCATION = "C9N4" #SEC = "1" !CDS_SEC = "1";
"A":   PN = "1"  !CDS_PN = "1";
"B":   PN = "2"  !CDS_PN = "2";
BODY = "CAP","I45": #LOCATION = "C9N5" !CDS_LOCATION = "C9N5" #SEC = "1" !CDS_SEC = "1";
"A":   PN = "1"  !CDS_PN = "1";
"B":   PN = "2"  !CDS_PN = "2";
BODY = "CAP","I46": #LOCATION = "C9N16" !CDS_LOCATION = "C9N16" #SEC = "1" !CDS_SEC = "1";
"A":   PN = "1"  !CDS_PN = "1";
"B":   PN = "2"  !CDS_PN = "2";
BODY = "CAP","I47": #LOCATION = "C9N3" !CDS_LOCATION = "C9N3" #SEC = "1" !CDS_SEC = "1";
"A":   PN = "1"  !CDS_PN = "1";
"B":   PN = "2"  !CDS_PN = "2";
BODY = "CAP","I48": #LOCATION = "C9N7" !CDS_LOCATION = "C9N7" #SEC = "1" !CDS_SEC = "1";
"A":   PN = "1"  !CDS_PN = "1";
"B":   PN = "2"  !CDS_PN = "2";
BODY = "CAP","I49": #LOCATION = "C9N10" !CDS_LOCATION = "C9N10" #SEC = "1" !CDS_SEC = "1";
"A":   PN = "1"  !CDS_PN = "1";
"B":   PN = "2"  !CDS_PN = "2";
BODY = "CAP","I52": #LOCATION = "C9N9" !CDS_LOCATION = "C9N9" #SEC = "1" !CDS_SEC = "1";
"A":   PN = "1"  !CDS_PN = "1";
"B":   PN = "2"  !CDS_PN = "2";
BODY = "CAP","I53": #LOCATION = "C9N8" !CDS_LOCATION = "C9N8" #SEC = "1" !CDS_SEC = "1";
"A":   PN = "1"  !CDS_PN = "1";
"B":   PN = "2"  !CDS_PN = "2";
BODY = "DM-FCI-CONN76-8R-GP-U-01","I79": #LOCATION = "J1C1" !CDS_LOCATION = "J1C1" #SEC = "1" !CDS_SEC = "1";
"COM_RX":   PN = "H3"  !CDS_PN = "H3";
"COM_TX":   PN = "G3"  !CDS_PN = "G3";
"FAN_PWM0":   PN = "F4"  !CDS_PN = "F4";
"FAN_TACH0":   PN = "D4"  !CDS_PN = "D4";
"FAN_TACH1":   PN = "C4"  !CDS_PN = "C4";
"FAN_TACH2":   PN = "B4"  !CDS_PN = "B4";
"FAN_TACH3":   PN = "A4"  !CDS_PN = "A4";
"GND1":   PN = "A2"  !CDS_PN = "A2";
"GND2":   PN = "A8"  !CDS_PN = "A8";
"GND3":   PN = "C1"  !CDS_PN = "C1";
"GND4":   PN = "C3"  !CDS_PN = "C3";
"GND5":   PN = "C5"  !CDS_PN = "C5";
"GND6":   PN = "C7"  !CDS_PN = "C7";
"GND7":   PN = "D2"  !CDS_PN = "D2";
"GND8":   PN = "D6"  !CDS_PN = "D6";
"GND9":   PN = "D8"  !CDS_PN = "D8";
"GND10":   PN = "F1"  !CDS_PN = "F1";
"GND11":   PN = "F3"  !CDS_PN = "F3";
"GND12":   PN = "F7"  !CDS_PN = "F7";
"GND13":   PN = "G2"  !CDS_PN = "G2";
"GND14":   PN = "G4"  !CDS_PN = "G4";
"GND15":   PN = "G6"  !CDS_PN = "G6";
"GND16":   PN = "G8"  !CDS_PN = "G8";
"GND17":   PN = "I1"  !CDS_PN = "I1";
"GND18":   PN = "I7"  !CDS_PN = "I7";
"J2":   PN = "J2"  !CDS_PN = "J2";
"J4":   PN = "J4"  !CDS_PN = "J4";
"J6":   PN = "J6"  !CDS_PN = "J6";
"J8":   PN = "J8"  !CDS_PN = "J8";
"MATED_IN#":   PN = "E4"  !CDS_PN = "E4";
"MB_ON#":   PN = "I3"  !CDS_PN = "I3";
"MB_SLOT_ID0":   PN = "F5"  !CDS_PN = "F5";
"MB_SLOT_ID1":   PN = "G5"  !CDS_PN = "G5";
"MB_SLOT_ID2":   PN = "H5"  !CDS_PN = "H5";
"MNG_RX_DN":   PN = "E5"  !CDS_PN = "E5";
"MNG_RX_DP":   PN = "D5"  !CDS_PN = "D5";
"MNG_TX_DN":   PN = "B5"  !CDS_PN = "B5";
"MNG_TX_DP":   PN = "A5"  !CDS_PN = "A5";
"PCIE_CLK_100M_DN":   PN = "I4"  !CDS_PN = "I4";
"PCIE_CLK_100M_DP":   PN = "H4"  !CDS_PN = "H4";
"PCIE_PERST#":   PN = "I5"  !CDS_PN = "I5";
"PCIE_RX_DN0":   PN = "B1"  !CDS_PN = "B1";
"PCIE_RX_DN1":   PN = "E1"  !CDS_PN = "E1";
"PCIE_RX_DN2":   PN = "H1"  !CDS_PN = "H1";
"PCIE_RX_DN3":   PN = "C2"  !CDS_PN = "C2";
"PCIE_RX_DN4":   PN = "F2"  !CDS_PN = "F2";
"PCIE_RX_DN5":   PN = "I2"  !CDS_PN = "I2";
"PCIE_RX_DN6":   PN = "B3"  !CDS_PN = "B3";
"PCIE_RX_DN7":   PN = "E3"  !CDS_PN = "E3";
"PCIE_RX_DP0":   PN = "A1"  !CDS_PN = "A1";
"PCIE_RX_DP1":   PN = "D1"  !CDS_PN = "D1";
"PCIE_RX_DP2":   PN = "G1"  !CDS_PN = "G1";
"PCIE_RX_DP3":   PN = "B2"  !CDS_PN = "B2";
"PCIE_RX_DP4":   PN = "E2"  !CDS_PN = "E2";
"PCIE_RX_DP5":   PN = "H2"  !CDS_PN = "H2";
"PCIE_RX_DP6":   PN = "A3"  !CDS_PN = "A3";
"PCIE_RX_DP7":   PN = "D3"  !CDS_PN = "D3";
"PCIE_TX_DN0":   PN = "C8"  !CDS_PN = "C8";
"PCIE_TX_DN1":   PN = "F8"  !CDS_PN = "F8";
"PCIE_TX_DN2":   PN = "I8"  !CDS_PN = "I8";
"PCIE_TX_DN3":   PN = "B7"  !CDS_PN = "B7";
"PCIE_TX_DN4":   PN = "E7"  !CDS_PN = "E7";
"PCIE_TX_DN5":   PN = "H7"  !CDS_PN = "H7";
"PCIE_TX_DN6":   PN = "F6"  !CDS_PN = "F6";
"PCIE_TX_DN7":   PN = "I6"  !CDS_PN = "I6";
"PCIE_TX_DP0":   PN = "B8"  !CDS_PN = "B8";
"PCIE_TX_DP1":   PN = "E8"  !CDS_PN = "E8";
"PCIE_TX_DP2":   PN = "H8"  !CDS_PN = "H8";
"PCIE_TX_DP3":   PN = "A7"  !CDS_PN = "A7";
"PCIE_TX_DP4":   PN = "D7"  !CDS_PN = "D7";
"PCIE_TX_DP5":   PN = "G7"  !CDS_PN = "G7";
"PCIE_TX_DP6":   PN = "E6"  !CDS_PN = "E6";
"PCIE_TX_DP7":   PN = "H6"  !CDS_PN = "H6";
"PMBUS_ALERT#":   PN = "A6"  !CDS_PN = "A6";
"PMBUS_CLK":   PN = "C6"  !CDS_PN = "C6";
"PMBUS_DATA":   PN = "B6"  !CDS_PN = "B6";
DRAWING = "@baseboard_fab2_lib.baseboard_fab2(sch_1):page269";
BODY = "RES","I4": #LOCATION = "R25W174" !CDS_LOCATION = "R25W174" #SEC = "1" !CDS_SEC = "1";
"A":   PN = "1"  !CDS_PN = "1";
"B":   PN = "2"  !CDS_PN = "2";
BODY = "RES","I10": #LOCATION = "R25W167" !CDS_LOCATION = "R25W167" &SEC = "1" #&CDS_SEC = "1";
"A":   PN = "1"  !CDS_PN = "1";
"B":   PN = "2"  !CDS_PN = "2";
BODY = "RES","I11": #LOCATION = "R25W168" !CDS_LOCATION = "R25W168" &SEC = "1" #&CDS_SEC = "1";
"A":   PN = "1"  !CDS_PN = "1";
"B":   PN = "2"  !CDS_PN = "2";
BODY = "RES","I12": #LOCATION = "R25W169" !CDS_LOCATION = "R25W169" &SEC = "1" #&CDS_SEC = "1";
"A":   PN = "1"  !CDS_PN = "1";
"B":   PN = "2"  !CDS_PN = "2";
BODY = "RES","I13": #LOCATION = "R25W170" !CDS_LOCATION = "R25W170" &SEC = "1" #&CDS_SEC = "1";
"A":   PN = "1"  !CDS_PN = "1";
"B":   PN = "2"  !CDS_PN = "2";
BODY = "RES","I18": #LOCATION = "R25W177" !CDS_LOCATION = "R25W177" &SEC = "1" #&CDS_SEC = "1";
"A":   PN = "1"  !CDS_PN = "1";
"B":   PN = "2"  !CDS_PN = "2";
BODY = "RES","I19": #LOCATION = "R25W178" !CDS_LOCATION = "R25W178" &SEC = "1" #&CDS_SEC = "1";
"A":   PN = "1"  !CDS_PN = "1";
"B":   PN = "2"  !CDS_PN = "2";
BODY = "RES","I20": #LOCATION = "R25W160" !CDS_LOCATION = "R25W160" &SEC = "1" #&CDS_SEC = "1";
"A":   PN = "1"  !CDS_PN = "1";
"B":   PN = "2"  !CDS_PN = "2";
BODY = "RES","I21": #LOCATION = "R25W161" !CDS_LOCATION = "R25W161" &SEC = "1" #&CDS_SEC = "1";
"A":   PN = "1"  !CDS_PN = "1";
"B":   PN = "2"  !CDS_PN = "2";
BODY = "RES","I22": #LOCATION = "R25W158" !CDS_LOCATION = "R25W158" &SEC = "1" #&CDS_SEC = "1";
"A":   PN = "1"  !CDS_PN = "1";
"B":   PN = "2"  !CDS_PN = "2";
BODY = "RES","I24": #LOCATION = "R25W159" !CDS_LOCATION = "R25W159" #SEC = "1" !CDS_SEC = "1";
"A":   PN = "1"  !CDS_PN = "1";
"B":   PN = "2"  !CDS_PN = "2";
BODY = "CAP_A","I26": #LOCATION = "C25W91" !CDS_LOCATION = "C25W91" #SEC = "1" !CDS_SEC = "1";
"A":   PN = "1"  !CDS_PN = "1";
"B":   PN = "2"  !CDS_PN = "2";
BODY = "CAP","I32": #LOCATION = "C25W94" !CDS_LOCATION = "C25W94" #SEC = "1" !CDS_SEC = "1";
"A":   PN = "1"  !CDS_PN = "1";
"B":   PN = "2"  !CDS_PN = "2";
BODY = "TTL3126","I33": #LOCATION = "U25W12" !CDS_LOCATION = "U25W12";
"A<0>":   PN = "12"  !CDS_PN = "12";
"A<1>":   PN = "9"  !CDS_PN = "9";
"A<2>":   PN = "5"  !CDS_PN = "5";
"A<3>":   PN = "2"  !CDS_PN = "2";
"B<0>":   PN = "11"  !CDS_PN = "11";
"B<1>":   PN = "8"  !CDS_PN = "8";
"B<2>":   PN = "6"  !CDS_PN = "6";
"B<3>":   PN = "3"  !CDS_PN = "3";
"OE<0>":   PN = "13"  !CDS_PN = "13";
"OE<1>":   PN = "10"  !CDS_PN = "10";
"OE<2>":   PN = "4"  !CDS_PN = "4";
"OE<3>":   PN = "1"  !CDS_PN = "1";
BODY = "GTL2014","I49": #LOCATION = "U25W10" !CDS_LOCATION = "U25W10" &SEC = "1" #&CDS_SEC = "1";
"A0":   PN = "13"  !CDS_PN = "13";
"A1":   PN = "12"  !CDS_PN = "12";
"A2":   PN = "10"  !CDS_PN = "10";
"A3":   PN = "9"  !CDS_PN = "9";
"B0":   PN = "2"  !CDS_PN = "2";
"B1":   PN = "3"  !CDS_PN = "3";
"B2":   PN = "5"  !CDS_PN = "5";
"B3":   PN = "6"  !CDS_PN = "6";
"DIR":   PN = "1"  !CDS_PN = "1";
"GND<0>":   PN = "7"  !CDS_PN = "7";
"GND<1>":   PN = "8"  !CDS_PN = "8";
"GND<2>":   PN = "11"  !CDS_PN = "11";
"VCC":   PN = "14"  !CDS_PN = "14";
"VREF":   PN = "4"  !CDS_PN = "4";
BODY = "MAX4564EKA-GP","I53": #LOCATION = "U25W13" !CDS_LOCATION = "U25W13" #SEC = "1" !CDS_SEC = "1";
"COM":   PN = "8"  !CDS_PN = "8";
"EN#":   PN = "7"  !CDS_PN = "7";
"GND":   PN = "5"  !CDS_PN = "5";
"IN":   PN = "3"  !CDS_PN = "3";
"NC":   PN = "1"  !CDS_PN = "1";
"NO":   PN = "4"  !CDS_PN = "4";
"V+":   PN = "2"  !CDS_PN = "2";
"V-":   PN = "6"  !CDS_PN = "6";
BODY = "CAP_A","I56": #LOCATION = "C25W95" !CDS_LOCATION = "C25W95" #SEC = "1" !CDS_SEC = "1";
"A":   PN = "1"  !CDS_PN = "1";
"B":   PN = "2"  !CDS_PN = "2";
BODY = "TTL1G08","I61": #LOCATION = "U25W17" !CDS_LOCATION = "U25W17" #SEC = "1" !CDS_SEC = "1";
"A<0>":   PN = "1"  !CDS_PN = "1";
"B<0>":   PN = "2"  !CDS_PN = "2";
"Y<0>":   PN = "4"  !CDS_PN = "4";
BODY = "CAP_A","I62": #LOCATION = "C25W99" !CDS_LOCATION = "C25W99" #SEC = "1" !CDS_SEC = "1";
"A":   PN = "1"  !CDS_PN = "1";
"B":   PN = "2"  !CDS_PN = "2";
BODY = "BLM15AG121SN-1GP","I71": #LOCATION = "FB25W1" !CDS_LOCATION = "FB25W1" #SEC = "1" !CDS_SEC = "1";
"1":   PN = "1"  !CDS_PN = "1";
"2":   PN = "2"  !CDS_PN = "2";
BODY = "BLM15AG121SN-1GP","I72": #LOCATION = "FB25W2" !CDS_LOCATION = "FB25W2" #SEC = "1" !CDS_SEC = "1";
"1":   PN = "1"  !CDS_PN = "1";
"2":   PN = "2"  !CDS_PN = "2";
BODY = "BLM15AG121SN-1GP","I73": #LOCATION = "FB25W3" !CDS_LOCATION = "FB25W3" #SEC = "1" !CDS_SEC = "1";
"1":   PN = "1"  !CDS_PN = "1";
"2":   PN = "2"  !CDS_PN = "2";
BODY = "BLM15AG121SN-1GP","I74": #LOCATION = "FB25W5" !CDS_LOCATION = "FB25W5" #SEC = "1" !CDS_SEC = "1";
"1":   PN = "1"  !CDS_PN = "1";
"2":   PN = "2"  !CDS_PN = "2";
BODY = "BLM15AG121SN-1GP","I75": #LOCATION = "FB25W4" !CDS_LOCATION = "FB25W4" #SEC = "1" !CDS_SEC = "1";
"1":   PN = "1"  !CDS_PN = "1";
"2":   PN = "2"  !CDS_PN = "2";
BODY = "TTL1G126_A","I76": #LOCATION = "U25W19" !CDS_LOCATION = "U25W19" #SEC = "1" !CDS_SEC = "1";
"A":   PN = "2"  !CDS_PN = "2";
"OE":   PN = "1"  !CDS_PN = "1";
"Y":   PN = "4"  !CDS_PN = "4";
BODY = "CAP_A","I79": #LOCATION = "C25W101" !CDS_LOCATION = "C25W101" #SEC = "1" !CDS_SEC = "1";
"A":   PN = "1"  !CDS_PN = "1";
"B":   PN = "2"  !CDS_PN = "2";
DRAWING = "@baseboard_fab2_lib.baseboard_fab2(sch_1):page268";
BODY = "RES","I2": #LOCATION = "R25W180" !CDS_LOCATION = "R25W180" &SEC = "1" #&CDS_SEC = "1";
"A":   PN = "1"  !CDS_PN = "1";
"B":   PN = "2"  !CDS_PN = "2";
BODY = "CAP_A","I4": #LOCATION = "C25W97" !CDS_LOCATION = "C25W97" #SEC = "1" !CDS_SEC = "1";
"A":   PN = "1"  !CDS_PN = "1";
"B":   PN = "2"  !CDS_PN = "2";
BODY = "RES","I7": #LOCATION = "R25W179" !CDS_LOCATION = "R25W179" &SEC = "1" #&CDS_SEC = "1";
"A":   PN = "1"  !CDS_PN = "1";
"B":   PN = "2"  !CDS_PN = "2";
BODY = "CAP_A","I9": #LOCATION = "C25W96" !CDS_LOCATION = "C25W96" #SEC = "1" !CDS_SEC = "1";
"A":   PN = "1"  !CDS_PN = "1";
"B":   PN = "2"  !CDS_PN = "2";
BODY = "TTL1G07_A","I12": #LOCATION = "U25W15" !CDS_LOCATION = "U25W15" #SEC = "1" !CDS_SEC = "1";
"A":   PN = "2"  !CDS_PN = "2";
"Y":   PN = "4"  !CDS_PN = "4";
BODY = "TTL1G07_A","I13": #LOCATION = "U25W14" !CDS_LOCATION = "U25W14" #SEC = "1" !CDS_SEC = "1";
"A":   PN = "2"  !CDS_PN = "2";
"Y":   PN = "4"  !CDS_PN = "4";
BODY = "RES","I14": #LOCATION = "R25W176" !CDS_LOCATION = "R25W176" &SEC = "1" #&CDS_SEC = "1";
"A":   PN = "1"  !CDS_PN = "1";
"B":   PN = "2"  !CDS_PN = "2";
BODY = "RES","I17": #LOCATION = "R25W175" !CDS_LOCATION = "R25W175" &SEC = "1" #&CDS_SEC = "1";
"A":   PN = "1"  !CDS_PN = "1";
"B":   PN = "2"  !CDS_PN = "2";
BODY = "CAP","I23": #LOCATION = "C25W92" !CDS_LOCATION = "C25W92" #SEC = "1" !CDS_SEC = "1";
"A":   PN = "1"  !CDS_PN = "1";
"B":   PN = "2"  !CDS_PN = "2";
BODY = "RES","I26": #LOCATION = "R25W166" !CDS_LOCATION = "R25W166" #SEC = "1" !CDS_SEC = "1";
"A":   PN = "1"  !CDS_PN = "1";
"B":   PN = "2"  !CDS_PN = "2";
BODY = "CAP_A","I27": #LOCATION = "C25W93" !CDS_LOCATION = "C25W93" #SEC = "1" !CDS_SEC = "1";
"A":   PN = "1"  !CDS_PN = "1";
"B":   PN = "2"  !CDS_PN = "2";
BODY = "RES","I28": #LOCATION = "R25W165" !CDS_LOCATION = "R25W165" #SEC = "1" !CDS_SEC = "1";
"A":   PN = "1"  !CDS_PN = "1";
"B":   PN = "2"  !CDS_PN = "2";
BODY = "RES","I29": #LOCATION = "R25W164" !CDS_LOCATION = "R25W164" #SEC = "1" !CDS_SEC = "1";
"A":   PN = "1"  !CDS_PN = "1";
"B":   PN = "2"  !CDS_PN = "2";
BODY = "GTL2014","I33": #LOCATION = "U25W11" !CDS_LOCATION = "U25W11" #SEC = "1" !CDS_SEC = "1";
"A0":   PN = "13"  !CDS_PN = "13";
"A1":   PN = "12"  !CDS_PN = "12";
"A2":   PN = "10"  !CDS_PN = "10";
"A3":   PN = "9"  !CDS_PN = "9";
"B0":   PN = "2"  !CDS_PN = "2";
"B1":   PN = "3"  !CDS_PN = "3";
"B2":   PN = "5"  !CDS_PN = "5";
"B3":   PN = "6"  !CDS_PN = "6";
"DIR":   PN = "1"  !CDS_PN = "1";
"GND<0>":   PN = "7"  !CDS_PN = "7";
"GND<1>":   PN = "8"  !CDS_PN = "8";
"GND<2>":   PN = "11"  !CDS_PN = "11";
"VCC":   PN = "14"  !CDS_PN = "14";
"VREF":   PN = "4"  !CDS_PN = "4";
BODY = "374R2F-1-GP","I36": #LOCATION = "R25W183" !CDS_LOCATION = "R25W183" &SEC = "1" #&CDS_SEC = "1";
"1":   PN = "1"  !CDS_PN = "1";
"2":   PN = "2"  !CDS_PN = "2";
BODY = "TTL3126","I38": #LOCATION = "U25W16" !CDS_LOCATION = "U25W16";
"A<0>":   PN = "12"  !CDS_PN = "12";
"A<1>":   PN = "9"  !CDS_PN = "9";
"A<2>":   PN = "5"  !CDS_PN = "5";
"A<3>":   PN = "2"  !CDS_PN = "2";
"B<0>":   PN = "11"  !CDS_PN = "11";
"B<1>":   PN = "8"  !CDS_PN = "8";
"B<2>":   PN = "6"  !CDS_PN = "6";
"B<3>":   PN = "3"  !CDS_PN = "3";
"OE<0>":   PN = "13"  !CDS_PN = "13";
"OE<1>":   PN = "10"  !CDS_PN = "10";
"OE<2>":   PN = "4"  !CDS_PN = "4";
"OE<3>":   PN = "1"  !CDS_PN = "1";
BODY = "CAP","I40": #LOCATION = "C25W98" !CDS_LOCATION = "C25W98" #SEC = "1" !CDS_SEC = "1";
"A":   PN = "1"  !CDS_PN = "1";
"B":   PN = "2"  !CDS_PN = "2";
BODY = "FET_N","I51": #LOCATION = "Q25W5" !CDS_LOCATION = "Q25W5" #SEC = "1" !CDS_SEC = "1";
"DRN":   PN = "3"  !CDS_PN = "3";
"GATE":   PN = "1"  !CDS_PN = "1";
"SRC":   PN = "2"  !CDS_PN = "2";
BODY = "RES","I54": #LOCATION = "R25W185" !CDS_LOCATION = "R25W185" #SEC = "1" !CDS_SEC = "1";
"A":   PN = "1"  !CDS_PN = "1";
"B":   PN = "2"  !CDS_PN = "2";
BODY = "TTL1G08","I57": #LOCATION = "U25W18" !CDS_LOCATION = "U25W18" #SEC = "1" !CDS_SEC = "1";
"A<0>":   PN = "1"  !CDS_PN = "1";
"B<0>":   PN = "2"  !CDS_PN = "2";
"Y<0>":   PN = "4"  !CDS_PN = "4";
BODY = "CAP_A","I60": #LOCATION = "C25W100" !CDS_LOCATION = "C25W100" #SEC = "1" !CDS_SEC = "1";
"A":   PN = "1"  !CDS_PN = "1";
"B":   PN = "2"  !CDS_PN = "2";
BODY = "SW-SLIDE75-GP","I63": #LOCATION = "S9W1" !CDS_LOCATION = "S9W1" #SEC = "1" !CDS_SEC = "1";
"1":   PN = "1"  !CDS_PN = "1";
"2":   PN = "2"  !CDS_PN = "2";
"3":   PN = "3"  !CDS_PN = "3";
"4":   PN = "4"  !CDS_PN = "4";
"5":   PN = "5"  !CDS_PN = "5";
"6":   PN = "6"  !CDS_PN = "6";
"7":   PN = "7"  !CDS_PN = "7";
"NP1":   PN = "NP1"  !CDS_PN = "NP1";
"NP2":   PN = "NP2"  !CDS_PN = "NP2";
BODY = "RES","I66": #LOCATION = "R25W187" !CDS_LOCATION = "R25W187" #SEC = "1" !CDS_SEC = "1";
"A":   PN = "1"  !CDS_PN = "1";
"B":   PN = "2"  !CDS_PN = "2";
DRAWING = "@baseboard_fab2_lib.baseboard_fab2(sch_1):page271";
BODY = "TPAD-DIFF-4P-GP","I3": #LOCATION = "T1P1" !CDS_LOCATION = "T1P1" #SEC = "1" !CDS_SEC = "1";
"1":   PN = "1"  !CDS_PN = "1";
"2":   PN = "2"  !CDS_PN = "2";
"GND1":   PN = "GND1"  !CDS_PN = "GND1";
"GND2":   PN = "GND2"  !CDS_PN = "GND2";
BODY = "TPAD-DIFF-4P-GP","I5": #LOCATION = "T1P2" !CDS_LOCATION = "T1P2" #SEC = "1" !CDS_SEC = "1";
"1":   PN = "1"  !CDS_PN = "1";
"2":   PN = "2"  !CDS_PN = "2";
"GND1":   PN = "GND1"  !CDS_PN = "GND1";
"GND2":   PN = "GND2"  !CDS_PN = "GND2";
BODY = "TPAD-DIFF-4P-GP","I7": #LOCATION = "T1P4" !CDS_LOCATION = "T1P4" #SEC = "1" !CDS_SEC = "1";
"1":   PN = "1"  !CDS_PN = "1";
"2":   PN = "2"  !CDS_PN = "2";
"GND1":   PN = "GND1"  !CDS_PN = "GND1";
"GND2":   PN = "GND2"  !CDS_PN = "GND2";
BODY = "TPAD-DIFF-4P-GP","I8": #LOCATION = "T1P3" !CDS_LOCATION = "T1P3" #SEC = "1" !CDS_SEC = "1";
"1":   PN = "1"  !CDS_PN = "1";
"2":   PN = "2"  !CDS_PN = "2";
"GND1":   PN = "GND1"  !CDS_PN = "GND1";
"GND2":   PN = "GND2"  !CDS_PN = "GND2";
BODY = "TPAD-DIFF-4P-GP","I11": #LOCATION = "T1P5" !CDS_LOCATION = "T1P5" #SEC = "1" !CDS_SEC = "1";
"1":   PN = "1"  !CDS_PN = "1";
"2":   PN = "2"  !CDS_PN = "2";
"GND1":   PN = "GND1"  !CDS_PN = "GND1";
"GND2":   PN = "GND2"  !CDS_PN = "GND2";
BODY = "TPAD-DIFF-4P-GP","I13": #LOCATION = "T1P6" !CDS_LOCATION = "T1P6" #SEC = "1" !CDS_SEC = "1";
"1":   PN = "1"  !CDS_PN = "1";
"2":   PN = "2"  !CDS_PN = "2";
"GND1":   PN = "GND1"  !CDS_PN = "GND1";
"GND2":   PN = "GND2"  !CDS_PN = "GND2";
BODY = "TPAD-DIFF-4P-GP","I15": #LOCATION = "T1P10" !CDS_LOCATION = "T1P10" #SEC = "1" !CDS_SEC = "1";
"1":   PN = "1"  !CDS_PN = "1";
"2":   PN = "2"  !CDS_PN = "2";
"GND1":   PN = "GND1"  !CDS_PN = "GND1";
"GND2":   PN = "GND2"  !CDS_PN = "GND2";
BODY = "TPAD-DIFF-4P-GP","I16": #LOCATION = "T1P8" !CDS_LOCATION = "T1P8" #SEC = "1" !CDS_SEC = "1";
"1":   PN = "1"  !CDS_PN = "1";
"2":   PN = "2"  !CDS_PN = "2";
"GND1":   PN = "GND1"  !CDS_PN = "GND1";
"GND2":   PN = "GND2"  !CDS_PN = "GND2";
BODY = "TPAD-DIFF-4P-GP","I17": #LOCATION = "T1P7" !CDS_LOCATION = "T1P7" #SEC = "1" !CDS_SEC = "1";
"1":   PN = "1"  !CDS_PN = "1";
"2":   PN = "2"  !CDS_PN = "2";
"GND1":   PN = "GND1"  !CDS_PN = "GND1";
"GND2":   PN = "GND2"  !CDS_PN = "GND2";
BODY = "TPAD-DIFF-4P-GP","I19": #LOCATION = "T1P9" !CDS_LOCATION = "T1P9" #SEC = "1" !CDS_SEC = "1";
"1":   PN = "1"  !CDS_PN = "1";
"2":   PN = "2"  !CDS_PN = "2";
"GND1":   PN = "GND1"  !CDS_PN = "GND1";
"GND2":   PN = "GND2"  !CDS_PN = "GND2";
BODY = "TPAD-DIFF-4P-GP","I23": #LOCATION = "T1P11" !CDS_LOCATION = "T1P11" #SEC = "1" !CDS_SEC = "1";
"1":   PN = "1"  !CDS_PN = "1";
"2":   PN = "2"  !CDS_PN = "2";
"GND1":   PN = "GND1"  !CDS_PN = "GND1";
"GND2":   PN = "GND2"  !CDS_PN = "GND2";
BODY = "TPAD-DIFF-4P-GP","I24": #LOCATION = "T1P12" !CDS_LOCATION = "T1P12" #SEC = "1" !CDS_SEC = "1";
"1":   PN = "1"  !CDS_PN = "1";
"2":   PN = "2"  !CDS_PN = "2";
"GND1":   PN = "GND1"  !CDS_PN = "GND1";
"GND2":   PN = "GND2"  !CDS_PN = "GND2";
BODY = "TPAD-DIFF-4P-GP","I30": #LOCATION = "T1P14" !CDS_LOCATION = "T1P14" #SEC = "1" !CDS_SEC = "1";
"1":   PN = "1"  !CDS_PN = "1";
"2":   PN = "2"  !CDS_PN = "2";
"GND1":   PN = "GND1"  !CDS_PN = "GND1";
"GND2":   PN = "GND2"  !CDS_PN = "GND2";
BODY = "TPAD-DIFF-4P-GP","I36": #LOCATION = "T1P17" !CDS_LOCATION = "T1P17" #SEC = "1" !CDS_SEC = "1";
"1":   PN = "1"  !CDS_PN = "1";
"2":   PN = "2"  !CDS_PN = "2";
"GND1":   PN = "GND1"  !CDS_PN = "GND1";
"GND2":   PN = "GND2"  !CDS_PN = "GND2";
BODY = "TPAD-DIFF-4P-GP","I38": #LOCATION = "T1P24" !CDS_LOCATION = "T1P24" #SEC = "1" !CDS_SEC = "1";
"1":   PN = "1"  !CDS_PN = "1";
"2":   PN = "2"  !CDS_PN = "2";
"GND1":   PN = "GND1"  !CDS_PN = "GND1";
"GND2":   PN = "GND2"  !CDS_PN = "GND2";
BODY = "TPAD-DIFF-4P-GP","I39": #LOCATION = "T1P19" !CDS_LOCATION = "T1P19" #SEC = "1" !CDS_SEC = "1";
"1":   PN = "1"  !CDS_PN = "1";
"2":   PN = "2"  !CDS_PN = "2";
"GND1":   PN = "GND1"  !CDS_PN = "GND1";
"GND2":   PN = "GND2"  !CDS_PN = "GND2";
BODY = "TPAD-DIFF-4P-GP","I45": #LOCATION = "T1P22" !CDS_LOCATION = "T1P22" #SEC = "1" !CDS_SEC = "1";
"1":   PN = "1"  !CDS_PN = "1";
"2":   PN = "2"  !CDS_PN = "2";
"GND1":   PN = "GND1"  !CDS_PN = "GND1";
"GND2":   PN = "GND2"  !CDS_PN = "GND2";
BODY = "TPAD-DIFF-4P-GP","I47": #LOCATION = "T1P23" !CDS_LOCATION = "T1P23" #SEC = "1" !CDS_SEC = "1";
"1":   PN = "1"  !CDS_PN = "1";
"2":   PN = "2"  !CDS_PN = "2";
"GND1":   PN = "GND1"  !CDS_PN = "GND1";
"GND2":   PN = "GND2"  !CDS_PN = "GND2";
BODY = "TPAD-SE-2P-GP","I50": #LOCATION = "T1P25" !CDS_LOCATION = "T1P25" &SEC = "1" #&CDS_SEC = "1";
"1":   PN = "1"  !CDS_PN = "1";
"GND1":   PN = "GND1"  !CDS_PN = "GND1";
BODY = "TPAD-SE-2P-GP","I52": #LOCATION = "T1P26" !CDS_LOCATION = "T1P26" &SEC = "1" #&CDS_SEC = "1";
"1":   PN = "1"  !CDS_PN = "1";
"GND1":   PN = "GND1"  !CDS_PN = "GND1";
BODY = "TPAD-SE-2P-GP","I54": #LOCATION = "T1P27" !CDS_LOCATION = "T1P27" &SEC = "1" #&CDS_SEC = "1";
"1":   PN = "1"  !CDS_PN = "1";
"GND1":   PN = "GND1"  !CDS_PN = "GND1";
BODY = "TPAD-SE-2P-GP","I56": #LOCATION = "T1P29" !CDS_LOCATION = "T1P29" &SEC = "1" #&CDS_SEC = "1";
"1":   PN = "1"  !CDS_PN = "1";
"GND1":   PN = "GND1"  !CDS_PN = "GND1";
BODY = "TPAD-SE-2P-GP","I60": #LOCATION = "T1P28" !CDS_LOCATION = "T1P28" &SEC = "1" #&CDS_SEC = "1";
"1":   PN = "1"  !CDS_PN = "1";
"GND1":   PN = "GND1"  !CDS_PN = "GND1";
BODY = "TPAD-SE-2P-GP","I61": #LOCATION = "T1P30" !CDS_LOCATION = "T1P30" &SEC = "1" #&CDS_SEC = "1";
"1":   PN = "1"  !CDS_PN = "1";
"GND1":   PN = "GND1"  !CDS_PN = "GND1";
BODY = "TPAD-SE-2P-GP","I62": #LOCATION = "T1P34" !CDS_LOCATION = "T1P34" &SEC = "1" #&CDS_SEC = "1";
"1":   PN = "1"  !CDS_PN = "1";
"GND1":   PN = "GND1"  !CDS_PN = "GND1";
BODY = "TPAD-SE-2P-GP","I63": #LOCATION = "T1P36" !CDS_LOCATION = "T1P36" &SEC = "1" #&CDS_SEC = "1";
"1":   PN = "1"  !CDS_PN = "1";
"GND1":   PN = "GND1"  !CDS_PN = "GND1";
BODY = "TPAD-SE-2P-GP","I67": #LOCATION = "T1P35" !CDS_LOCATION = "T1P35" &SEC = "1" #&CDS_SEC = "1";
"1":   PN = "1"  !CDS_PN = "1";
"GND1":   PN = "GND1"  !CDS_PN = "GND1";
BODY = "TPAD-SE-2P-GP","I71": #LOCATION = "T1P31" !CDS_LOCATION = "T1P31" &SEC = "1" #&CDS_SEC = "1";
"1":   PN = "1"  !CDS_PN = "1";
"GND1":   PN = "GND1"  !CDS_PN = "GND1";
BODY = "TPAD-SE-2P-GP","I72": #LOCATION = "T1P32" !CDS_LOCATION = "T1P32" &SEC = "1" #&CDS_SEC = "1";
"1":   PN = "1"  !CDS_PN = "1";
"GND1":   PN = "GND1"  !CDS_PN = "GND1";
BODY = "TPAD-SE-2P-GP","I73": #LOCATION = "T1P33" !CDS_LOCATION = "T1P33" &SEC = "1" #&CDS_SEC = "1";
"1":   PN = "1"  !CDS_PN = "1";
"GND1":   PN = "GND1"  !CDS_PN = "GND1";
DRAWING = "@baseboard_fab2_lib.baseboard_fab2(sch_1):page270";
BODY = "TEST-PAD-12P-1-GP-U","I1": #LOCATION = "T1D1" !CDS_LOCATION = "T1D1" #SEC = "1" !CDS_SEC = "1";
"DN":   PN = "2"  !CDS_PN = "2";
"DP":   PN = "1"  !CDS_PN = "1";
"GND<0>":   PN = "3"  !CDS_PN = "3";
"GND<1>":   PN = "4"  !CDS_PN = "4";
"GND<2>":   PN = "5"  !CDS_PN = "5";
"GND<3>":   PN = "6"  !CDS_PN = "6";
"GND<4>":   PN = "7"  !CDS_PN = "7";
"GND<5>":   PN = "8"  !CDS_PN = "8";
"GND<6>":   PN = "9"  !CDS_PN = "9";
"GND<7>":   PN = "10"  !CDS_PN = "10";
"GND<8>":   PN = "11"  !CDS_PN = "11";
"GND<9>":   PN = "12"  !CDS_PN = "12";
BODY = "TEST-PAD-12P-1-GP-U","I3": #LOCATION = "T1D2" !CDS_LOCATION = "T1D2" #SEC = "1" !CDS_SEC = "1";
"DN":   PN = "2"  !CDS_PN = "2";
"DP":   PN = "1"  !CDS_PN = "1";
"GND<0>":   PN = "3"  !CDS_PN = "3";
"GND<1>":   PN = "4"  !CDS_PN = "4";
"GND<2>":   PN = "5"  !CDS_PN = "5";
"GND<3>":   PN = "6"  !CDS_PN = "6";
"GND<4>":   PN = "7"  !CDS_PN = "7";
"GND<5>":   PN = "8"  !CDS_PN = "8";
"GND<6>":   PN = "9"  !CDS_PN = "9";
"GND<7>":   PN = "10"  !CDS_PN = "10";
"GND<8>":   PN = "11"  !CDS_PN = "11";
"GND<9>":   PN = "12"  !CDS_PN = "12";
BODY = "TEST-PAD-12P-1-GP-U","I5": #LOCATION = "T1D3" !CDS_LOCATION = "T1D3" #SEC = "1" !CDS_SEC = "1";
"DN":   PN = "2"  !CDS_PN = "2";
"DP":   PN = "1"  !CDS_PN = "1";
"GND<0>":   PN = "3"  !CDS_PN = "3";
"GND<1>":   PN = "4"  !CDS_PN = "4";
"GND<2>":   PN = "5"  !CDS_PN = "5";
"GND<3>":   PN = "6"  !CDS_PN = "6";
"GND<4>":   PN = "7"  !CDS_PN = "7";
"GND<5>":   PN = "8"  !CDS_PN = "8";
"GND<6>":   PN = "9"  !CDS_PN = "9";
"GND<7>":   PN = "10"  !CDS_PN = "10";
"GND<8>":   PN = "11"  !CDS_PN = "11";
"GND<9>":   PN = "12"  !CDS_PN = "12";
BODY = "TEST-PAD-12P-1-GP-U","I6": #LOCATION = "T1D4" !CDS_LOCATION = "T1D4" #SEC = "1" !CDS_SEC = "1";
"DN":   PN = "2"  !CDS_PN = "2";
"DP":   PN = "1"  !CDS_PN = "1";
"GND<0>":   PN = "3"  !CDS_PN = "3";
"GND<1>":   PN = "4"  !CDS_PN = "4";
"GND<2>":   PN = "5"  !CDS_PN = "5";
"GND<3>":   PN = "6"  !CDS_PN = "6";
"GND<4>":   PN = "7"  !CDS_PN = "7";
"GND<5>":   PN = "8"  !CDS_PN = "8";
"GND<6>":   PN = "9"  !CDS_PN = "9";
"GND<7>":   PN = "10"  !CDS_PN = "10";
"GND<8>":   PN = "11"  !CDS_PN = "11";
"GND<9>":   PN = "12"  !CDS_PN = "12";
BODY = "TEST-PAD-12P-1-GP-U","I9": #LOCATION = "T1D6" !CDS_LOCATION = "T1D6" #SEC = "1" !CDS_SEC = "1";
"DN":   PN = "2"  !CDS_PN = "2";
"DP":   PN = "1"  !CDS_PN = "1";
"GND<0>":   PN = "3"  !CDS_PN = "3";
"GND<1>":   PN = "4"  !CDS_PN = "4";
"GND<2>":   PN = "5"  !CDS_PN = "5";
"GND<3>":   PN = "6"  !CDS_PN = "6";
"GND<4>":   PN = "7"  !CDS_PN = "7";
"GND<5>":   PN = "8"  !CDS_PN = "8";
"GND<6>":   PN = "9"  !CDS_PN = "9";
"GND<7>":   PN = "10"  !CDS_PN = "10";
"GND<8>":   PN = "11"  !CDS_PN = "11";
"GND<9>":   PN = "12"  !CDS_PN = "12";
BODY = "TEST-PAD-12P-1-GP-U","I12": #LOCATION = "T1D5" !CDS_LOCATION = "T1D5" #SEC = "1" !CDS_SEC = "1";
"DN":   PN = "2"  !CDS_PN = "2";
"DP":   PN = "1"  !CDS_PN = "1";
"GND<0>":   PN = "3"  !CDS_PN = "3";
"GND<1>":   PN = "4"  !CDS_PN = "4";
"GND<2>":   PN = "5"  !CDS_PN = "5";
"GND<3>":   PN = "6"  !CDS_PN = "6";
"GND<4>":   PN = "7"  !CDS_PN = "7";
"GND<5>":   PN = "8"  !CDS_PN = "8";
"GND<6>":   PN = "9"  !CDS_PN = "9";
"GND<7>":   PN = "10"  !CDS_PN = "10";
"GND<8>":   PN = "11"  !CDS_PN = "11";
"GND<9>":   PN = "12"  !CDS_PN = "12";
BODY = "TEST-PAD-12P-1-GP-U","I13": #LOCATION = "T1D8" !CDS_LOCATION = "T1D8" #SEC = "1" !CDS_SEC = "1";
"DN":   PN = "2"  !CDS_PN = "2";
"DP":   PN = "1"  !CDS_PN = "1";
"GND<0>":   PN = "3"  !CDS_PN = "3";
"GND<1>":   PN = "4"  !CDS_PN = "4";
"GND<2>":   PN = "5"  !CDS_PN = "5";
"GND<3>":   PN = "6"  !CDS_PN = "6";
"GND<4>":   PN = "7"  !CDS_PN = "7";
"GND<5>":   PN = "8"  !CDS_PN = "8";
"GND<6>":   PN = "9"  !CDS_PN = "9";
"GND<7>":   PN = "10"  !CDS_PN = "10";
"GND<8>":   PN = "11"  !CDS_PN = "11";
"GND<9>":   PN = "12"  !CDS_PN = "12";
BODY = "TEST-PAD-12P-1-GP-U","I16": #LOCATION = "T1D7" !CDS_LOCATION = "T1D7" #SEC = "1" !CDS_SEC = "1";
"DN":   PN = "2"  !CDS_PN = "2";
"DP":   PN = "1"  !CDS_PN = "1";
"GND<0>":   PN = "3"  !CDS_PN = "3";
"GND<1>":   PN = "4"  !CDS_PN = "4";
"GND<2>":   PN = "5"  !CDS_PN = "5";
"GND<3>":   PN = "6"  !CDS_PN = "6";
"GND<4>":   PN = "7"  !CDS_PN = "7";
"GND<5>":   PN = "8"  !CDS_PN = "8";
"GND<6>":   PN = "9"  !CDS_PN = "9";
"GND<7>":   PN = "10"  !CDS_PN = "10";
"GND<8>":   PN = "11"  !CDS_PN = "11";
"GND<9>":   PN = "12"  !CDS_PN = "12";
BODY = "TEST-PAD-12P-1-GP-U","I17": #LOCATION = "T1D10" !CDS_LOCATION = "T1D10" #SEC = "1" !CDS_SEC = "1";
"DN":   PN = "2"  !CDS_PN = "2";
"DP":   PN = "1"  !CDS_PN = "1";
"GND<0>":   PN = "3"  !CDS_PN = "3";
"GND<1>":   PN = "4"  !CDS_PN = "4";
"GND<2>":   PN = "5"  !CDS_PN = "5";
"GND<3>":   PN = "6"  !CDS_PN = "6";
"GND<4>":   PN = "7"  !CDS_PN = "7";
"GND<5>":   PN = "8"  !CDS_PN = "8";
"GND<6>":   PN = "9"  !CDS_PN = "9";
"GND<7>":   PN = "10"  !CDS_PN = "10";
"GND<8>":   PN = "11"  !CDS_PN = "11";
"GND<9>":   PN = "12"  !CDS_PN = "12";
BODY = "TEST-PAD-12P-1-GP-U","I18": #LOCATION = "T1D9" !CDS_LOCATION = "T1D9" #SEC = "1" !CDS_SEC = "1";
"DN":   PN = "2"  !CDS_PN = "2";
"DP":   PN = "1"  !CDS_PN = "1";
"GND<0>":   PN = "3"  !CDS_PN = "3";
"GND<1>":   PN = "4"  !CDS_PN = "4";
"GND<2>":   PN = "5"  !CDS_PN = "5";
"GND<3>":   PN = "6"  !CDS_PN = "6";
"GND<4>":   PN = "7"  !CDS_PN = "7";
"GND<5>":   PN = "8"  !CDS_PN = "8";
"GND<6>":   PN = "9"  !CDS_PN = "9";
"GND<7>":   PN = "10"  !CDS_PN = "10";
"GND<8>":   PN = "11"  !CDS_PN = "11";
"GND<9>":   PN = "12"  !CDS_PN = "12";
BODY = "TEST-PAD-12P-1-GP-U","I21": #LOCATION = "T1D12" !CDS_LOCATION = "T1D12" #SEC = "1" !CDS_SEC = "1";
"DN":   PN = "2"  !CDS_PN = "2";
"DP":   PN = "1"  !CDS_PN = "1";
"GND<0>":   PN = "3"  !CDS_PN = "3";
"GND<1>":   PN = "4"  !CDS_PN = "4";
"GND<2>":   PN = "5"  !CDS_PN = "5";
"GND<3>":   PN = "6"  !CDS_PN = "6";
"GND<4>":   PN = "7"  !CDS_PN = "7";
"GND<5>":   PN = "8"  !CDS_PN = "8";
"GND<6>":   PN = "9"  !CDS_PN = "9";
"GND<7>":   PN = "10"  !CDS_PN = "10";
"GND<8>":   PN = "11"  !CDS_PN = "11";
"GND<9>":   PN = "12"  !CDS_PN = "12";
BODY = "TEST-PAD-12P-1-GP-U","I24": #LOCATION = "T1D11" !CDS_LOCATION = "T1D11" #SEC = "1" !CDS_SEC = "1";
"DN":   PN = "2"  !CDS_PN = "2";
"DP":   PN = "1"  !CDS_PN = "1";
"GND<0>":   PN = "3"  !CDS_PN = "3";
"GND<1>":   PN = "4"  !CDS_PN = "4";
"GND<2>":   PN = "5"  !CDS_PN = "5";
"GND<3>":   PN = "6"  !CDS_PN = "6";
"GND<4>":   PN = "7"  !CDS_PN = "7";
"GND<5>":   PN = "8"  !CDS_PN = "8";
"GND<6>":   PN = "9"  !CDS_PN = "9";
"GND<7>":   PN = "10"  !CDS_PN = "10";
"GND<8>":   PN = "11"  !CDS_PN = "11";
"GND<9>":   PN = "12"  !CDS_PN = "12";
DRAWING = "@baseboard_fab2_lib.baseboard_fab2(sch_1):page272";
BODY = "TEST-PAD-12P-1-GP-U","I1": #LOCATION = "T1D17" !CDS_LOCATION = "T1D17" #SEC = "1" !CDS_SEC = "1";
"DN":   PN = "2"  !CDS_PN = "2";
"DP":   PN = "1"  !CDS_PN = "1";
"GND<0>":   PN = "3"  !CDS_PN = "3";
"GND<1>":   PN = "4"  !CDS_PN = "4";
"GND<2>":   PN = "5"  !CDS_PN = "5";
"GND<3>":   PN = "6"  !CDS_PN = "6";
"GND<4>":   PN = "7"  !CDS_PN = "7";
"GND<5>":   PN = "8"  !CDS_PN = "8";
"GND<6>":   PN = "9"  !CDS_PN = "9";
"GND<7>":   PN = "10"  !CDS_PN = "10";
"GND<8>":   PN = "11"  !CDS_PN = "11";
"GND<9>":   PN = "12"  !CDS_PN = "12";
BODY = "TEST-PAD-12P-1-GP-U","I3": #LOCATION = "T1D15" !CDS_LOCATION = "T1D15" #SEC = "1" !CDS_SEC = "1";
"DN":   PN = "2"  !CDS_PN = "2";
"DP":   PN = "1"  !CDS_PN = "1";
"GND<0>":   PN = "3"  !CDS_PN = "3";
"GND<1>":   PN = "4"  !CDS_PN = "4";
"GND<2>":   PN = "5"  !CDS_PN = "5";
"GND<3>":   PN = "6"  !CDS_PN = "6";
"GND<4>":   PN = "7"  !CDS_PN = "7";
"GND<5>":   PN = "8"  !CDS_PN = "8";
"GND<6>":   PN = "9"  !CDS_PN = "9";
"GND<7>":   PN = "10"  !CDS_PN = "10";
"GND<8>":   PN = "11"  !CDS_PN = "11";
"GND<9>":   PN = "12"  !CDS_PN = "12";
BODY = "TEST-PAD-12P-1-GP-U","I5": #LOCATION = "T1D13" !CDS_LOCATION = "T1D13" #SEC = "1" !CDS_SEC = "1";
"DN":   PN = "2"  !CDS_PN = "2";
"DP":   PN = "1"  !CDS_PN = "1";
"GND<0>":   PN = "3"  !CDS_PN = "3";
"GND<1>":   PN = "4"  !CDS_PN = "4";
"GND<2>":   PN = "5"  !CDS_PN = "5";
"GND<3>":   PN = "6"  !CDS_PN = "6";
"GND<4>":   PN = "7"  !CDS_PN = "7";
"GND<5>":   PN = "8"  !CDS_PN = "8";
"GND<6>":   PN = "9"  !CDS_PN = "9";
"GND<7>":   PN = "10"  !CDS_PN = "10";
"GND<8>":   PN = "11"  !CDS_PN = "11";
"GND<9>":   PN = "12"  !CDS_PN = "12";
BODY = "TEST-PAD-12P-1-GP-U","I8": #LOCATION = "T1D18" !CDS_LOCATION = "T1D18" #SEC = "1" !CDS_SEC = "1";
"DN":   PN = "2"  !CDS_PN = "2";
"DP":   PN = "1"  !CDS_PN = "1";
"GND<0>":   PN = "3"  !CDS_PN = "3";
"GND<1>":   PN = "4"  !CDS_PN = "4";
"GND<2>":   PN = "5"  !CDS_PN = "5";
"GND<3>":   PN = "6"  !CDS_PN = "6";
"GND<4>":   PN = "7"  !CDS_PN = "7";
"GND<5>":   PN = "8"  !CDS_PN = "8";
"GND<6>":   PN = "9"  !CDS_PN = "9";
"GND<7>":   PN = "10"  !CDS_PN = "10";
"GND<8>":   PN = "11"  !CDS_PN = "11";
"GND<9>":   PN = "12"  !CDS_PN = "12";
BODY = "TEST-PAD-12P-1-GP-U","I9": #LOCATION = "T1D23" !CDS_LOCATION = "T1D23" #SEC = "1" !CDS_SEC = "1";
"DN":   PN = "2"  !CDS_PN = "2";
"DP":   PN = "1"  !CDS_PN = "1";
"GND<0>":   PN = "3"  !CDS_PN = "3";
"GND<1>":   PN = "4"  !CDS_PN = "4";
"GND<2>":   PN = "5"  !CDS_PN = "5";
"GND<3>":   PN = "6"  !CDS_PN = "6";
"GND<4>":   PN = "7"  !CDS_PN = "7";
"GND<5>":   PN = "8"  !CDS_PN = "8";
"GND<6>":   PN = "9"  !CDS_PN = "9";
"GND<7>":   PN = "10"  !CDS_PN = "10";
"GND<8>":   PN = "11"  !CDS_PN = "11";
"GND<9>":   PN = "12"  !CDS_PN = "12";
BODY = "TEST-PAD-12P-1-GP-U","I12": #LOCATION = "T1D24" !CDS_LOCATION = "T1D24" #SEC = "1" !CDS_SEC = "1";
"DN":   PN = "2"  !CDS_PN = "2";
"DP":   PN = "1"  !CDS_PN = "1";
"GND<0>":   PN = "3"  !CDS_PN = "3";
"GND<1>":   PN = "4"  !CDS_PN = "4";
"GND<2>":   PN = "5"  !CDS_PN = "5";
"GND<3>":   PN = "6"  !CDS_PN = "6";
"GND<4>":   PN = "7"  !CDS_PN = "7";
"GND<5>":   PN = "8"  !CDS_PN = "8";
"GND<6>":   PN = "9"  !CDS_PN = "9";
"GND<7>":   PN = "10"  !CDS_PN = "10";
"GND<8>":   PN = "11"  !CDS_PN = "11";
"GND<9>":   PN = "12"  !CDS_PN = "12";
BODY = "TEST-PAD-12P-1-GP-U","I14": #LOCATION = "T1D16" !CDS_LOCATION = "T1D16" #SEC = "1" !CDS_SEC = "1";
"DN":   PN = "2"  !CDS_PN = "2";
"DP":   PN = "1"  !CDS_PN = "1";
"GND<0>":   PN = "3"  !CDS_PN = "3";
"GND<1>":   PN = "4"  !CDS_PN = "4";
"GND<2>":   PN = "5"  !CDS_PN = "5";
"GND<3>":   PN = "6"  !CDS_PN = "6";
"GND<4>":   PN = "7"  !CDS_PN = "7";
"GND<5>":   PN = "8"  !CDS_PN = "8";
"GND<6>":   PN = "9"  !CDS_PN = "9";
"GND<7>":   PN = "10"  !CDS_PN = "10";
"GND<8>":   PN = "11"  !CDS_PN = "11";
"GND<9>":   PN = "12"  !CDS_PN = "12";
BODY = "TEST-PAD-12P-1-GP-U","I16": #LOCATION = "T1D21" !CDS_LOCATION = "T1D21" #SEC = "1" !CDS_SEC = "1";
"DN":   PN = "2"  !CDS_PN = "2";
"DP":   PN = "1"  !CDS_PN = "1";
"GND<0>":   PN = "3"  !CDS_PN = "3";
"GND<1>":   PN = "4"  !CDS_PN = "4";
"GND<2>":   PN = "5"  !CDS_PN = "5";
"GND<3>":   PN = "6"  !CDS_PN = "6";
"GND<4>":   PN = "7"  !CDS_PN = "7";
"GND<5>":   PN = "8"  !CDS_PN = "8";
"GND<6>":   PN = "9"  !CDS_PN = "9";
"GND<7>":   PN = "10"  !CDS_PN = "10";
"GND<8>":   PN = "11"  !CDS_PN = "11";
"GND<9>":   PN = "12"  !CDS_PN = "12";
BODY = "TEST-PAD-12P-1-GP-U","I21": #LOCATION = "T1D22" !CDS_LOCATION = "T1D22" #SEC = "1" !CDS_SEC = "1";
"DN":   PN = "2"  !CDS_PN = "2";
"DP":   PN = "1"  !CDS_PN = "1";
"GND<0>":   PN = "3"  !CDS_PN = "3";
"GND<1>":   PN = "4"  !CDS_PN = "4";
"GND<2>":   PN = "5"  !CDS_PN = "5";
"GND<3>":   PN = "6"  !CDS_PN = "6";
"GND<4>":   PN = "7"  !CDS_PN = "7";
"GND<5>":   PN = "8"  !CDS_PN = "8";
"GND<6>":   PN = "9"  !CDS_PN = "9";
"GND<7>":   PN = "10"  !CDS_PN = "10";
"GND<8>":   PN = "11"  !CDS_PN = "11";
"GND<9>":   PN = "12"  !CDS_PN = "12";
BODY = "TEST-PAD-12P-1-GP-U","I22": #LOCATION = "T1D14" !CDS_LOCATION = "T1D14" #SEC = "1" !CDS_SEC = "1";
"DN":   PN = "2"  !CDS_PN = "2";
"DP":   PN = "1"  !CDS_PN = "1";
"GND<0>":   PN = "3"  !CDS_PN = "3";
"GND<1>":   PN = "4"  !CDS_PN = "4";
"GND<2>":   PN = "5"  !CDS_PN = "5";
"GND<3>":   PN = "6"  !CDS_PN = "6";
"GND<4>":   PN = "7"  !CDS_PN = "7";
"GND<5>":   PN = "8"  !CDS_PN = "8";
"GND<6>":   PN = "9"  !CDS_PN = "9";
"GND<7>":   PN = "10"  !CDS_PN = "10";
"GND<8>":   PN = "11"  !CDS_PN = "11";
"GND<9>":   PN = "12"  !CDS_PN = "12";
BODY = "TEST-PAD-12P-1-GP-U","I23": #LOCATION = "T1D19" !CDS_LOCATION = "T1D19" #SEC = "1" !CDS_SEC = "1";
"DN":   PN = "2"  !CDS_PN = "2";
"DP":   PN = "1"  !CDS_PN = "1";
"GND<0>":   PN = "3"  !CDS_PN = "3";
"GND<1>":   PN = "4"  !CDS_PN = "4";
"GND<2>":   PN = "5"  !CDS_PN = "5";
"GND<3>":   PN = "6"  !CDS_PN = "6";
"GND<4>":   PN = "7"  !CDS_PN = "7";
"GND<5>":   PN = "8"  !CDS_PN = "8";
"GND<6>":   PN = "9"  !CDS_PN = "9";
"GND<7>":   PN = "10"  !CDS_PN = "10";
"GND<8>":   PN = "11"  !CDS_PN = "11";
"GND<9>":   PN = "12"  !CDS_PN = "12";
BODY = "TEST-PAD-12P-1-GP-U","I24": #LOCATION = "T1D20" !CDS_LOCATION = "T1D20" #SEC = "1" !CDS_SEC = "1";
"DN":   PN = "2"  !CDS_PN = "2";
"DP":   PN = "1"  !CDS_PN = "1";
"GND<0>":   PN = "3"  !CDS_PN = "3";
"GND<1>":   PN = "4"  !CDS_PN = "4";
"GND<2>":   PN = "5"  !CDS_PN = "5";
"GND<3>":   PN = "6"  !CDS_PN = "6";
"GND<4>":   PN = "7"  !CDS_PN = "7";
"GND<5>":   PN = "8"  !CDS_PN = "8";
"GND<6>":   PN = "9"  !CDS_PN = "9";
"GND<7>":   PN = "10"  !CDS_PN = "10";
"GND<8>":   PN = "11"  !CDS_PN = "11";
"GND<9>":   PN = "12"  !CDS_PN = "12";
END.
